G04 ================== begin FILE IDENTIFICATION RECORD ==================*
G04 Layout Name:  9324_DA0F0TMBIJ0_F0T_Motherboard_J_v01_20230324_0910.brd*
G04 Film Name:    vcc*
G04 File Format:  Gerber RS274X*
G04 File Origin:  Cadence Allegro 17.2-S081*
G04 Origin Date:  Sat Mar 25 08:44:59 2023*
G04 *
G04 Layer:  DRAWING FORMAT/TITLE_BLOCK_A*
G04 Layer:  PIN/SPECIAL_DRILL*
G04 Layer:  VIA CLASS/VCC*
G04 Layer:  PIN/VCC*
G04 Layer:  MANUFACTURING/PHOTOPLOT_OUTLINE*
G04 Layer:  ETCH/VCC*
G04 Layer:  DRAWING FORMAT/TITLE_BLOCK*
G04 Layer:  DRAWING FORMAT/TITLE_DATA_VCC*
G04 *
G04 Offset:    (0.00 0.00)*
G04 Mirror:    No*
G04 Mode:      Negative*
G04 Rotation:  0*
G04 FullContactRelief:  No*
G04 UndefLineWidth:     6.00*
G04 ================== end FILE IDENTIFICATION RECORD ====================*
%FSLAX25Y25*MOIN*%
%IR0*IPPOS*OFA0.00000B0.00000*MIA0B0*SFA1.00000B1.00000*%
%ADD20O,.121X.072*%
%ADD11C,.03*%
%ADD56O,.127X.074*%
%ADD51C,.042*%
%ADD31C,.024*%
%ADD30C,.06*%
%ADD44C,.061*%
%ADD24C,.07*%
%ADD48C,.071*%
%ADD28C,.062*%
%ADD14C,.026*%
%AMMACRO27*
4,1,36,.0025,0.0,
.002462,.000434,
.002349,.000855,
.002165,.00125,
.001915,.001607,
.001607,.001915,
.00125,.002165,
.000855,.002349,
.000434,.002462,
0.0,.0025,
-.000434,.002462,
-.000855,.002349,
-.00125,.002165,
-.001607,.001915,
-.001915,.001607,
-.002165,.00125,
-.002349,.000855,
-.002462,.000434,
-.0025,0.0,
-.002462,-.000434,
-.002349,-.000855,
-.002165,-.00125,
-.001915,-.001607,
-.001607,-.001915,
-.00125,-.002165,
-.000855,-.002349,
-.000434,-.002462,
0.0,-.0025,
.000434,-.002462,
.000855,-.002349,
.00125,-.002165,
.001607,-.001915,
.001915,-.001607,
.002165,-.00125,
.002349,-.000855,
.002462,-.000434,
.0025,0.0,
270.*
%
%ADD27MACRO27*%
%AMMACRO25*
4,1,36,.0025,0.0,
.002462,.000434,
.002349,.000855,
.002165,.00125,
.001915,.001607,
.001607,.001915,
.00125,.002165,
.000855,.002349,
.000434,.002462,
0.0,.0025,
-.000434,.002462,
-.000855,.002349,
-.00125,.002165,
-.001607,.001915,
-.001915,.001607,
-.002165,.00125,
-.002349,.000855,
-.002462,.000434,
-.0025,0.0,
-.002462,-.000434,
-.002349,-.000855,
-.002165,-.00125,
-.001915,-.001607,
-.001607,-.001915,
-.00125,-.002165,
-.000855,-.002349,
-.000434,-.002462,
0.0,-.0025,
.000434,-.002462,
.000855,-.002349,
.00125,-.002165,
.001607,-.001915,
.001915,-.001607,
.002165,-.00125,
.002349,-.000855,
.002462,-.000434,
.0025,0.0,
180.*
%
%ADD25MACRO25*%
%ADD21C,.064*%
%AMMACRO66*
4,1,36,.003,0.0,
.002954,.000521,
.002819,.001026,
.002598,.0015,
.002298,.001928,
.001928,.002298,
.0015,.002598,
.001026,.002819,
.000521,.002954,
0.0,.003,
-.000521,.002954,
-.001026,.002819,
-.0015,.002598,
-.001928,.002298,
-.002298,.001928,
-.002598,.0015,
-.002819,.001026,
-.002954,.000521,
-.003,0.0,
-.002954,-.000521,
-.002819,-.001026,
-.002598,-.0015,
-.002298,-.001928,
-.001928,-.002298,
-.0015,-.002598,
-.001026,-.002819,
-.000521,-.002954,
0.0,-.003,
.000521,-.002954,
.001026,-.002819,
.0015,-.002598,
.001928,-.002298,
.002298,-.001928,
.002598,-.0015,
.002819,-.001026,
.002954,-.000521,
.003,0.0,
270.*
%
%ADD66MACRO66*%
%AMMACRO49*
4,1,36,-.0025,0.0,
-.002462,.000434,
-.002349,.000855,
-.002165,.00125,
-.001915,.001607,
-.001607,.001915,
-.00125,.002165,
-.000855,.002349,
-.000434,.002462,
0.0,.0025,
.000434,.002462,
.000855,.002349,
.00125,.002165,
.001607,.001915,
.001915,.001607,
.002165,.00125,
.002349,.000855,
.002462,.000434,
.0025,0.0,
.002462,-.000434,
.002349,-.000855,
.002165,-.00125,
.001915,-.001607,
.001607,-.001915,
.00125,-.002165,
.000855,-.002349,
.000434,-.002462,
0.0,-.0025,
-.000434,-.002462,
-.000855,-.002349,
-.00125,-.002165,
-.001607,-.001915,
-.001915,-.001607,
-.002165,-.00125,
-.002349,-.000855,
-.002462,-.000434,
-.0025,0.0,
180.*
%
%ADD49MACRO49*%
%AMMACRO41*
4,1,36,.003,0.0,
.002954,.000521,
.002819,.001026,
.002598,.0015,
.002298,.001928,
.001928,.002298,
.0015,.002598,
.001026,.002819,
.000521,.002954,
0.0,.003,
-.000521,.002954,
-.001026,.002819,
-.0015,.002598,
-.001928,.002298,
-.002298,.001928,
-.002598,.0015,
-.002819,.001026,
-.002954,.000521,
-.003,0.0,
-.002954,-.000521,
-.002819,-.001026,
-.002598,-.0015,
-.002298,-.001928,
-.001928,-.002298,
-.0015,-.002598,
-.001026,-.002819,
-.000521,-.002954,
0.0,-.003,
.000521,-.002954,
.001026,-.002819,
.0015,-.002598,
.001928,-.002298,
.002298,-.001928,
.002598,-.0015,
.002819,-.001026,
.002954,-.000521,
.003,0.0,
180.*
%
%ADD41MACRO41*%
%ADD22C,.074*%
%AMMACRO67*
4,1,36,-.003,0.0,
-.002954,.000521,
-.002819,.001026,
-.002598,.0015,
-.002298,.001928,
-.001928,.002298,
-.0015,.002598,
-.001026,.002819,
-.000521,.002954,
0.0,.003,
.000521,.002954,
.001026,.002819,
.0015,.002598,
.001928,.002298,
.002298,.001928,
.002598,.0015,
.002819,.001026,
.002954,.000521,
.003,0.0,
.002954,-.000521,
.002819,-.001026,
.002598,-.0015,
.002298,-.001928,
.001928,-.002298,
.0015,-.002598,
.001026,-.002819,
.000521,-.002954,
0.0,-.003,
-.000521,-.002954,
-.001026,-.002819,
-.0015,-.002598,
-.001928,-.002298,
-.002298,-.001928,
-.002598,-.0015,
-.002819,-.001026,
-.002954,-.000521,
-.003,0.0,
270.*
%
%ADD67MACRO67*%
%ADD65C,.0435*%
%ADD58C,.06015*%
%ADD46C,.076*%
%ADD45C,.095*%
%ADD19C,.0257*%
%ADD70C,.087*%
%ADD34C,.03417*%
%ADD40C,.0259*%
%ADD17C,.0277*%
%ADD55C,.099*%
%AMMACRO47*
4,1,18,.09673,.06845,
.107147,.050613,
.114308,.031238,
.117996,.010914,
.118098,-.009741,
.114613,-.030101,
.107644,-.049546,
.097406,-.067485,
.09673,-.06845,
.10175,-.07347,
.112962,-.054685,
.120742,-.034239,
.124853,-.012752,
.125171,.009122,
.121685,.030719,
.114502,.051383,
.10384,.070486,
.10175,.07347,
.09673,.06845,
0.0*
4,1,18,.06845,-.09673,
.050613,-.107147,
.031238,-.114308,
.010914,-.117996,
-.009741,-.118098,
-.030101,-.114613,
-.049546,-.107644,
-.067485,-.097406,
-.06845,-.09673,
-.07347,-.10175,
-.054685,-.112962,
-.034239,-.120742,
-.012752,-.124853,
.009122,-.125171,
.030719,-.121685,
.051383,-.114502,
.070486,-.10384,
.07347,-.10175,
.06845,-.09673,
0.0*
4,1,18,-.09673,-.06845,
-.107147,-.050613,
-.114308,-.031238,
-.117996,-.010914,
-.118098,.009741,
-.114613,.030101,
-.107644,.049546,
-.097406,.067485,
-.09673,.06845,
-.10175,.07347,
-.112962,.054685,
-.120742,.034239,
-.124853,.012752,
-.125171,-.009122,
-.121685,-.030719,
-.114502,-.051383,
-.10384,-.070486,
-.10175,-.07347,
-.09673,-.06845,
0.0*
4,1,18,-.06845,.09673,
-.050613,.107147,
-.031238,.114308,
-.010914,.117996,
.009741,.118098,
.030101,.114613,
.049546,.107644,
.067485,.097406,
.06845,.09673,
.07347,.10175,
.054685,.112962,
.034239,.120742,
.012752,.124853,
-.009122,.125171,
-.030719,.121685,
-.051383,.114502,
-.070486,.10384,
-.07347,.10175,
-.06845,.09673,
0.0*
%
%ADD47MACRO47*%
%ADD35C,.03187*%
%AMMACRO42*
4,1,15,.02438,.01377,
.026401,.009327,
.027619,.004601,
.027999,-.000265,
.027527,-.005123,
.02622,-.009825,
.02438,-.01377,
.02948,-.01887,
.032309,-.013464,
.034156,-.007649,
.034965,-.001602,
.034712,.004494,
.033405,.010454,
.031082,.016095,
.02948,.01887,
.02438,.01377,
90.*
4,1,15,.01377,-.02438,
.009327,-.026401,
.004601,-.027619,
-.000265,-.027999,
-.005123,-.027527,
-.009825,-.02622,
-.01377,-.02438,
-.01887,-.02948,
-.013464,-.032309,
-.007649,-.034156,
-.001602,-.034965,
.004494,-.034712,
.010454,-.033405,
.016095,-.031082,
.01887,-.02948,
.01377,-.02438,
90.*
4,1,15,-.02438,-.01377,
-.026401,-.009327,
-.027619,-.004601,
-.027999,.000265,
-.027527,.005123,
-.02622,.009825,
-.02438,.01377,
-.02948,.01887,
-.032309,.013464,
-.034156,.007649,
-.034965,.001602,
-.034712,-.004494,
-.033405,-.010454,
-.031082,-.016095,
-.02948,-.01887,
-.02438,-.01377,
90.*
4,1,15,-.01377,.02438,
-.009327,.026401,
-.004601,.027619,
.000265,.027999,
.005123,.027527,
.009825,.02622,
.01377,.02438,
.01887,.02948,
.013464,.032309,
.007649,.034156,
.001602,.034965,
-.004494,.034712,
-.010454,.033405,
-.016095,.031082,
-.01887,.02948,
-.01377,.02438,
90.*
%
%ADD42MACRO42*%
%AMMACRO63*
4,1,15,.02438,.01377,
.026401,.009327,
.027619,.004601,
.027999,-.000265,
.027527,-.005123,
.02622,-.009825,
.02438,-.01377,
.02948,-.01887,
.032309,-.013464,
.034156,-.007649,
.034965,-.001602,
.034712,.004494,
.033405,.010454,
.031082,.016095,
.02948,.01887,
.02438,.01377,
0.0*
4,1,15,.01377,-.02438,
.009327,-.026401,
.004601,-.027619,
-.000265,-.027999,
-.005123,-.027527,
-.009825,-.02622,
-.01377,-.02438,
-.01887,-.02948,
-.013464,-.032309,
-.007649,-.034156,
-.001602,-.034965,
.004494,-.034712,
.010454,-.033405,
.016095,-.031082,
.01887,-.02948,
.01377,-.02438,
0.0*
4,1,15,-.02438,-.01377,
-.026401,-.009327,
-.027619,-.004601,
-.027999,.000265,
-.027527,.005123,
-.02622,.009825,
-.02438,.01377,
-.02948,.01887,
-.032309,.013464,
-.034156,.007649,
-.034965,.001602,
-.034712,-.004494,
-.033405,-.010454,
-.031082,-.016095,
-.02948,-.01887,
-.02438,-.01377,
0.0*
4,1,15,-.01377,.02438,
-.009327,.026401,
-.004601,.027619,
.000265,.027999,
.005123,.027527,
.009825,.02622,
.01377,.02438,
.01887,.02948,
.013464,.032309,
.007649,.034156,
.001602,.034965,
-.004494,.034712,
-.010454,.033405,
-.016095,.031082,
-.01887,.02948,
-.01377,.02438,
0.0*
%
%ADD63MACRO63*%
%AMMACRO61*
4,1,18,.07103,.05689,
.07983,.043691,
.086204,.029165,
.089959,.013753,
.09098,-.002077,
.089237,-.017844,
.084783,-.033069,
.077753,-.047289,
.07103,-.05689,
.07601,-.06186,
.085597,-.047721,
.092583,-.032132,
.096757,-.015567,
.09799,.001471,
.096246,.018464,
.091577,.034897,
.084126,.050269,
.07601,.06186,
.07103,.05689,
0.0*
4,1,18,.05689,-.07103,
.043691,-.07983,
.029165,-.086204,
.013753,-.089959,
-.002077,-.09098,
-.017844,-.089237,
-.033069,-.084783,
-.047289,-.077753,
-.05689,-.07103,
-.06186,-.07601,
-.047721,-.085597,
-.032132,-.092583,
-.015567,-.096757,
.001471,-.09799,
.018464,-.096246,
.034897,-.091577,
.050269,-.084126,
.06186,-.07601,
.05689,-.07103,
0.0*
4,1,18,-.07103,-.05689,
-.07983,-.043691,
-.086204,-.029165,
-.089959,-.013753,
-.09098,.002077,
-.089237,.017844,
-.084783,.033069,
-.077753,.047289,
-.07103,.05689,
-.07601,.06186,
-.085597,.047721,
-.092583,.032132,
-.096757,.015567,
-.09799,-.001471,
-.096246,-.018464,
-.091577,-.034897,
-.084126,-.050269,
-.07601,-.06186,
-.07103,-.05689,
0.0*
4,1,18,-.05689,.07103,
-.043691,.07983,
-.029165,.086204,
-.013753,.089959,
.002077,.09098,
.017844,.089237,
.033069,.084783,
.047289,.077753,
.05689,.07103,
.06186,.07601,
.047721,.085597,
.032132,.092583,
.015567,.096757,
-.001471,.09799,
-.018464,.096246,
-.034897,.091577,
-.050269,.084126,
-.06186,.07601,
-.05689,.07103,
0.0*
%
%ADD61MACRO61*%
%AMMACRO60*
4,1,15,.02475,.01414,
.026829,.009627,
.028094,.004822,
.028504,-.000129,
.028049,-.005077,
.026741,-.009871,
.02475,-.01414,
.02984,-.01923,
.032726,-.013756,
.034617,-.007864,
.035457,-.001734,
.03522,.00445,
.033912,.010498,
.031574,.016227,
.02984,.01923,
.02475,.01414,
0.0*
4,1,15,.01414,-.02475,
.009627,-.026829,
.004822,-.028094,
-.000129,-.028504,
-.005077,-.028049,
-.009871,-.026741,
-.01414,-.02475,
-.01923,-.02984,
-.013756,-.032726,
-.007864,-.034617,
-.001734,-.035457,
.00445,-.03522,
.010498,-.033912,
.016227,-.031574,
.01923,-.02984,
.01414,-.02475,
0.0*
4,1,15,-.02475,-.01414,
-.026829,-.009627,
-.028094,-.004822,
-.028504,.000129,
-.028049,.005077,
-.026741,.009871,
-.02475,.01414,
-.02984,.01923,
-.032726,.013756,
-.034617,.007864,
-.035457,.001734,
-.03522,-.00445,
-.033912,-.010498,
-.031574,-.016227,
-.02984,-.01923,
-.02475,-.01414,
0.0*
4,1,15,-.01414,.02475,
-.009627,.026829,
-.004822,.028094,
.000129,.028504,
.005077,.028049,
.009871,.026741,
.01414,.02475,
.01923,.02984,
.013756,.032726,
.007864,.034617,
.001734,.035457,
-.00445,.03522,
-.010498,.033912,
-.016227,.031574,
-.01923,.02984,
-.01414,.02475,
0.0*
%
%ADD60MACRO60*%
%AMMACRO37*
4,1,16,.02511,.01451,
.027248,.009929,
.028558,.005047,
.029001,.000011,
.028562,-.005025,
.027256,-.009909,
.025121,-.014491,
.02511,-.01451,
.0302,-.01959,
.033143,-.014048,
.035079,-.00808,
.035949,-.001865,
.035727,.004405,
.034419,.010542,
.032065,.016359,
.0302,.01959,
.02511,.01451,
90.*
4,1,16,.01451,-.02511,
.009929,-.027248,
.005047,-.028558,
.000011,-.029001,
-.005025,-.028562,
-.009909,-.027256,
-.014491,-.025121,
-.01451,-.02511,
-.01959,-.0302,
-.014048,-.033143,
-.00808,-.035079,
-.001865,-.035949,
.004405,-.035727,
.010542,-.034419,
.016359,-.032065,
.01959,-.0302,
.01451,-.02511,
90.*
4,1,16,-.02511,-.01451,
-.027248,-.009929,
-.028558,-.005047,
-.029001,-.000011,
-.028562,.005025,
-.027256,.009909,
-.025121,.014491,
-.02511,.01451,
-.0302,.01959,
-.033143,.014048,
-.035079,.00808,
-.035949,.001865,
-.035727,-.004405,
-.034419,-.010542,
-.032065,-.016359,
-.0302,-.01959,
-.02511,-.01451,
90.*
4,1,16,-.01451,.02511,
-.009929,.027248,
-.005047,.028558,
-.000011,.029001,
.005025,.028562,
.009909,.027256,
.014491,.025121,
.01451,.02511,
.01959,.0302,
.014048,.033143,
.00808,.035079,
.001865,.035949,
-.004405,.035727,
-.010542,.034419,
-.016359,.032065,
-.01959,.0302,
-.01451,.02511,
90.*
%
%ADD37MACRO37*%
%ADD33C,.03968*%
%AMMACRO29*
4,1,16,.02511,.01451,
.027248,.009929,
.028558,.005047,
.029001,.000011,
.028562,-.005025,
.027256,-.009909,
.025121,-.014491,
.02511,-.01451,
.0302,-.01959,
.033143,-.014048,
.035079,-.00808,
.035949,-.001865,
.035727,.004405,
.034419,.010542,
.032065,.016359,
.0302,.01959,
.02511,.01451,
0.0*
4,1,16,.01451,-.02511,
.009929,-.027248,
.005047,-.028558,
.000011,-.029001,
-.005025,-.028562,
-.009909,-.027256,
-.014491,-.025121,
-.01451,-.02511,
-.01959,-.0302,
-.014048,-.033143,
-.00808,-.035079,
-.001865,-.035949,
.004405,-.035727,
.010542,-.034419,
.016359,-.032065,
.01959,-.0302,
.01451,-.02511,
0.0*
4,1,16,-.02511,-.01451,
-.027248,-.009929,
-.028558,-.005047,
-.029001,-.000011,
-.028562,.005025,
-.027256,.009909,
-.025121,.014491,
-.02511,.01451,
-.0302,.01959,
-.033143,.014048,
-.035079,.00808,
-.035949,.001865,
-.035727,-.004405,
-.034419,-.010542,
-.032065,-.016359,
-.0302,-.01959,
-.02511,-.01451,
0.0*
4,1,16,-.01451,.02511,
-.009929,.027248,
-.005047,.028558,
-.000011,.029001,
.005025,.028562,
.009909,.027256,
.014491,.025121,
.01451,.02511,
.01959,.0302,
.014048,.033143,
.00808,.035079,
.001865,.035949,
-.004405,.035727,
-.010542,.034419,
-.016359,.032065,
-.01959,.0302,
-.01451,.02511,
0.0*
%
%ADD29MACRO29*%
%AMMACRO72*
4,1,15,.03682,.01914,
.039584,.012455,
.041146,.005393,
.041457,-.001834,
.040509,-.009005,
.03833,-.015903,
.03682,-.01914,
.04197,-.0243,
.045552,-.016643,
.04775,-.00848,
.048497,-.000059,
.047771,.008363,
.045593,.016531,
.042029,.024197,
.04197,.0243,
.03682,.01914,
0.0*
4,1,15,.01914,-.03682,
.012455,-.039584,
.005393,-.041146,
-.001834,-.041457,
-.009005,-.040509,
-.015903,-.03833,
-.01914,-.03682,
-.0243,-.04197,
-.016643,-.045552,
-.00848,-.04775,
-.000059,-.048497,
.008363,-.047771,
.016531,-.045593,
.024197,-.042029,
.0243,-.04197,
.01914,-.03682,
0.0*
4,1,15,-.03682,-.01914,
-.039584,-.012455,
-.041146,-.005393,
-.041457,.001834,
-.040509,.009005,
-.03833,.015903,
-.03682,.01914,
-.04197,.0243,
-.045552,.016643,
-.04775,.00848,
-.048497,.000059,
-.047771,-.008363,
-.045593,-.016531,
-.042029,-.024197,
-.04197,-.0243,
-.03682,-.01914,
0.0*
4,1,15,-.01914,.03682,
-.012455,.039584,
-.005393,.041146,
.001834,.041457,
.009005,.040509,
.015903,.03833,
.01914,.03682,
.0243,.04197,
.016643,.045552,
.00848,.04775,
.000059,.048497,
-.008363,.047771,
-.016531,.045593,
-.024197,.042029,
-.0243,.04197,
-.01914,.03682,
0.0*
%
%ADD72MACRO72*%
%AMMACRO69*
4,1,15,-.03682,.01914,
-.039584,.012455,
-.041146,.005393,
-.041457,-.001834,
-.040509,-.009005,
-.03833,-.015903,
-.03682,-.01914,
-.04197,-.0243,
-.045552,-.016643,
-.04775,-.00848,
-.048497,-.000059,
-.047771,.008363,
-.045593,.016531,
-.042029,.024197,
-.04197,.0243,
-.03682,.01914,
0.0*
4,1,15,-.01914,-.03682,
-.012455,-.039584,
-.005393,-.041146,
.001834,-.041457,
.009005,-.040509,
.015903,-.03833,
.01914,-.03682,
.0243,-.04197,
.016643,-.045552,
.00848,-.04775,
.000059,-.048497,
-.008363,-.047771,
-.016531,-.045593,
-.024197,-.042029,
-.0243,-.04197,
-.01914,-.03682,
0.0*
4,1,15,.03682,-.01914,
.039584,-.012455,
.041146,-.005393,
.041457,.001834,
.040509,.009005,
.03833,.015903,
.03682,.01914,
.04197,.0243,
.045552,.016643,
.04775,.00848,
.048497,.000059,
.047771,-.008363,
.045593,-.016531,
.042029,-.024197,
.04197,-.0243,
.03682,-.01914,
0.0*
4,1,15,.01914,.03682,
.012455,.039584,
.005393,.041146,
-.001834,.041457,
-.009005,.040509,
-.015903,.03833,
-.01914,.03682,
-.0243,.04197,
-.016643,.045552,
-.00848,.04775,
-.000059,.048497,
.008363,.047771,
.016531,.045593,
.024197,.042029,
.0243,.04197,
.01914,.03682,
0.0*
%
%ADD69MACRO69*%
%AMMACRO18*
4,1,25,-.0605,.00499,
-.05909,.011105,
-.05664,.016881,
-.053224,.022145,
-.048946,.026736,
-.043935,.030513,
-.038345,.033364,
-.032345,.0352,
-.02985,.03564,
-.025195,.035958,
-.02422,.03599,
-.005,.03599,
-.005,.03099,
-.02474,.03099,
-.026534,.030943,
-.028322,.030793,
-.02985,.03058,
-.035086,.029247,
-.040011,.027025,
-.044475,.023982,
-.048343,.020209,
-.051497,.015823,
-.053842,.010955,
-.055305,.005754,
-.05544,.00499,
-.0605,.00499,
0.0*
4,1,27,.005,.03599,
.02451,.03599,
.026071,.035998,
.027631,.035916,
.029183,.035743,
.02985,.03564,
.035965,.03423,
.041741,.03178,
.047005,.028364,
.051596,.024086,
.055373,.019075,
.058224,.013485,
.06006,.007485,
.0605,.00499,
.05544,.00499,
.054107,.010226,
.051885,.015151,
.048842,.019615,
.045069,.023483,
.040683,.026637,
.035815,.028982,
.030614,.030445,
.02985,.03058,
.0281,.030818,
.02634,.030955,
.02482,.03099,
.005,.03099,
.005,.03599,
0.0*
4,1,25,-.0605,-.00501,
-.05544,-.00501,
-.054107,-.010246,
-.051885,-.015171,
-.048842,-.019635,
-.045069,-.023503,
-.040683,-.026657,
-.035815,-.029002,
-.030614,-.030465,
-.02985,-.0306,
-.028079,-.03084,
-.026298,-.030976,
-.02487,-.03101,
-.005,-.03101,
-.005,-.03601,
-.02375,-.03601,
-.028562,-.035772,
-.02985,-.03566,
-.035965,-.03425,
-.041741,-.0318,
-.047005,-.028384,
-.051596,-.024106,
-.055373,-.019095,
-.058224,-.013505,
-.06006,-.007505,
-.0605,-.00501,
0.0*
4,1,27,.005,-.03101,
.02485,-.03101,
.02659,-.030963,
.028324,-.030815,
.02985,-.0306,
.035086,-.029267,
.040011,-.027045,
.044475,-.024002,
.048343,-.020229,
.051497,-.015843,
.053842,-.010975,
.055305,-.005774,
.05544,-.00501,
.0605,-.00501,
.05909,-.011125,
.05664,-.016901,
.053224,-.022165,
.048946,-.026756,
.043935,-.030533,
.038345,-.033384,
.032345,-.03522,
.02985,-.03566,
.028758,-.035841,
.027658,-.035958,
.026553,-.036011,
.02578,-.03601,
.005,-.03601,
.005,-.03101,
0.0*
%
%ADD18MACRO18*%
%ADD57R,.285X.23*%
%ADD62C,.142*%
%ADD32O,.219X.156*%
%ADD10C,.241*%
%ADD36C,.17*%
%ADD12C,.125*%
%ADD15C,.424*%
%ADD39C,.146*%
%ADD16C,.155*%
%ADD50C,.291*%
%ADD38C,.165*%
%ADD52C,.247*%
%ADD43C,.256*%
%AMMACRO26*
4,1,36,.0025,0.0,
.002462,.000434,
.002349,.000855,
.002165,.00125,
.001915,.001607,
.001607,.001915,
.00125,.002165,
.000855,.002349,
.000434,.002462,
0.0,.0025,
-.000434,.002462,
-.000855,.002349,
-.00125,.002165,
-.001607,.001915,
-.001915,.001607,
-.002165,.00125,
-.002349,.000855,
-.002462,.000434,
-.0025,0.0,
-.002462,-.000434,
-.002349,-.000855,
-.002165,-.00125,
-.001915,-.001607,
-.001607,-.001915,
-.00125,-.002165,
-.000855,-.002349,
-.000434,-.002462,
0.0,-.0025,
.000434,-.002462,
.000855,-.002349,
.00125,-.002165,
.001607,-.001915,
.001915,-.001607,
.002165,-.00125,
.002349,-.000855,
.002462,-.000434,
.0025,0.0,
90.*
%
%ADD26MACRO26*%
%AMMACRO68*
4,1,36,.003,0.0,
.002954,.000521,
.002819,.001026,
.002598,.0015,
.002298,.001928,
.001928,.002298,
.0015,.002598,
.001026,.002819,
.000521,.002954,
0.0,.003,
-.000521,.002954,
-.001026,.002819,
-.0015,.002598,
-.001928,.002298,
-.002298,.001928,
-.002598,.0015,
-.002819,.001026,
-.002954,.000521,
-.003,0.0,
-.002954,-.000521,
-.002819,-.001026,
-.002598,-.0015,
-.002298,-.001928,
-.001928,-.002298,
-.0015,-.002598,
-.001026,-.002819,
-.000521,-.002954,
0.0,-.003,
.000521,-.002954,
.001026,-.002819,
.0015,-.002598,
.001928,-.002298,
.002298,-.001928,
.002598,-.0015,
.002819,-.001026,
.002954,-.000521,
.003,0.0,
90.*
%
%ADD68MACRO68*%
%AMMACRO53*
4,1,36,0.0,.019,
-.003299,.018711,
-.006498,.017854,
-.0095,.016454,
-.012213,.014555,
-.014555,.012213,
-.016454,.0095,
-.017854,.006498,
-.018711,.003299,
-.019,0.0,
-.018711,-.003299,
-.017854,-.006498,
-.016454,-.0095,
-.014555,-.012213,
-.012213,-.014555,
-.0095,-.016454,
-.006498,-.017854,
-.003299,-.018711,
0.0,-.019,
.003299,-.018711,
.006498,-.017854,
.0095,-.016454,
.012213,-.014555,
.014555,-.012213,
.016454,-.0095,
.017854,-.006498,
.018711,-.003299,
.019,0.0,
.018711,.003299,
.017854,.006498,
.016454,.0095,
.014555,.012213,
.012213,.014555,
.0095,.016454,
.006498,.017854,
.003299,.018711,
0.0,.019,
270.*
%
%ADD53MACRO53*%
%AMMACRO23*
4,1,36,.0025,0.0,
.002462,.000434,
.002349,.000855,
.002165,.00125,
.001915,.001607,
.001607,.001915,
.00125,.002165,
.000855,.002349,
.000434,.002462,
0.0,.0025,
-.000434,.002462,
-.000855,.002349,
-.00125,.002165,
-.001607,.001915,
-.001915,.001607,
-.002165,.00125,
-.002349,.000855,
-.002462,.000434,
-.0025,0.0,
-.002462,-.000434,
-.002349,-.000855,
-.002165,-.00125,
-.001915,-.001607,
-.001607,-.001915,
-.00125,-.002165,
-.000855,-.002349,
-.000434,-.002462,
0.0,-.0025,
.000434,-.002462,
.000855,-.002349,
.00125,-.002165,
.001607,-.001915,
.001915,-.001607,
.002165,-.00125,
.002349,-.000855,
.002462,-.000434,
.0025,0.0,
0.0*
%
%ADD23MACRO23*%
%AMMACRO64*
4,1,36,-.003,0.0,
-.002954,.000521,
-.002819,.001026,
-.002598,.0015,
-.002298,.001928,
-.001928,.002298,
-.0015,.002598,
-.001026,.002819,
-.000521,.002954,
0.0,.003,
.000521,.002954,
.001026,.002819,
.0015,.002598,
.001928,.002298,
.002298,.001928,
.002598,.0015,
.002819,.001026,
.002954,.000521,
.003,0.0,
.002954,-.000521,
.002819,-.001026,
.002598,-.0015,
.002298,-.001928,
.001928,-.002298,
.0015,-.002598,
.001026,-.002819,
.000521,-.002954,
0.0,-.003,
-.000521,-.002954,
-.001026,-.002819,
-.0015,-.002598,
-.001928,-.002298,
-.002298,-.001928,
-.002598,-.0015,
-.002819,-.001026,
-.002954,-.000521,
-.003,0.0,
90.*
%
%ADD64MACRO64*%
%AMMACRO59*
4,1,36,-.0025,0.0,
-.002462,.000434,
-.002349,.000855,
-.002165,.00125,
-.001915,.001607,
-.001607,.001915,
-.00125,.002165,
-.000855,.002349,
-.000434,.002462,
0.0,.0025,
.000434,.002462,
.000855,.002349,
.00125,.002165,
.001607,.001915,
.001915,.001607,
.002165,.00125,
.002349,.000855,
.002462,.000434,
.0025,0.0,
.002462,-.000434,
.002349,-.000855,
.002165,-.00125,
.001915,-.001607,
.001607,-.001915,
.00125,-.002165,
.000855,-.002349,
.000434,-.002462,
0.0,-.0025,
-.000434,-.002462,
-.000855,-.002349,
-.00125,-.002165,
-.001607,-.001915,
-.001915,-.001607,
-.002165,-.00125,
-.002349,-.000855,
-.002462,-.000434,
-.0025,0.0,
0.0*
%
%ADD59MACRO59*%
%ADD54C,.188*%
%AMMACRO13*
4,1,36,.003,0.0,
.002954,.000521,
.002819,.001026,
.002598,.0015,
.002298,.001928,
.001928,.002298,
.0015,.002598,
.001026,.002819,
.000521,.002954,
0.0,.003,
-.000521,.002954,
-.001026,.002819,
-.0015,.002598,
-.001928,.002298,
-.002298,.001928,
-.002598,.0015,
-.002819,.001026,
-.002954,.000521,
-.003,0.0,
-.002954,-.000521,
-.002819,-.001026,
-.002598,-.0015,
-.002298,-.001928,
-.001928,-.002298,
-.0015,-.002598,
-.001026,-.002819,
-.000521,-.002954,
0.0,-.003,
.000521,-.002954,
.001026,-.002819,
.0015,-.002598,
.001928,-.002298,
.002298,-.001928,
.002598,-.0015,
.002819,-.001026,
.002954,-.000521,
.003,0.0,
0.0*
%
%ADD13MACRO13*%
%AMMACRO73*
4,1,15,.03682,.01914,
.039584,.012455,
.041146,.005393,
.041457,-.001834,
.040509,-.009005,
.03833,-.015903,
.03682,-.01914,
.04197,-.0243,
.045552,-.016643,
.04775,-.00848,
.048497,-.000059,
.047771,.008363,
.045593,.016531,
.042029,.024197,
.04197,.0243,
.03682,.01914,
180.*
4,1,15,.01914,-.03682,
.012455,-.039584,
.005393,-.041146,
-.001834,-.041457,
-.009005,-.040509,
-.015903,-.03833,
-.01914,-.03682,
-.0243,-.04197,
-.016643,-.045552,
-.00848,-.04775,
-.000059,-.048497,
.008363,-.047771,
.016531,-.045593,
.024197,-.042029,
.0243,-.04197,
.01914,-.03682,
180.*
4,1,15,-.03682,-.01914,
-.039584,-.012455,
-.041146,-.005393,
-.041457,.001834,
-.040509,.009005,
-.03833,.015903,
-.03682,.01914,
-.04197,.0243,
-.045552,.016643,
-.04775,.00848,
-.048497,.000059,
-.047771,-.008363,
-.045593,-.016531,
-.042029,-.024197,
-.04197,-.0243,
-.03682,-.01914,
180.*
4,1,15,-.01914,.03682,
-.012455,.039584,
-.005393,.041146,
.001834,.041457,
.009005,.040509,
.015903,.03833,
.01914,.03682,
.0243,.04197,
.016643,.045552,
.00848,.04775,
.000059,.048497,
-.008363,.047771,
-.016531,.045593,
-.024197,.042029,
-.0243,.04197,
-.01914,.03682,
180.*
%
%ADD73MACRO73*%
%AMMACRO71*
4,1,15,-.03682,.01914,
-.039584,.012455,
-.041146,.005393,
-.041457,-.001834,
-.040509,-.009005,
-.03833,-.015903,
-.03682,-.01914,
-.04197,-.0243,
-.045552,-.016643,
-.04775,-.00848,
-.048497,-.000059,
-.047771,.008363,
-.045593,.016531,
-.042029,.024197,
-.04197,.0243,
-.03682,.01914,
180.*
4,1,15,-.01914,-.03682,
-.012455,-.039584,
-.005393,-.041146,
.001834,-.041457,
.009005,-.040509,
.015903,-.03833,
.01914,-.03682,
.0243,-.04197,
.016643,-.045552,
.00848,-.04775,
.000059,-.048497,
-.008363,-.047771,
-.016531,-.045593,
-.024197,-.042029,
-.0243,-.04197,
-.01914,-.03682,
180.*
4,1,15,.03682,-.01914,
.039584,-.012455,
.041146,-.005393,
.041457,.001834,
.040509,.009005,
.03833,.015903,
.03682,.01914,
.04197,.0243,
.045552,.016643,
.04775,.00848,
.048497,.000059,
.047771,-.008363,
.045593,-.016531,
.042029,-.024197,
.04197,-.0243,
.03682,-.01914,
180.*
4,1,15,.01914,.03682,
.012455,.039584,
.005393,.041146,
-.001834,.041457,
-.009005,.040509,
-.015903,.03833,
-.01914,.03682,
-.0243,.04197,
-.016643,.045552,
-.00848,.04775,
-.000059,.048497,
.008363,.047771,
.016531,.045593,
.024197,.042029,
.0243,.04197,
.01914,.03682,
180.*
%
%ADD71MACRO71*%
%ADD74C,.006*%
%ADD101C,.03016*%
%ADD91C,.04006*%
%ADD89C,.03018*%
%ADD93C,.076*%
%ADD92C,.07006*%
%ADD90C,.07008*%
%ADD77C,.07306*%
%ADD82C,.07208*%
%ADD96C,.07308*%
%ADD85C,.07608*%
%ADD84C,.07808*%
%ADD83C,.09708*%
%ADD81O,.1621X.2251*%
%ADD99C,.311*%
%ADD97C,.1621*%
%ADD76O,.03004X.06404*%
%ADD100C,.16211*%
%ADD98C,.1751*%
%ADD75O,.03006X.06406*%
%ADD87C,.41506*%
%ADD86C,.43406*%
%ADD78C,.16506*%
%ADD94C,.23944*%
%ADD88C,.43376*%
%ADD95O,.43374X.77626*%
%ADD79O,.43374X.69752*%
%ADD80O,.43376X.69754*%
G75*
%LPD*%
G75*
G36*
G01X-984580Y-698988D02*
X5868320D01*
Y4193602D01*
X-984580D01*
Y-698988D01*
G37*
%LPC*%
G75*
G36*
G01X1828062Y36504D02*
X1828081Y36500D01*
G03X1828470Y36462I388J1962D01*
G03X1828859Y36500I1J2000D01*
G01X1828878Y36504D01*
X1849606D01*
G02X1855480Y30630I0J-5874D01*
G01Y-40945D01*
G02X1849606Y-46819I-5874J0D01*
G01X7874D01*
G02X2000Y-40945I0J5874D01*
G01Y30630D01*
G02X7874Y36504I5874J0D01*
G01X35835D01*
G02X41709Y30630I0J-5874D01*
G01Y-3937D01*
G03X51583Y-13811I9874J0D01*
G01X321661D01*
G03X331535Y-3937I0J9874D01*
G01Y30630D01*
G02X337409Y36504I5874J0D01*
G01X480717D01*
G02X486591Y30630I0J-5874D01*
G01Y16850D01*
G03X496465Y6976I9874J0D01*
G01X766543D01*
G03X776417Y16850I0J9874D01*
G01Y30630D01*
G02X782291Y36504I5874J0D01*
G01X879134D01*
G03X889008Y46378I0J9874D01*
G01Y122824D01*
X895188Y129004D01*
X1002542D01*
X1009024Y122522D01*
Y46378D01*
G03X1018898Y36504I9874J0D01*
G01X1510244D01*
G02X1516118Y30630I0J-5874D01*
G01Y-3937D01*
G03X1525992Y-13811I9874J0D01*
G01X1796071D01*
G03X1805945Y-3937I0J9874D01*
G01Y30630D01*
G02X1811819Y36504I5874J0D01*
G01X1828062D01*
G37*
G36*
G01X315661Y27782D02*
G02X315038Y27450I-400J0D01*
G03Y21133I-2117J-3159D01*
G02X315661Y20801I223J-332D01*
G01Y6000D01*
X57583D01*
Y17233D01*
G02X57850Y17421I200J0D01*
G01X57909Y17400D01*
X57934Y17380D01*
G03X58024Y17311I2358J2983D01*
G03X62587Y23395I2283J3041D01*
G03X58204Y23525I-2284J-3041D01*
G02X57583Y23858I-221J333D01*
G01Y38504D01*
G03X43709Y52378I-13874J0D01*
G01X7874D01*
G02X6000Y54252I0J1874D01*
G01Y305794D01*
G02X6549Y307118I1873J-1D01*
G01X9811Y310380D01*
G03X13874Y320189I-9810J9809D01*
G01Y1588078D01*
G02X14423Y1589402I1873J-1D01*
G01X27529Y1602508D01*
G03X31591Y1612315I-9809J9807D01*
G01Y1706064D01*
G02X32354Y1706232I400J0D01*
G03X51181Y1694208I18828J8729D01*
G03X71934Y1714961I0J20753D01*
G03X60774Y1733363I-20752J0D01*
G02X60958Y1734118I184J355D01*
G01X228891D01*
X228914Y1733945D01*
G03X232898I1992J267D01*
G01X232921Y1734118D01*
X244639D01*
X244662Y1733945D01*
G03X248646I1992J267D01*
G01X248669Y1734118D01*
X260387D01*
X260410Y1733945D01*
G03X264394I1992J267D01*
G01X264417Y1734118D01*
X276135D01*
X276158Y1733945D01*
G03X280142I1992J267D01*
G01X280165Y1734118D01*
X295820D01*
X295843Y1733945D01*
G03X299827I1992J267D01*
G01X299850Y1734118D01*
X311568D01*
X311591Y1733945D01*
G03X315575I1992J267D01*
G01X315598Y1734118D01*
X327316D01*
X327339Y1733945D01*
G03X331323I1992J267D01*
G01X331346Y1734118D01*
X343064D01*
X343087Y1733945D01*
G03X347071I1992J267D01*
G01X347094Y1734118D01*
X385893D01*
G02X386077Y1733363I0J-400D01*
G03X374918Y1714961I9594J-18402D01*
G03X416422I20752J0D01*
G03X405263Y1733363I-20753J0D01*
G02X405447Y1734118I184J355D01*
G01X427418D01*
Y1705442D01*
G03X425644Y1698268I13625J-7175D01*
G03X427418Y1691094I15399J1D01*
G01Y1656978D01*
X455212D01*
Y1692240D01*
G03X456442Y1698268I-14168J6031D01*
G03X455212Y1704296I-15398J-3D01*
G01Y1734118D01*
X493064D01*
X493087Y1733945D01*
G03X497071I1992J267D01*
G01X497094Y1734118D01*
X508812D01*
X508835Y1733945D01*
G03X512819I1992J267D01*
G01X512842Y1734118D01*
X524560D01*
X524583Y1733945D01*
G03X528567I1992J267D01*
G01X528590Y1734118D01*
X540308D01*
X540331Y1733945D01*
G03X544315I1992J267D01*
G01X544338Y1734118D01*
X559993D01*
X560016Y1733945D01*
G03X564000I1992J267D01*
G01X564023Y1734118D01*
X575741D01*
X575764Y1733945D01*
G03X579748I1992J267D01*
G01X579771Y1734118D01*
X591489D01*
X591512Y1733945D01*
G03X595496I1992J267D01*
G01X595519Y1734118D01*
X607237D01*
X607260Y1733945D01*
G03X611244I1992J267D01*
G01X611267Y1734118D01*
X656434D01*
X658560Y1731992D01*
Y1641270D01*
G03X658926Y1640386I1251J0D01*
G01X670238Y1629074D01*
G03X671122Y1628708I884J885D01*
G01X709835D01*
G03X711305I735J1181D01*
G01X712777D01*
G03X714805I1014J1108D01*
G01X727122D01*
Y1608233D01*
G03X727488Y1607349I1251J0D01*
G01X727922Y1606915D01*
Y1603507D01*
G03X727550Y1602518I1129J-989D01*
G03X727554Y1602417I1502J9D01*
G01X727560Y1602325D01*
X726988Y1601753D01*
G03X726622Y1600869I885J-884D01*
G01Y1577501D01*
G03X727872Y1576251I1250J0D01*
G01X743045D01*
G03X743935Y1576624I-1J1250D01*
G01X744730Y1577431D01*
G03X745090Y1578308I-890J878D01*
G01Y1588651D01*
X745940D01*
G03X746824Y1589017I0J1251D01*
G01X747656Y1589849D01*
G03X748022Y1590733I-885J884D01*
G01Y1591915D01*
X749314Y1593207D01*
X749411Y1593194D01*
G03X749612Y1593181I197J1489D01*
G03X751114Y1594683I0J1502D01*
G03X751101Y1594884I-1502J4D01*
G01X751088Y1594982D01*
X751976Y1595870D01*
X774954D01*
X778870Y1591954D01*
Y1578322D01*
G03X779236Y1577438I1251J0D01*
G01X779988Y1576686D01*
G03X780872Y1576320I884J885D01*
G01X795258D01*
G03X796142Y1576686I0J1251D01*
G01X796924Y1577468D01*
G03X797290Y1578352I-885J884D01*
G01Y1591854D01*
X797656Y1592220D01*
G03X798022Y1593104I-885J884D01*
G01Y1604234D01*
X804298Y1610510D01*
X812654D01*
X820122Y1603042D01*
Y1593082D01*
G03X820488Y1592198I1251J0D01*
G01X820870Y1591816D01*
Y1578322D01*
G03X821236Y1577438I1251J0D01*
G01X821988Y1576686D01*
G03X822872Y1576320I884J885D01*
G01X837278D01*
G03X838162Y1576686I0J1251D01*
G01X838914Y1577438D01*
G03X839280Y1578322I-885J884D01*
G01Y1591944D01*
X839614Y1592278D01*
G03X839980Y1593162I-885J884D01*
G01Y1603914D01*
X846166Y1610100D01*
X854886D01*
X862122Y1602864D01*
Y1593202D01*
G03X862488Y1592318I1251J0D01*
G01X862840Y1591966D01*
Y1578372D01*
G03X863206Y1577488I1251J0D01*
G01X864008Y1576686D01*
G03X864892Y1576320I884J885D01*
G01X879228D01*
G03X880112Y1576686I0J1251D01*
G01X880944Y1577518D01*
G03X881310Y1578402I-885J884D01*
G01Y1591922D01*
X881656Y1592268D01*
G03X882022Y1593152I-885J884D01*
G01Y1603434D01*
X889128Y1610540D01*
X896864D01*
X904022Y1603382D01*
Y1593222D01*
G03X904388Y1592338I1251J0D01*
G01X904830Y1591896D01*
Y1578352D01*
G03X905196Y1577468I1251J0D01*
G01X905988Y1576676D01*
G03X906872Y1576310I884J885D01*
G01X921248D01*
G03X922132Y1576676I0J1251D01*
G01X922924Y1577468D01*
G03X923290Y1578352I-885J884D01*
G01Y1591914D01*
X927766Y1596390D01*
X936008D01*
G03X936892Y1596756I0J1251D01*
G01X940214Y1600078D01*
X940822D01*
X941000Y1599900D01*
Y1566299D01*
G03X941092Y1565829I1250J1D01*
G01X941313Y1565284D01*
G03X941602Y1564855I1159J469D01*
G01X941807Y1564658D01*
X943672Y1562793D01*
G03X945581Y1562000I1911J1907D01*
G01X1079201D01*
G03X1079671Y1562092I-1J1250D01*
G01X1080216Y1562313D01*
G03X1080645Y1562602I-469J1159D01*
G01X1080842Y1562807D01*
X1081707Y1563672D01*
G03X1081801Y1563770I-1901J1917D01*
G02X1082380Y1563784I296J-269D01*
G01X1083798Y1562366D01*
G03X1084682Y1562000I884J885D01*
G01X1105660D01*
G03X1106544Y1562366I0J1251D01*
G01X1108636Y1564458D01*
G03X1109002Y1565342I-885J884D01*
G01Y1598066D01*
G03X1108636Y1598950I-1251J0D01*
G01X1107332Y1600254D01*
G03X1106448Y1600620I-884J-885D01*
G01X1095210D01*
G03X1095052Y1600630I-158J-1240D01*
G01X1084062D01*
G03X1083178Y1600264I0J-1251D01*
G01X1083024Y1600110D01*
G02X1082367Y1600255I-282J284D01*
G03X1081707Y1601328I-2566J-839D01*
G01X1080194Y1602842D01*
Y1603162D01*
X1081112Y1604080D01*
X1102758D01*
G03X1103642Y1604446I0J1251D01*
G01X1105274Y1606078D01*
G03X1105640Y1606962I-885J884D01*
G01Y1633288D01*
X1151544D01*
X1151601Y1633181D01*
G03X1154259I1329J698D01*
G01X1154316Y1633288D01*
X1200179D01*
X1200232Y1633170D01*
G03X1202968I1368J620D01*
G01X1203021Y1633288D01*
X1216928D01*
G03X1217812Y1633654I0J1251D01*
G01X1222474Y1638316D01*
G03X1222840Y1639200I-885J884D01*
G01Y1732462D01*
X1224496Y1734118D01*
X1236765D01*
X1236788Y1733945D01*
G03X1240772I1992J267D01*
G01X1240795Y1734118D01*
X1252513D01*
X1252536Y1733945D01*
G03X1256520I1992J267D01*
G01X1256543Y1734118D01*
X1268261D01*
X1268284Y1733945D01*
G03X1272268I1992J267D01*
G01X1272291Y1734118D01*
X1284009D01*
X1284032Y1733945D01*
G03X1288016I1992J267D01*
G01X1288039Y1734118D01*
X1303694D01*
X1303717Y1733945D01*
G03X1307701I1992J267D01*
G01X1307724Y1734118D01*
X1319442D01*
X1319465Y1733945D01*
G03X1323449I1992J267D01*
G01X1323472Y1734118D01*
X1335190D01*
X1335213Y1733945D01*
G03X1339197I1992J267D01*
G01X1339220Y1734118D01*
X1350938D01*
X1350961Y1733945D01*
G03X1354945I1992J267D01*
G01X1354968Y1734118D01*
X1402508D01*
Y1704833D01*
G03Y1691701I13929J-6566D01*
G01Y1656858D01*
X1430302D01*
Y1691571D01*
G03Y1704963I-13867J6696D01*
G01Y1734118D01*
X1452028D01*
G02X1452212Y1733363I0J-400D01*
G03X1441052Y1714961I9592J-18402D01*
G03X1482558I20753J0D01*
G03X1471398Y1733363I-20752J0D01*
G02X1471582Y1734118I184J355D01*
G01X1500938D01*
X1500961Y1733945D01*
G03X1504945I1992J267D01*
G01X1504968Y1734118D01*
X1516686D01*
X1516709Y1733945D01*
G03X1520693I1992J267D01*
G01X1520716Y1734118D01*
X1532434D01*
X1532457Y1733945D01*
G03X1536441I1992J267D01*
G01X1536464Y1734118D01*
X1548182D01*
X1548205Y1733945D01*
G03X1552189I1992J267D01*
G01X1552212Y1734118D01*
X1567867D01*
X1567890Y1733945D01*
G03X1571874I1992J267D01*
G01X1571897Y1734118D01*
X1583615D01*
X1583638Y1733945D01*
G03X1587622I1992J267D01*
G01X1587645Y1734118D01*
X1599363D01*
X1599386Y1733945D01*
G03X1603370I1992J267D01*
G01X1603393Y1734118D01*
X1615111D01*
X1615134Y1733945D01*
G03X1619118I1992J267D01*
G01X1619141Y1734118D01*
X1796522D01*
G02X1796706Y1733363I0J-400D01*
G03X1785546Y1714961I9592J-18402D01*
G03X1806299Y1694208I20753J0D01*
G03X1825127Y1706234I0J20752D01*
G02X1825890Y1706066I363J-168D01*
G01Y1612315D01*
G03X1829953Y1602506I13873J0D01*
G01X1837152Y1595307D01*
G02X1837701Y1593983I-1324J-1325D01*
G01Y1433025D01*
G02X1836974Y1432795I-400J0D01*
G03X1819209Y1442032I-17765J-12465D01*
G01X1819208D01*
G03Y1398628I0J-21702D01*
G01X1819209D01*
G03X1836974Y1407865I0J21702D01*
G02X1837701Y1407635I327J-230D01*
G01Y1373990D01*
G02X1836913Y1373894I-400J1D01*
G03X1816771Y1389650I-20142J-4996D01*
G03Y1348144I0J-20753D01*
G03X1836913Y1363900I0J20752D01*
G02X1837701Y1363804I388J-97D01*
G01Y636983D01*
G02X1836913Y636887I-400J1D01*
G03X1816771Y652642I-20142J-4998D01*
G03Y611138I0J-20752D01*
G03X1836913Y626893I0J20753D01*
G02X1837701Y626797I388J-97D01*
G01Y460596D01*
X1837562Y460551D01*
G03Y457691I457J-1430D01*
G01X1837701Y457646D01*
Y455261D01*
G03Y452581I678J-1340D01*
G01Y326094D01*
G03X1841764Y316285I13873J0D01*
G01X1850931Y307118D01*
G02X1851480Y305794I-1324J-1325D01*
G01Y54252D01*
G02X1849606Y52378I-1874J0D01*
G01X1803945D01*
G03X1790071Y38504I0J-13874D01*
G01Y27781D01*
G02X1789448Y27449I-400J0D01*
G03Y21133I-2118J-3158D01*
G02X1790071Y20801I223J-332D01*
G01Y6000D01*
X1531992D01*
Y16851D01*
G02X1532613Y17184I400J0D01*
G03Y23525I2099J3170D01*
G02X1531992Y23858I-221J333D01*
G01Y38504D01*
G03X1518118Y52378I-13874J0D01*
G01X1262702D01*
X1262658Y52517D01*
G03X1261227Y53563I-1431J-456D01*
G03X1260240Y53193I0J-1501D01*
G02X1259714I-263J302D01*
G03X1258727Y53563I-987J-1131D01*
G03X1257296Y52517I0J-1502D01*
G01X1257252Y52378D01*
X1026772D01*
G02X1024898Y54252I0J1874D01*
G01Y82853D01*
G02X1025687Y82946I400J0D01*
G03X1045865Y67042I20178J4848D01*
G03Y108548I0J20753D01*
G03X1025687Y92644I0J-20752D01*
G02X1024898Y92737I-389J93D01*
G01Y131004D01*
G03X1011024Y144878I-13874J0D01*
G01X887008D01*
G03X873134Y131004I0J-13874D01*
G01Y54252D01*
G02X871260Y52378I-1874J0D01*
G01X774417D01*
G03X762331Y45318I0J-13875D01*
G02X761585Y45473I-348J196D01*
G03X760292Y42204I-3782J-394D01*
G02X760944Y41814I262J-302D01*
G03X760543Y38504I13473J-3311D01*
G01Y26787D01*
X502465D01*
Y37639D01*
G02X503086Y37972I400J0D01*
G03X502189Y43484I2099J3171D01*
G02X501502Y43583I-315J246D01*
G03X488591Y52378I-12911J-5079D01*
G01X329535D01*
G03X315661Y38504I0J-13874D01*
G01Y27782D01*
G37*
G36*
G01X1218684Y1734118D02*
X1220340Y1732462D01*
Y1639718D01*
X1216410Y1635788D01*
X1104908D01*
X1102962Y1637734D01*
G03X1102078Y1638100I-884J-885D01*
G01X1085876D01*
X1065772Y1658204D01*
G03X1064888Y1658570I-884J-885D01*
G01X918658D01*
X909510Y1667718D01*
Y1712848D01*
G03X909144Y1713732I-1251J0D01*
G01X902102Y1720774D01*
G03X901218Y1721140I-884J-885D01*
G01X816942D01*
G03X816058Y1720774I0J-1251D01*
G01X810826Y1715542D01*
G03X810460Y1714658I885J-884D01*
G01Y1692196D01*
X776584Y1658320D01*
X758750D01*
G03X757866Y1657954I0J-1251D01*
G01X731120Y1631208D01*
X713959D01*
X713947Y1631209D01*
G03X713791Y1631218I-159J-1393D01*
G03X713635Y1631209I3J-1402D01*
G01X713623Y1631208D01*
X711019D01*
X710989Y1631217D01*
G03X710570Y1631282I-420J-1327D01*
G03X710151Y1631217I1J-1392D01*
G01X710121Y1631208D01*
X671640D01*
X661060Y1641788D01*
Y1731992D01*
X663186Y1734118D01*
X762234D01*
G03X769705Y1728921I7471J2772D01*
G01X1087854D01*
G03X1095325Y1734118I0J7969D01*
G01X1218684D01*
G37*
G36*
G01X817460Y1718640D02*
X900700D01*
X907010Y1712330D01*
Y1667200D01*
G03X907376Y1666316I1251J0D01*
G01X917256Y1656436D01*
G03X918140Y1656070I884J885D01*
G01X1064370D01*
X1084474Y1635966D01*
G03X1085358Y1635600I884J885D01*
G01X1101560D01*
X1103140Y1634020D01*
Y1607480D01*
X1102240Y1606580D01*
X943698D01*
G03X942814Y1606214I0J-1251D01*
G01X935490Y1598890D01*
X927248D01*
G03X926364Y1598524I0J-1251D01*
G01X921156Y1593316D01*
G03X920790Y1592432I885J-884D01*
G01Y1578870D01*
X920730Y1578810D01*
X907390D01*
X907330Y1578870D01*
Y1592414D01*
G03X906964Y1593298I-1251J0D01*
G01X906522Y1593740D01*
Y1603900D01*
G03X906156Y1604784I-1251J0D01*
G01X898266Y1612674D01*
G03X897382Y1613040I-884J-885D01*
G01X888610D01*
G03X887726Y1612674I0J-1251D01*
G01X879888Y1604836D01*
G03X879522Y1603952I885J-884D01*
G01Y1593670D01*
X879176Y1593324D01*
G03X878810Y1592440I885J-884D01*
G01Y1578920D01*
X878710Y1578820D01*
X865410D01*
X865340Y1578890D01*
Y1592484D01*
G03X864974Y1593368I-1251J0D01*
G01X864622Y1593720D01*
Y1603382D01*
G03X864256Y1604266I-1251J0D01*
G01X856288Y1612234D01*
G03X855404Y1612600I-884J-885D01*
G01X845648D01*
G03X844764Y1612234I0J-1251D01*
G01X837846Y1605316D01*
G03X837480Y1604432I885J-884D01*
G01Y1593680D01*
X837146Y1593346D01*
G03X836780Y1592462I885J-884D01*
G01Y1578840D01*
X836760Y1578820D01*
X823390D01*
X823370Y1578840D01*
Y1592334D01*
G03X823004Y1593218I-1251J0D01*
G01X822622Y1593600D01*
Y1603560D01*
G03X822256Y1604444I-1251J0D01*
G01X814056Y1612644D01*
G03X813172Y1613010I-884J-885D01*
G01X803780D01*
G03X802896Y1612644I0J-1251D01*
G01X795888Y1605636D01*
G03X795522Y1604752I885J-884D01*
G01Y1593622D01*
X795156Y1593256D01*
G03X794790Y1592372I885J-884D01*
G01Y1578870D01*
X794740Y1578820D01*
X781390D01*
X781370Y1578840D01*
Y1592472D01*
G03X781004Y1593356I-1251J0D01*
G01X776356Y1598004D01*
G03X775472Y1598370I-884J-885D01*
G01X751458D01*
G03X750574Y1598004I0J-1251D01*
G01X745888Y1593317D01*
G03X745522Y1592433I885J-884D01*
G01Y1591251D01*
X745422Y1591151D01*
X744540D01*
G03X743656Y1590785I0J-1251D01*
G01X742956Y1590085D01*
G03X742590Y1589201I885J-884D01*
G01Y1578820D01*
X742522Y1578751D01*
X729122D01*
Y1600351D01*
X730056Y1601285D01*
G03X730360Y1601779I-884J885D01*
G03X730554Y1602518I-1308J738D01*
G03X730438Y1603098I-1502J1D01*
G01X730422Y1603135D01*
Y1607433D01*
G03X730056Y1608317I-1251J0D01*
G01X729622Y1608751D01*
Y1626174D01*
X759268Y1655820D01*
X777102D01*
G03X777986Y1656186I0J1251D01*
G01X812594Y1690794D01*
G03X812960Y1691678I-885J884D01*
G01Y1714140D01*
X817460Y1718640D01*
G37*
G36*
G01X1077918Y1601500D02*
G02X1078058Y1601442I-1J-200D01*
G01X1079940Y1599560D01*
G03X1080000Y1599504I882J885D01*
G01Y1565496D01*
G03X1079940Y1565440I822J-941D01*
G01X1079067Y1564567D01*
G03X1079004Y1564500I879J-889D01*
G01X945496D01*
G03X945440Y1564560I-941J-822D01*
G01X943567Y1566433D01*
X943566Y1566434D01*
G03X943500Y1566496I-888J-880D01*
G01Y1600504D01*
G03X943560Y1600560I-822J941D01*
G01X944440Y1601440D01*
G03X944496Y1601500I-885J882D01*
G01X1077918D01*
G37*
G36*
G01X1105930Y1598120D02*
X1106502Y1597548D01*
Y1565860D01*
X1105142Y1564500D01*
X1085200D01*
X1084200Y1565500D01*
Y1597750D01*
X1084580Y1598130D01*
X1094904D01*
X1094915Y1598129D01*
G03X1095062Y1598120I150J1241D01*
G01X1105930D01*
G37*
G36*
G01X1867354Y305795D02*
G03X1862156Y318343I-17746J-1D01*
G01X1855296Y325203D01*
G02X1853575Y329357I4153J4154D01*
G01Y1593984D01*
G03X1848377Y1606532I-17746J-1D01*
G01X1843484Y1611425D01*
G02X1841764Y1615579I4156J4154D01*
G01Y1732244D01*
G02X1847638Y1738118I5874J0D01*
G01X1857480D01*
G03X1867354Y1747992I0J9874D01*
G01Y1815072D01*
G02X1873228Y1820946I5874J0D01*
G01X2093700D01*
G02X2099574Y1815072I0J-5874D01*
G01Y1791450D01*
G02X2093700Y1785576I-5874J0D01*
G01X2031574D01*
G03X2021700Y1775702I0J-9874D01*
G01Y1229954D01*
G03X2031574Y1220080I9874J0D01*
G01X2093700D01*
G02X2099574Y1214206I0J-5874D01*
G01Y-40945D01*
G02X2093700Y-46819I-5874J0D01*
G01X1873228D01*
G02X1867354Y-40945I0J5874D01*
G01Y305795D01*
G37*
%LPD*%
G75*
G36*
G01X1758669Y52153D02*
G02X1760173Y50649I0J-1504D01*
G01Y50648D01*
G02X1760172Y50593I-1504J0D01*
G02X1758669Y49100I-1503J10D01*
G01X1755269D01*
G02X1753766Y50593I0J1503D01*
G02X1753765Y50648I1503J55D01*
G01Y50649D01*
G02X1755269Y52153I1504J0D01*
G02X1755620Y52112I2J-1504D01*
G01X1755643Y52106D01*
X1758295D01*
X1758318Y52112D01*
G02X1758669Y52153I349J-1463D01*
G37*
G36*
G01X880168Y504762D02*
Y508162D01*
G02X881670Y509664I1502J0D01*
G02X882945Y508955I0J-1501D01*
G02X883184Y508142I-1265J-813D01*
G01Y508141D01*
G02X883173Y507963I-1504J4D01*
G01X883172Y507952D01*
Y504897D01*
X883173Y504888D01*
G02X883180Y504743I-1493J-145D01*
G01Y504742D01*
G02X881680Y503242I-1500J0D01*
G02X880398Y503963I0J1500D01*
G02X880168Y504762I1273J799D01*
G37*
G36*
G01X963269Y1556947D02*
G03X963539I135J148D01*
G02X965904Y1557866I2365J-2584D01*
G02X969159Y1555655I0J-3501D01*
G02X970402Y1554262I-159J-1393D01*
G02X969067Y1552862I-1402J0D01*
G02X965904Y1550862I-3163J1501D01*
G02X963539Y1551781I0J3503D01*
G03X963269I-135J-148D01*
G02X960904Y1550862I-2365J2584D01*
G02Y1557866I0J3502D01*
G02X963269Y1556947I0J-3503D01*
G37*
G36*
G01X986635D02*
G03X986905I135J148D01*
G02X989270Y1557866I2365J-2584D01*
G02X992522Y1555663I0J-3502D01*
G02X993868Y1554262I-56J-1401D01*
G02X992466Y1552860I-1402J0D01*
G01X992433D01*
G02X989270Y1550862I-3163J1505D01*
G02X986905Y1551781I0J3503D01*
G03X986635I-135J-148D01*
G02X984270Y1550862I-2365J2584D01*
G02Y1557866I0J3502D01*
G02X986635Y1556947I0J-3503D01*
G37*
G36*
G01X1010001D02*
G03X1010271I135J148D01*
G02X1012636Y1557866I2365J-2584D01*
G02X1015890Y1555659I0J-3502D01*
G02X1016012Y1555664I118J-1397D01*
G02Y1552860I0J-1402D01*
G01X1016009D01*
G02X1015806Y1552875I2J1402D01*
G02X1012636Y1550862I-3170J1490D01*
G02X1010271Y1551781I0J3503D01*
G03X1010001I-135J-148D01*
G02X1007636Y1550862I-2365J2584D01*
G02Y1557866I0J3502D01*
G02X1010001Y1556947I0J-3503D01*
G37*
G36*
G01X1033367D02*
G03X1033637I135J148D01*
G02X1036002Y1557866I2365J-2584D01*
G02X1039254Y1555663I0J-3502D01*
G02X1039298Y1555664I54J-1401D01*
G02Y1552860I0J-1402D01*
G02X1039167Y1552866I-1J1402D01*
G02X1036002Y1550862I-3165J1497D01*
G02X1033637Y1551781I0J3503D01*
G03X1033367I-135J-148D01*
G02X1031002Y1550862I-2365J2584D01*
G02Y1557866I0J3502D01*
G02X1033367Y1556947I0J-3503D01*
G37*
G36*
G01X1056733D02*
G03X1057003I135J148D01*
G02X1059368Y1557866I2365J-2584D01*
G02X1062623Y1555655I0J-3501D01*
G02X1063866Y1554262I-159J-1393D01*
G02X1062531Y1552862I-1402J0D01*
G02X1059368Y1550862I-3163J1501D01*
G02X1057003Y1551781I0J3503D01*
G03X1056733I-135J-148D01*
G02X1054368Y1550862I-2365J2584D01*
G02Y1557866I0J3502D01*
G02X1056733Y1556947I0J-3503D01*
G37*
G36*
G01X1080099D02*
G03X1080369I135J148D01*
G02X1082734Y1557866I2365J-2584D01*
G02X1085989Y1555655I0J-3501D01*
G02X1087232Y1554262I-159J-1393D01*
G02X1085897Y1552862I-1402J0D01*
G02X1082734Y1550862I-3163J1501D01*
G02X1080369Y1551781I0J3503D01*
G03X1080099I-135J-148D01*
G02X1077734Y1550862I-2365J2584D01*
G02Y1557866I0J3502D01*
G02X1080099Y1556947I0J-3503D01*
G37*
G36*
G01X229206Y1656840D02*
X232906D01*
G02X233208Y1656537I-1J-303D01*
G01Y1646531D01*
G02X232906Y1646228I-302J-1D01*
G01X229206D01*
G02X228904Y1646531I1J303D01*
G01Y1648936D01*
G02X228890Y1649173I2002J237D01*
G02X228904Y1649410I2016J0D01*
G01Y1653660D01*
G02X228890Y1653897I2002J237D01*
G02X228904Y1654134I2016J0D01*
G01Y1656537D01*
G02X229206Y1656840I302J1D01*
G37*
G36*
G01X276450D02*
X280150D01*
G02X280452Y1656537I-1J-303D01*
G01Y1646531D01*
G02X280150Y1646228I-302J-1D01*
G01X276450D01*
G02X276148Y1646531I1J303D01*
G01Y1648936D01*
G02X276134Y1649173I2002J237D01*
G02X276148Y1649410I2016J0D01*
G01Y1653660D01*
G02X276134Y1653897I2002J237D01*
G02X276148Y1654134I2016J0D01*
G01Y1656537D01*
G02X276450Y1656840I302J1D01*
G37*
G36*
G01X237080Y1660776D02*
X240780D01*
G02X241082Y1660474I0J-302D01*
G01Y1650468D01*
G02X240780Y1650166I-302J0D01*
G01X237080D01*
G02X236778Y1650468I0J302D01*
G01Y1652873D01*
G02X236764Y1653110I2002J237D01*
G02X236778Y1653347I2016J0D01*
G01Y1657597D01*
G02X236764Y1657834I2002J237D01*
G02X236778Y1658071I2016J0D01*
G01Y1660474D01*
G02X237080Y1660776I302J0D01*
G37*
G36*
G01X268576D02*
X272276D01*
G02X272578Y1660474I0J-302D01*
G01Y1650468D01*
G02X272276Y1650166I-302J0D01*
G01X268576D01*
G02X268274Y1650468I0J302D01*
G01Y1652873D01*
G02X268260Y1653110I2002J237D01*
G02X268274Y1653347I2016J0D01*
G01Y1657597D01*
G02X268260Y1657834I2002J237D01*
G02X268274Y1658071I2016J0D01*
G01Y1660474D01*
G02X268576Y1660776I302J0D01*
G37*
G36*
G01X284324D02*
X288024D01*
G02X288326Y1660474I0J-302D01*
G01Y1650468D01*
G02X288024Y1650166I-302J0D01*
G01X284324D01*
G02X284022Y1650468I0J302D01*
G01Y1652873D01*
G02X284008Y1653110I2002J237D01*
G02X284022Y1653347I2016J0D01*
G01Y1657597D01*
G02X284008Y1657834I2002J237D01*
G02X284022Y1658071I2016J0D01*
G01Y1660474D01*
G02X284324Y1660776I302J0D01*
G37*
G36*
G01X229206Y1671014D02*
X232906D01*
G02X233208Y1670711I-1J-303D01*
G01Y1660705D01*
G02X232906Y1660402I-302J-1D01*
G01X229206D01*
G02X228904Y1660705I1J303D01*
G01Y1663109D01*
G02X228890Y1663346I2002J237D01*
G02X228904Y1663583I2016J0D01*
G01Y1667833D01*
G02X228890Y1668070I2002J237D01*
G02X228904Y1668307I2016J0D01*
G01Y1670711D01*
G02X229206Y1671014I302J1D01*
G37*
G36*
G01X244954D02*
X248654D01*
G02X248956Y1670711I-1J-303D01*
G01Y1660705D01*
G02X248654Y1660402I-302J-1D01*
G01X244954D01*
G02X244652Y1660705I1J303D01*
G01Y1663109D01*
G02X244638Y1663346I2002J237D01*
G02X244652Y1663583I2016J0D01*
G01Y1667833D01*
G02X244638Y1668070I2002J237D01*
G02X244652Y1668307I2016J0D01*
G01Y1670711D01*
G02X244954Y1671014I302J1D01*
G37*
G36*
G01X276450D02*
X280150D01*
G02X280452Y1670711I-1J-303D01*
G01Y1660705D01*
G02X280150Y1660402I-302J-1D01*
G01X276450D01*
G02X276148Y1660705I1J303D01*
G01Y1663109D01*
G02X276134Y1663346I2002J237D01*
G02X276148Y1663583I2016J0D01*
G01Y1667833D01*
G02X276134Y1668070I2002J237D01*
G02X276148Y1668307I2016J0D01*
G01Y1670711D01*
G02X276450Y1671014I302J1D01*
G37*
G36*
G01X252828Y1674950D02*
X256528D01*
G02X256830Y1674648I0J-302D01*
G01Y1664642D01*
G02X256528Y1664340I-302J0D01*
G01X252828D01*
G02X252526Y1664642I0J302D01*
G01Y1667046D01*
G02X252512Y1667283I2002J237D01*
G02X252526Y1667520I2016J0D01*
G01Y1671770D01*
G02X252512Y1672007I2002J237D01*
G02X252526Y1672244I2016J0D01*
G01Y1674648D01*
G02X252828Y1674950I302J0D01*
G37*
G36*
G01X268576D02*
X272276D01*
G02X272578Y1674648I0J-302D01*
G01Y1664642D01*
G02X272276Y1664340I-302J0D01*
G01X268576D01*
G02X268274Y1664642I0J302D01*
G01Y1667046D01*
G02X268260Y1667283I2002J237D01*
G02X268274Y1667520I2016J0D01*
G01Y1671770D01*
G02X268260Y1672007I2002J237D01*
G02X268274Y1672244I2016J0D01*
G01Y1674648D01*
G02X268576Y1674950I302J0D01*
G37*
G36*
G01X284324D02*
X288024D01*
G02X288326Y1674648I0J-302D01*
G01Y1664642D01*
G02X288024Y1664340I-302J0D01*
G01X284324D01*
G02X284022Y1664642I0J302D01*
G01Y1667046D01*
G02X284008Y1667283I2002J237D01*
G02X284022Y1667520I2016J0D01*
G01Y1671770D01*
G02X284008Y1672007I2002J237D01*
G02X284022Y1672244I2016J0D01*
G01Y1674648D01*
G02X284324Y1674950I302J0D01*
G37*
G36*
G01X229206Y1685186D02*
X232906D01*
G02X233208Y1684884I0J-302D01*
G01Y1674878D01*
G02X232906Y1674576I-302J0D01*
G01X229206D01*
G02X228904Y1674878I0J302D01*
G01Y1677282D01*
G02X228890Y1677519I2002J237D01*
G02X228904Y1677756I2016J0D01*
G01Y1682007D01*
G02X228890Y1682244I2002J237D01*
G02X228904Y1682481I2016J0D01*
G01Y1684884D01*
G02X229206Y1685186I302J0D01*
G37*
G36*
G01X244954D02*
X248654D01*
G02X248956Y1684884I0J-302D01*
G01Y1674878D01*
G02X248654Y1674576I-302J0D01*
G01X244954D01*
G02X244652Y1674878I0J302D01*
G01Y1677282D01*
G02X244638Y1677519I2002J237D01*
G02X244652Y1677756I2016J0D01*
G01Y1682007D01*
G02X244638Y1682244I2002J237D01*
G02X244652Y1682481I2016J0D01*
G01Y1684884D01*
G02X244954Y1685186I302J0D01*
G37*
G36*
G01X260702D02*
X264402D01*
G02X264704Y1684884I0J-302D01*
G01Y1674878D01*
G02X264402Y1674576I-302J0D01*
G01X260702D01*
G02X260400Y1674878I0J302D01*
G01Y1677282D01*
G02X260386Y1677519I2002J237D01*
G02X260400Y1677756I2016J0D01*
G01Y1682007D01*
G02X260386Y1682244I2002J237D01*
G02X260400Y1682481I2016J0D01*
G01Y1684884D01*
G02X260702Y1685186I302J0D01*
G37*
G36*
G01X276450D02*
X280150D01*
G02X280452Y1684884I0J-302D01*
G01Y1674878D01*
G02X280150Y1674576I-302J0D01*
G01X276450D01*
G02X276148Y1674878I0J302D01*
G01Y1677282D01*
G02X276134Y1677519I2002J237D01*
G02X276148Y1677756I2016J0D01*
G01Y1682007D01*
G02X276134Y1682244I2002J237D01*
G02X276148Y1682481I2016J0D01*
G01Y1684884D01*
G02X276450Y1685186I302J0D01*
G37*
G36*
G01X560308D02*
X564008D01*
G02X564310Y1684884I0J-302D01*
G01Y1674878D01*
G02X564008Y1674576I-302J0D01*
G01X560308D01*
G02X560006Y1674878I0J302D01*
G01Y1677282D01*
G02X559992Y1677519I2002J237D01*
G02X560006Y1677756I2016J0D01*
G01Y1682007D01*
G02X559992Y1682244I2002J237D01*
G02X560006Y1682481I2016J0D01*
G01Y1684884D01*
G02X560308Y1685186I302J0D01*
G37*
G36*
G01X576056D02*
X579756D01*
G02X580058Y1684884I0J-302D01*
G01Y1674878D01*
G02X579756Y1674576I-302J0D01*
G01X576056D01*
G02X575754Y1674878I0J302D01*
G01Y1677282D01*
G02X575740Y1677519I2002J237D01*
G02X575754Y1677756I2016J0D01*
G01Y1682007D01*
G02X575740Y1682244I2002J237D01*
G02X575754Y1682481I2016J0D01*
G01Y1684884D01*
G02X576056Y1685186I302J0D01*
G37*
G36*
G01X591804D02*
X595504D01*
G02X595806Y1684884I0J-302D01*
G01Y1674878D01*
G02X595504Y1674576I-302J0D01*
G01X591804D01*
G02X591502Y1674878I0J302D01*
G01Y1677282D01*
G02X591488Y1677519I2002J237D01*
G02X591502Y1677756I2016J0D01*
G01Y1682007D01*
G02X591488Y1682244I2002J237D01*
G02X591502Y1682481I2016J0D01*
G01Y1684884D01*
G02X591804Y1685186I302J0D01*
G37*
G36*
G01X607552D02*
X611252D01*
G02X611554Y1684884I0J-302D01*
G01Y1674878D01*
G02X611252Y1674576I-302J0D01*
G01X607552D01*
G02X607250Y1674878I0J302D01*
G01Y1677282D01*
G02X607236Y1677519I2002J237D01*
G02X607250Y1677756I2016J0D01*
G01Y1682007D01*
G02X607236Y1682244I2002J237D01*
G02X607250Y1682481I2016J0D01*
G01Y1684884D01*
G02X607552Y1685186I302J0D01*
G37*
G36*
G01X1237080D02*
X1240780D01*
G02X1241082Y1684884I0J-302D01*
G01Y1674878D01*
G02X1240780Y1674576I-302J0D01*
G01X1237080D01*
G02X1236778Y1674878I0J302D01*
G01Y1677282D01*
G02X1236764Y1677519I2002J237D01*
G02X1236778Y1677756I2016J0D01*
G01Y1682007D01*
G02X1236764Y1682244I2002J237D01*
G02X1236778Y1682481I2016J0D01*
G01Y1684884D01*
G02X1237080Y1685186I302J0D01*
G37*
G36*
G01X1252828D02*
X1256528D01*
G02X1256830Y1684884I0J-302D01*
G01Y1674878D01*
G02X1256528Y1674576I-302J0D01*
G01X1252828D01*
G02X1252526Y1674878I0J302D01*
G01Y1677282D01*
G02X1252512Y1677519I2002J237D01*
G02X1252526Y1677756I2016J0D01*
G01Y1682007D01*
G02X1252512Y1682244I2002J237D01*
G02X1252526Y1682481I2016J0D01*
G01Y1684884D01*
G02X1252828Y1685186I302J0D01*
G37*
G36*
G01X1268576D02*
X1272276D01*
G02X1272578Y1684884I0J-302D01*
G01Y1674878D01*
G02X1272276Y1674576I-302J0D01*
G01X1268576D01*
G02X1268274Y1674878I0J302D01*
G01Y1677282D01*
G02X1268260Y1677519I2002J237D01*
G02X1268274Y1677756I2016J0D01*
G01Y1682007D01*
G02X1268260Y1682244I2002J237D01*
G02X1268274Y1682481I2016J0D01*
G01Y1684884D01*
G02X1268576Y1685186I302J0D01*
G37*
G36*
G01X1284324D02*
X1288024D01*
G02X1288326Y1684884I0J-302D01*
G01Y1674878D01*
G02X1288024Y1674576I-302J0D01*
G01X1284324D01*
G02X1284022Y1674878I0J302D01*
G01Y1677282D01*
G02X1284008Y1677519I2002J237D01*
G02X1284022Y1677756I2016J0D01*
G01Y1682007D01*
G02X1284008Y1682244I2002J237D01*
G02X1284022Y1682481I2016J0D01*
G01Y1684884D01*
G02X1284324Y1685186I302J0D01*
G37*
G36*
G01X1568182D02*
X1571882D01*
G02X1572184Y1684884I0J-302D01*
G01Y1674878D01*
G02X1571882Y1674576I-302J0D01*
G01X1568182D01*
G02X1567880Y1674878I0J302D01*
G01Y1677282D01*
G02X1567866Y1677519I2002J237D01*
G02X1567880Y1677756I2016J0D01*
G01Y1682007D01*
G02X1567866Y1682244I2002J237D01*
G02X1567880Y1682481I2016J0D01*
G01Y1684884D01*
G02X1568182Y1685186I302J0D01*
G37*
G36*
G01X1583930D02*
X1587630D01*
G02X1587932Y1684884I0J-302D01*
G01Y1674878D01*
G02X1587630Y1674576I-302J0D01*
G01X1583930D01*
G02X1583628Y1674878I0J302D01*
G01Y1677282D01*
G02X1583614Y1677519I2002J237D01*
G02X1583628Y1677756I2016J0D01*
G01Y1682007D01*
G02X1583614Y1682244I2002J237D01*
G02X1583628Y1682481I2016J0D01*
G01Y1684884D01*
G02X1583930Y1685186I302J0D01*
G37*
G36*
G01X1599678D02*
X1603378D01*
G02X1603680Y1684884I0J-302D01*
G01Y1674878D01*
G02X1603378Y1674576I-302J0D01*
G01X1599678D01*
G02X1599376Y1674878I0J302D01*
G01Y1677282D01*
G02X1599362Y1677519I2002J237D01*
G02X1599376Y1677756I2016J0D01*
G01Y1682007D01*
G02X1599362Y1682244I2002J237D01*
G02X1599376Y1682481I2016J0D01*
G01Y1684884D01*
G02X1599678Y1685186I302J0D01*
G37*
G36*
G01X1615426D02*
X1619126D01*
G02X1619428Y1684884I0J-302D01*
G01Y1674878D01*
G02X1619126Y1674576I-302J0D01*
G01X1615426D01*
G02X1615124Y1674878I0J302D01*
G01Y1677282D01*
G02X1615110Y1677519I2002J237D01*
G02X1615124Y1677756I2016J0D01*
G01Y1682007D01*
G02X1615110Y1682244I2002J237D01*
G02X1615124Y1682481I2016J0D01*
G01Y1684884D01*
G02X1615426Y1685186I302J0D01*
G37*
G36*
G01X296135D02*
X299835D01*
G02X300138Y1684884I1J-302D01*
G01Y1674878D01*
G02X299835Y1674576I-303J1D01*
G01X296135D01*
G02X295832Y1674878I-1J302D01*
G01Y1677290D01*
G02X295819Y1677519I2003J229D01*
G02X295832Y1677748I2016J0D01*
G01Y1682015D01*
G02X295819Y1682244I2003J229D01*
G02X295832Y1682473I2016J0D01*
G01Y1684884D01*
G02X296135Y1685186I303J-1D01*
G37*
G36*
G01X311883D02*
X315583D01*
G02X315886Y1684884I1J-302D01*
G01Y1674878D01*
G02X315583Y1674576I-303J1D01*
G01X311883D01*
G02X311580Y1674878I-1J302D01*
G01Y1677290D01*
G02X311567Y1677519I2003J229D01*
G02X311580Y1677748I2016J0D01*
G01Y1682015D01*
G02X311567Y1682244I2003J229D01*
G02X311580Y1682473I2016J0D01*
G01Y1684884D01*
G02X311883Y1685186I303J-1D01*
G37*
G36*
G01X327631D02*
X331331D01*
G02X331634Y1684884I1J-302D01*
G01Y1674878D01*
G02X331331Y1674576I-303J1D01*
G01X327631D01*
G02X327328Y1674878I-1J302D01*
G01Y1677290D01*
G02X327315Y1677519I2003J229D01*
G02X327328Y1677748I2016J0D01*
G01Y1682015D01*
G02X327315Y1682244I2003J229D01*
G02X327328Y1682473I2016J0D01*
G01Y1684884D01*
G02X327631Y1685186I303J-1D01*
G37*
G36*
G01X343379D02*
X347079D01*
G02X347382Y1684884I1J-302D01*
G01Y1674878D01*
G02X347079Y1674576I-303J1D01*
G01X343379D01*
G02X343076Y1674878I-1J302D01*
G01Y1677290D01*
G02X343063Y1677519I2003J229D01*
G02X343076Y1677748I2016J0D01*
G01Y1682015D01*
G02X343063Y1682244I2003J229D01*
G02X343076Y1682473I2016J0D01*
G01Y1684884D01*
G02X343379Y1685186I303J-1D01*
G37*
G36*
G01X493379D02*
X497079D01*
G02X497382Y1684884I1J-302D01*
G01Y1674878D01*
G02X497079Y1674576I-303J1D01*
G01X493379D01*
G02X493076Y1674878I-1J302D01*
G01Y1677290D01*
G02X493063Y1677519I2003J229D01*
G02X493076Y1677748I2016J0D01*
G01Y1682015D01*
G02X493063Y1682244I2003J229D01*
G02X493076Y1682473I2016J0D01*
G01Y1684884D01*
G02X493379Y1685186I303J-1D01*
G37*
G36*
G01X509127D02*
X512827D01*
G02X513130Y1684884I1J-302D01*
G01Y1674878D01*
G02X512827Y1674576I-303J1D01*
G01X509127D01*
G02X508824Y1674878I-1J302D01*
G01Y1677290D01*
G02X508811Y1677519I2003J229D01*
G02X508824Y1677748I2016J0D01*
G01Y1682015D01*
G02X508811Y1682244I2003J229D01*
G02X508824Y1682473I2016J0D01*
G01Y1684884D01*
G02X509127Y1685186I303J-1D01*
G37*
G36*
G01X524875D02*
X528575D01*
G02X528878Y1684884I1J-302D01*
G01Y1674878D01*
G02X528575Y1674576I-303J1D01*
G01X524875D01*
G02X524572Y1674878I-1J302D01*
G01Y1677290D01*
G02X524559Y1677519I2003J229D01*
G02X524572Y1677748I2016J0D01*
G01Y1682015D01*
G02X524559Y1682244I2003J229D01*
G02X524572Y1682473I2016J0D01*
G01Y1684884D01*
G02X524875Y1685186I303J-1D01*
G37*
G36*
G01X540623D02*
X544323D01*
G02X544626Y1684884I1J-302D01*
G01Y1674878D01*
G02X544323Y1674576I-303J1D01*
G01X540623D01*
G02X540320Y1674878I-1J302D01*
G01Y1677290D01*
G02X540307Y1677519I2003J229D01*
G02X540320Y1677748I2016J0D01*
G01Y1682015D01*
G02X540307Y1682244I2003J229D01*
G02X540320Y1682473I2016J0D01*
G01Y1684884D01*
G02X540623Y1685186I303J-1D01*
G37*
G36*
G01X1304009D02*
X1307709D01*
G02X1308012Y1684884I1J-302D01*
G01Y1674878D01*
G02X1307709Y1674576I-303J1D01*
G01X1304009D01*
G02X1303706Y1674878I-1J302D01*
G01Y1677290D01*
G02X1303693Y1677519I2003J229D01*
G02X1303706Y1677748I2016J0D01*
G01Y1682015D01*
G02X1303693Y1682244I2003J229D01*
G02X1303706Y1682473I2016J0D01*
G01Y1684884D01*
G02X1304009Y1685186I303J-1D01*
G37*
G36*
G01X1319757D02*
X1323457D01*
G02X1323760Y1684884I1J-302D01*
G01Y1674878D01*
G02X1323457Y1674576I-303J1D01*
G01X1319757D01*
G02X1319454Y1674878I-1J302D01*
G01Y1677290D01*
G02X1319441Y1677519I2003J229D01*
G02X1319454Y1677748I2016J0D01*
G01Y1682015D01*
G02X1319441Y1682244I2003J229D01*
G02X1319454Y1682473I2016J0D01*
G01Y1684884D01*
G02X1319757Y1685186I303J-1D01*
G37*
G36*
G01X1335505D02*
X1339205D01*
G02X1339508Y1684884I1J-302D01*
G01Y1674878D01*
G02X1339205Y1674576I-303J1D01*
G01X1335505D01*
G02X1335202Y1674878I-1J302D01*
G01Y1677290D01*
G02X1335189Y1677519I2003J229D01*
G02X1335202Y1677748I2016J0D01*
G01Y1682015D01*
G02X1335189Y1682244I2003J229D01*
G02X1335202Y1682473I2016J0D01*
G01Y1684884D01*
G02X1335505Y1685186I303J-1D01*
G37*
G36*
G01X1351253D02*
X1354953D01*
G02X1355256Y1684884I1J-302D01*
G01Y1674878D01*
G02X1354953Y1674576I-303J1D01*
G01X1351253D01*
G02X1350950Y1674878I-1J302D01*
G01Y1677290D01*
G02X1350937Y1677519I2003J229D01*
G02X1350950Y1677748I2016J0D01*
G01Y1682015D01*
G02X1350937Y1682244I2003J229D01*
G02X1350950Y1682473I2016J0D01*
G01Y1684884D01*
G02X1351253Y1685186I303J-1D01*
G37*
G36*
G01X1501253D02*
X1504953D01*
G02X1505256Y1684884I1J-302D01*
G01Y1674878D01*
G02X1504953Y1674576I-303J1D01*
G01X1501253D01*
G02X1500950Y1674878I-1J302D01*
G01Y1677290D01*
G02X1500937Y1677519I2003J229D01*
G02X1500950Y1677748I2016J0D01*
G01Y1682015D01*
G02X1500937Y1682244I2003J229D01*
G02X1500950Y1682473I2016J0D01*
G01Y1684884D01*
G02X1501253Y1685186I303J-1D01*
G37*
G36*
G01X1517001D02*
X1520701D01*
G02X1521004Y1684884I1J-302D01*
G01Y1674878D01*
G02X1520701Y1674576I-303J1D01*
G01X1517001D01*
G02X1516698Y1674878I-1J302D01*
G01Y1677290D01*
G02X1516685Y1677519I2003J229D01*
G02X1516698Y1677748I2016J0D01*
G01Y1682015D01*
G02X1516685Y1682244I2003J229D01*
G02X1516698Y1682473I2016J0D01*
G01Y1684884D01*
G02X1517001Y1685186I303J-1D01*
G37*
G36*
G01X1532749D02*
X1536449D01*
G02X1536752Y1684884I1J-302D01*
G01Y1674878D01*
G02X1536449Y1674576I-303J1D01*
G01X1532749D01*
G02X1532446Y1674878I-1J302D01*
G01Y1677290D01*
G02X1532433Y1677519I2003J229D01*
G02X1532446Y1677748I2016J0D01*
G01Y1682015D01*
G02X1532433Y1682244I2003J229D01*
G02X1532446Y1682473I2016J0D01*
G01Y1684884D01*
G02X1532749Y1685186I303J-1D01*
G37*
G36*
G01X1548497D02*
X1552197D01*
G02X1552500Y1684884I1J-302D01*
G01Y1674878D01*
G02X1552197Y1674576I-303J1D01*
G01X1548497D01*
G02X1548194Y1674878I-1J302D01*
G01Y1677290D01*
G02X1548181Y1677519I2003J229D01*
G02X1548194Y1677748I2016J0D01*
G01Y1682015D01*
G02X1548181Y1682244I2003J229D01*
G02X1548194Y1682473I2016J0D01*
G01Y1684884D01*
G02X1548497Y1685186I303J-1D01*
G37*
G36*
G01X237080Y1689124D02*
X240780D01*
G02X241082Y1688821I-1J-303D01*
G01Y1678815D01*
G02X240780Y1678512I-302J-1D01*
G01X237080D01*
G02X236778Y1678815I1J303D01*
G01Y1681219D01*
G02X236764Y1681456I2002J237D01*
G02X236778Y1681693I2016J0D01*
G01Y1685943D01*
G02X236764Y1686180I2002J237D01*
G02X236778Y1686417I2016J0D01*
G01Y1688821D01*
G02X237080Y1689124I302J1D01*
G37*
G36*
G01X252828D02*
X256528D01*
G02X256830Y1688821I-1J-303D01*
G01Y1678815D01*
G02X256528Y1678512I-302J-1D01*
G01X252828D01*
G02X252526Y1678815I1J303D01*
G01Y1681219D01*
G02X252512Y1681456I2002J237D01*
G02X252526Y1681693I2016J0D01*
G01Y1685943D01*
G02X252512Y1686180I2002J237D01*
G02X252526Y1686417I2016J0D01*
G01Y1688821D01*
G02X252828Y1689124I302J1D01*
G37*
G36*
G01X268576D02*
X272276D01*
G02X272578Y1688821I-1J-303D01*
G01Y1678815D01*
G02X272276Y1678512I-302J-1D01*
G01X268576D01*
G02X268274Y1678815I1J303D01*
G01Y1681219D01*
G02X268260Y1681456I2002J237D01*
G02X268274Y1681693I2016J0D01*
G01Y1685943D01*
G02X268260Y1686180I2002J237D01*
G02X268274Y1686417I2016J0D01*
G01Y1688821D01*
G02X268576Y1689124I302J1D01*
G37*
G36*
G01X284324D02*
X288024D01*
G02X288326Y1688821I-1J-303D01*
G01Y1678815D01*
G02X288024Y1678512I-302J-1D01*
G01X284324D01*
G02X284022Y1678815I1J303D01*
G01Y1681219D01*
G02X284008Y1681456I2002J237D01*
G02X284022Y1681693I2016J0D01*
G01Y1685943D01*
G02X284008Y1686180I2002J237D01*
G02X284022Y1686417I2016J0D01*
G01Y1688821D01*
G02X284324Y1689124I302J1D01*
G37*
G36*
G01X304009D02*
X307709D01*
G02X308012Y1688821I0J-303D01*
G01Y1678815D01*
G02X307709Y1678512I-303J0D01*
G01X304009D01*
G02X303706Y1678815I0J303D01*
G01Y1681227D01*
G02X303693Y1681456I2003J229D01*
G02X303706Y1681685I2016J0D01*
G01Y1685951D01*
G02X303693Y1686180I2003J229D01*
G02X303706Y1686409I2016J0D01*
G01Y1688821D01*
G02X304009Y1689124I303J0D01*
G37*
G36*
G01X319757D02*
X323457D01*
G02X323760Y1688821I0J-303D01*
G01Y1678815D01*
G02X323457Y1678512I-303J0D01*
G01X319757D01*
G02X319454Y1678815I0J303D01*
G01Y1681227D01*
G02X319441Y1681456I2003J229D01*
G02X319454Y1681685I2016J0D01*
G01Y1685951D01*
G02X319441Y1686180I2003J229D01*
G02X319454Y1686409I2016J0D01*
G01Y1688821D01*
G02X319757Y1689124I303J0D01*
G37*
G36*
G01X335505D02*
X339205D01*
G02X339508Y1688821I0J-303D01*
G01Y1678815D01*
G02X339205Y1678512I-303J0D01*
G01X335505D01*
G02X335202Y1678815I0J303D01*
G01Y1681227D01*
G02X335189Y1681456I2003J229D01*
G02X335202Y1681685I2016J0D01*
G01Y1685951D01*
G02X335189Y1686180I2003J229D01*
G02X335202Y1686409I2016J0D01*
G01Y1688821D01*
G02X335505Y1689124I303J0D01*
G37*
G36*
G01X351253D02*
X354953D01*
G02X355256Y1688821I0J-303D01*
G01Y1678815D01*
G02X354953Y1678512I-303J0D01*
G01X351253D01*
G02X350950Y1678815I0J303D01*
G01Y1681227D01*
G02X350937Y1681456I2003J229D01*
G02X350950Y1681685I2016J0D01*
G01Y1685951D01*
G02X350937Y1686180I2003J229D01*
G02X350950Y1686409I2016J0D01*
G01Y1688821D01*
G02X351253Y1689124I303J0D01*
G37*
G36*
G01X501253D02*
X504953D01*
G02X505256Y1688821I0J-303D01*
G01Y1678815D01*
G02X504953Y1678512I-303J0D01*
G01X501253D01*
G02X500950Y1678815I0J303D01*
G01Y1681227D01*
G02X500937Y1681456I2003J229D01*
G02X500950Y1681685I2016J0D01*
G01Y1685951D01*
G02X500937Y1686180I2003J229D01*
G02X500950Y1686409I2016J0D01*
G01Y1688821D01*
G02X501253Y1689124I303J0D01*
G37*
G36*
G01X517001D02*
X520701D01*
G02X521004Y1688821I0J-303D01*
G01Y1678815D01*
G02X520701Y1678512I-303J0D01*
G01X517001D01*
G02X516698Y1678815I0J303D01*
G01Y1681227D01*
G02X516685Y1681456I2003J229D01*
G02X516698Y1681685I2016J0D01*
G01Y1685951D01*
G02X516685Y1686180I2003J229D01*
G02X516698Y1686409I2016J0D01*
G01Y1688821D01*
G02X517001Y1689124I303J0D01*
G37*
G36*
G01X532749D02*
X536449D01*
G02X536752Y1688821I0J-303D01*
G01Y1678815D01*
G02X536449Y1678512I-303J0D01*
G01X532749D01*
G02X532446Y1678815I0J303D01*
G01Y1681227D01*
G02X532433Y1681456I2003J229D01*
G02X532446Y1681685I2016J0D01*
G01Y1685951D01*
G02X532433Y1686180I2003J229D01*
G02X532446Y1686409I2016J0D01*
G01Y1688821D01*
G02X532749Y1689124I303J0D01*
G37*
G36*
G01X548497D02*
X552197D01*
G02X552500Y1688821I0J-303D01*
G01Y1678815D01*
G02X552197Y1678512I-303J0D01*
G01X548497D01*
G02X548194Y1678815I0J303D01*
G01Y1681227D01*
G02X548181Y1681456I2003J229D01*
G02X548194Y1681685I2016J0D01*
G01Y1685951D01*
G02X548181Y1686180I2003J229D01*
G02X548194Y1686409I2016J0D01*
G01Y1688821D01*
G02X548497Y1689124I303J0D01*
G37*
G36*
G01X568182D02*
X571882D01*
G02X572184Y1688821I-1J-303D01*
G01Y1678815D01*
G02X571882Y1678512I-302J-1D01*
G01X568182D01*
G02X567880Y1678815I1J303D01*
G01Y1681219D01*
G02X567866Y1681456I2002J237D01*
G02X567880Y1681693I2016J0D01*
G01Y1685943D01*
G02X567866Y1686180I2002J237D01*
G02X567880Y1686417I2016J0D01*
G01Y1688821D01*
G02X568182Y1689124I302J1D01*
G37*
G36*
G01X583930D02*
X587630D01*
G02X587932Y1688821I-1J-303D01*
G01Y1678815D01*
G02X587630Y1678512I-302J-1D01*
G01X583930D01*
G02X583628Y1678815I1J303D01*
G01Y1681219D01*
G02X583614Y1681456I2002J237D01*
G02X583628Y1681693I2016J0D01*
G01Y1685943D01*
G02X583614Y1686180I2002J237D01*
G02X583628Y1686417I2016J0D01*
G01Y1688821D01*
G02X583930Y1689124I302J1D01*
G37*
G36*
G01X599678D02*
X603378D01*
G02X603680Y1688821I-1J-303D01*
G01Y1678815D01*
G02X603378Y1678512I-302J-1D01*
G01X599678D01*
G02X599376Y1678815I1J303D01*
G01Y1681219D01*
G02X599362Y1681456I2002J237D01*
G02X599376Y1681693I2016J0D01*
G01Y1685943D01*
G02X599362Y1686180I2002J237D01*
G02X599376Y1686417I2016J0D01*
G01Y1688821D01*
G02X599678Y1689124I302J1D01*
G37*
G36*
G01X615426D02*
X619126D01*
G02X619428Y1688821I-1J-303D01*
G01Y1678815D01*
G02X619126Y1678512I-302J-1D01*
G01X615426D01*
G02X615124Y1678815I1J303D01*
G01Y1681219D01*
G02X615110Y1681456I2002J237D01*
G02X615124Y1681693I2016J0D01*
G01Y1685943D01*
G02X615110Y1686180I2002J237D01*
G02X615124Y1686417I2016J0D01*
G01Y1688821D01*
G02X615426Y1689124I302J1D01*
G37*
G36*
G01X1244954D02*
X1248654D01*
G02X1248956Y1688821I-1J-303D01*
G01Y1678815D01*
G02X1248654Y1678512I-302J-1D01*
G01X1244954D01*
G02X1244652Y1678815I1J303D01*
G01Y1681219D01*
G02X1244638Y1681456I2002J237D01*
G02X1244652Y1681693I2016J0D01*
G01Y1685943D01*
G02X1244638Y1686180I2002J237D01*
G02X1244652Y1686417I2016J0D01*
G01Y1688821D01*
G02X1244954Y1689124I302J1D01*
G37*
G36*
G01X1260702D02*
X1264402D01*
G02X1264704Y1688821I-1J-303D01*
G01Y1678815D01*
G02X1264402Y1678512I-302J-1D01*
G01X1260702D01*
G02X1260400Y1678815I1J303D01*
G01Y1681219D01*
G02X1260386Y1681456I2002J237D01*
G02X1260400Y1681693I2016J0D01*
G01Y1685943D01*
G02X1260386Y1686180I2002J237D01*
G02X1260400Y1686417I2016J0D01*
G01Y1688821D01*
G02X1260702Y1689124I302J1D01*
G37*
G36*
G01X1276450D02*
X1280150D01*
G02X1280452Y1688821I-1J-303D01*
G01Y1678815D01*
G02X1280150Y1678512I-302J-1D01*
G01X1276450D01*
G02X1276148Y1678815I1J303D01*
G01Y1681219D01*
G02X1276134Y1681456I2002J237D01*
G02X1276148Y1681693I2016J0D01*
G01Y1685943D01*
G02X1276134Y1686180I2002J237D01*
G02X1276148Y1686417I2016J0D01*
G01Y1688821D01*
G02X1276450Y1689124I302J1D01*
G37*
G36*
G01X1292198D02*
X1295898D01*
G02X1296200Y1688821I-1J-303D01*
G01Y1678815D01*
G02X1295898Y1678512I-302J-1D01*
G01X1292198D01*
G02X1291896Y1678815I1J303D01*
G01Y1681219D01*
G02X1291882Y1681456I2002J237D01*
G02X1291896Y1681693I2016J0D01*
G01Y1685943D01*
G02X1291882Y1686180I2002J237D01*
G02X1291896Y1686417I2016J0D01*
G01Y1688821D01*
G02X1292198Y1689124I302J1D01*
G37*
G36*
G01X1311883D02*
X1315583D01*
G02X1315886Y1688821I0J-303D01*
G01Y1678815D01*
G02X1315583Y1678512I-303J0D01*
G01X1311883D01*
G02X1311580Y1678815I0J303D01*
G01Y1681227D01*
G02X1311567Y1681456I2003J229D01*
G02X1311580Y1681685I2016J0D01*
G01Y1685951D01*
G02X1311567Y1686180I2003J229D01*
G02X1311580Y1686409I2016J0D01*
G01Y1688821D01*
G02X1311883Y1689124I303J0D01*
G37*
G36*
G01X1327631D02*
X1331331D01*
G02X1331634Y1688821I0J-303D01*
G01Y1678815D01*
G02X1331331Y1678512I-303J0D01*
G01X1327631D01*
G02X1327328Y1678815I0J303D01*
G01Y1681227D01*
G02X1327315Y1681456I2003J229D01*
G02X1327328Y1681685I2016J0D01*
G01Y1685951D01*
G02X1327315Y1686180I2003J229D01*
G02X1327328Y1686409I2016J0D01*
G01Y1688821D01*
G02X1327631Y1689124I303J0D01*
G37*
G36*
G01X1343379D02*
X1347079D01*
G02X1347382Y1688821I0J-303D01*
G01Y1678815D01*
G02X1347079Y1678512I-303J0D01*
G01X1343379D01*
G02X1343076Y1678815I0J303D01*
G01Y1681227D01*
G02X1343063Y1681456I2003J229D01*
G02X1343076Y1681685I2016J0D01*
G01Y1685951D01*
G02X1343063Y1686180I2003J229D01*
G02X1343076Y1686409I2016J0D01*
G01Y1688821D01*
G02X1343379Y1689124I303J0D01*
G37*
G36*
G01X1359127D02*
X1362827D01*
G02X1363130Y1688821I0J-303D01*
G01Y1678815D01*
G02X1362827Y1678512I-303J0D01*
G01X1359127D01*
G02X1358824Y1678815I0J303D01*
G01Y1681227D01*
G02X1358811Y1681456I2003J229D01*
G02X1358824Y1681685I2016J0D01*
G01Y1685951D01*
G02X1358811Y1686180I2003J229D01*
G02X1358824Y1686409I2016J0D01*
G01Y1688821D01*
G02X1359127Y1689124I303J0D01*
G37*
G36*
G01X1509127D02*
X1512827D01*
G02X1513130Y1688821I0J-303D01*
G01Y1678815D01*
G02X1512827Y1678512I-303J0D01*
G01X1509127D01*
G02X1508824Y1678815I0J303D01*
G01Y1681227D01*
G02X1508811Y1681456I2003J229D01*
G02X1508824Y1681685I2016J0D01*
G01Y1685951D01*
G02X1508811Y1686180I2003J229D01*
G02X1508824Y1686409I2016J0D01*
G01Y1688821D01*
G02X1509127Y1689124I303J0D01*
G37*
G36*
G01X1524875D02*
X1528575D01*
G02X1528878Y1688821I0J-303D01*
G01Y1678815D01*
G02X1528575Y1678512I-303J0D01*
G01X1524875D01*
G02X1524572Y1678815I0J303D01*
G01Y1681227D01*
G02X1524559Y1681456I2003J229D01*
G02X1524572Y1681685I2016J0D01*
G01Y1685951D01*
G02X1524559Y1686180I2003J229D01*
G02X1524572Y1686409I2016J0D01*
G01Y1688821D01*
G02X1524875Y1689124I303J0D01*
G37*
G36*
G01X1540623D02*
X1544323D01*
G02X1544626Y1688821I0J-303D01*
G01Y1678815D01*
G02X1544323Y1678512I-303J0D01*
G01X1540623D01*
G02X1540320Y1678815I0J303D01*
G01Y1681227D01*
G02X1540307Y1681456I2003J229D01*
G02X1540320Y1681685I2016J0D01*
G01Y1685951D01*
G02X1540307Y1686180I2003J229D01*
G02X1540320Y1686409I2016J0D01*
G01Y1688821D01*
G02X1540623Y1689124I303J0D01*
G37*
G36*
G01X1556371D02*
X1560071D01*
G02X1560374Y1688821I0J-303D01*
G01Y1678815D01*
G02X1560071Y1678512I-303J0D01*
G01X1556371D01*
G02X1556068Y1678815I0J303D01*
G01Y1681227D01*
G02X1556055Y1681456I2003J229D01*
G02X1556068Y1681685I2016J0D01*
G01Y1685951D01*
G02X1556055Y1686180I2003J229D01*
G02X1556068Y1686409I2016J0D01*
G01Y1688821D01*
G02X1556371Y1689124I303J0D01*
G37*
G36*
G01X1576056D02*
X1579756D01*
G02X1580058Y1688821I-1J-303D01*
G01Y1678815D01*
G02X1579756Y1678512I-302J-1D01*
G01X1576056D01*
G02X1575754Y1678815I1J303D01*
G01Y1681219D01*
G02X1575740Y1681456I2002J237D01*
G02X1575754Y1681693I2016J0D01*
G01Y1685943D01*
G02X1575740Y1686180I2002J237D01*
G02X1575754Y1686417I2016J0D01*
G01Y1688821D01*
G02X1576056Y1689124I302J1D01*
G37*
G36*
G01X1591804D02*
X1595504D01*
G02X1595806Y1688821I-1J-303D01*
G01Y1678815D01*
G02X1595504Y1678512I-302J-1D01*
G01X1591804D01*
G02X1591502Y1678815I1J303D01*
G01Y1681219D01*
G02X1591488Y1681456I2002J237D01*
G02X1591502Y1681693I2016J0D01*
G01Y1685943D01*
G02X1591488Y1686180I2002J237D01*
G02X1591502Y1686417I2016J0D01*
G01Y1688821D01*
G02X1591804Y1689124I302J1D01*
G37*
G36*
G01X1607552D02*
X1611252D01*
G02X1611554Y1688821I-1J-303D01*
G01Y1678815D01*
G02X1611252Y1678512I-302J-1D01*
G01X1607552D01*
G02X1607250Y1678815I1J303D01*
G01Y1681219D01*
G02X1607236Y1681456I2002J237D01*
G02X1607250Y1681693I2016J0D01*
G01Y1685943D01*
G02X1607236Y1686180I2002J237D01*
G02X1607250Y1686417I2016J0D01*
G01Y1688821D01*
G02X1607552Y1689124I302J1D01*
G37*
G36*
G01X1623300D02*
X1627000D01*
G02X1627302Y1688821I-1J-303D01*
G01Y1678815D01*
G02X1627000Y1678512I-302J-1D01*
G01X1623300D01*
G02X1622998Y1678815I1J303D01*
G01Y1681219D01*
G02X1622984Y1681456I2002J237D01*
G02X1622998Y1681693I2016J0D01*
G01Y1685943D01*
G02X1622984Y1686180I2002J237D01*
G02X1622998Y1686417I2016J0D01*
G01Y1688821D01*
G02X1623300Y1689124I302J1D01*
G37*
G36*
G01X229206Y1699360D02*
X232906D01*
G02X233208Y1699057I-1J-303D01*
G01Y1689051D01*
G02X232906Y1688748I-302J-1D01*
G01X229206D01*
G02X228904Y1689051I1J303D01*
G01Y1691455D01*
G02X228890Y1691692I2002J237D01*
G02X228904Y1691929I2016J0D01*
G01Y1696180D01*
G02X228890Y1696417I2002J237D01*
G02X228904Y1696654I2016J0D01*
G01Y1699057D01*
G02X229206Y1699360I302J1D01*
G37*
G36*
G01X244954D02*
X248654D01*
G02X248956Y1699057I-1J-303D01*
G01Y1689051D01*
G02X248654Y1688748I-302J-1D01*
G01X244954D01*
G02X244652Y1689051I1J303D01*
G01Y1691455D01*
G02X244638Y1691692I2002J237D01*
G02X244652Y1691929I2016J0D01*
G01Y1696180D01*
G02X244638Y1696417I2002J237D01*
G02X244652Y1696654I2016J0D01*
G01Y1699057D01*
G02X244954Y1699360I302J1D01*
G37*
G36*
G01X260702D02*
X264402D01*
G02X264704Y1699057I-1J-303D01*
G01Y1689051D01*
G02X264402Y1688748I-302J-1D01*
G01X260702D01*
G02X260400Y1689051I1J303D01*
G01Y1691455D01*
G02X260386Y1691692I2002J237D01*
G02X260400Y1691929I2016J0D01*
G01Y1696180D01*
G02X260386Y1696417I2002J237D01*
G02X260400Y1696654I2016J0D01*
G01Y1699057D01*
G02X260702Y1699360I302J1D01*
G37*
G36*
G01X276450D02*
X280150D01*
G02X280452Y1699057I-1J-303D01*
G01Y1689051D01*
G02X280150Y1688748I-302J-1D01*
G01X276450D01*
G02X276148Y1689051I1J303D01*
G01Y1691455D01*
G02X276134Y1691692I2002J237D01*
G02X276148Y1691929I2016J0D01*
G01Y1696180D01*
G02X276134Y1696417I2002J237D01*
G02X276148Y1696654I2016J0D01*
G01Y1699057D01*
G02X276450Y1699360I302J1D01*
G37*
G36*
G01X296135D02*
X299835D01*
G02X300138Y1699057I0J-303D01*
G01Y1689051D01*
G02X299835Y1688748I-303J0D01*
G01X296135D01*
G02X295832Y1689051I0J303D01*
G01Y1691463D01*
G02X295819Y1691692I2003J229D01*
G02X295832Y1691921I2016J0D01*
G01Y1696188D01*
G02X295819Y1696417I2003J229D01*
G02X295832Y1696646I2016J0D01*
G01Y1699057D01*
G02X296135Y1699360I303J0D01*
G37*
G36*
G01X311883D02*
X315583D01*
G02X315886Y1699057I0J-303D01*
G01Y1689051D01*
G02X315583Y1688748I-303J0D01*
G01X311883D01*
G02X311580Y1689051I0J303D01*
G01Y1691463D01*
G02X311567Y1691692I2003J229D01*
G02X311580Y1691921I2016J0D01*
G01Y1696188D01*
G02X311567Y1696417I2003J229D01*
G02X311580Y1696646I2016J0D01*
G01Y1699057D01*
G02X311883Y1699360I303J0D01*
G37*
G36*
G01X327631D02*
X331331D01*
G02X331634Y1699057I0J-303D01*
G01Y1689051D01*
G02X331331Y1688748I-303J0D01*
G01X327631D01*
G02X327328Y1689051I0J303D01*
G01Y1691463D01*
G02X327315Y1691692I2003J229D01*
G02X327328Y1691921I2016J0D01*
G01Y1696188D01*
G02X327315Y1696417I2003J229D01*
G02X327328Y1696646I2016J0D01*
G01Y1699057D01*
G02X327631Y1699360I303J0D01*
G37*
G36*
G01X343379D02*
X347079D01*
G02X347382Y1699057I0J-303D01*
G01Y1689051D01*
G02X347079Y1688748I-303J0D01*
G01X343379D01*
G02X343076Y1689051I0J303D01*
G01Y1691463D01*
G02X343063Y1691692I2003J229D01*
G02X343076Y1691921I2016J0D01*
G01Y1696188D01*
G02X343063Y1696417I2003J229D01*
G02X343076Y1696646I2016J0D01*
G01Y1699057D01*
G02X343379Y1699360I303J0D01*
G37*
G36*
G01X493379D02*
X497079D01*
G02X497382Y1699057I0J-303D01*
G01Y1689051D01*
G02X497079Y1688748I-303J0D01*
G01X493379D01*
G02X493076Y1689051I0J303D01*
G01Y1691463D01*
G02X493063Y1691692I2003J229D01*
G02X493076Y1691921I2016J0D01*
G01Y1696188D01*
G02X493063Y1696417I2003J229D01*
G02X493076Y1696646I2016J0D01*
G01Y1699057D01*
G02X493379Y1699360I303J0D01*
G37*
G36*
G01X509127D02*
X512827D01*
G02X513130Y1699057I0J-303D01*
G01Y1689051D01*
G02X512827Y1688748I-303J0D01*
G01X509127D01*
G02X508824Y1689051I0J303D01*
G01Y1691463D01*
G02X508811Y1691692I2003J229D01*
G02X508824Y1691921I2016J0D01*
G01Y1696188D01*
G02X508811Y1696417I2003J229D01*
G02X508824Y1696646I2016J0D01*
G01Y1699057D01*
G02X509127Y1699360I303J0D01*
G37*
G36*
G01X524875D02*
X528575D01*
G02X528878Y1699057I0J-303D01*
G01Y1689051D01*
G02X528575Y1688748I-303J0D01*
G01X524875D01*
G02X524572Y1689051I0J303D01*
G01Y1691463D01*
G02X524559Y1691692I2003J229D01*
G02X524572Y1691921I2016J0D01*
G01Y1696188D01*
G02X524559Y1696417I2003J229D01*
G02X524572Y1696646I2016J0D01*
G01Y1699057D01*
G02X524875Y1699360I303J0D01*
G37*
G36*
G01X540623D02*
X544323D01*
G02X544626Y1699057I0J-303D01*
G01Y1689051D01*
G02X544323Y1688748I-303J0D01*
G01X540623D01*
G02X540320Y1689051I0J303D01*
G01Y1691463D01*
G02X540307Y1691692I2003J229D01*
G02X540320Y1691921I2016J0D01*
G01Y1696188D01*
G02X540307Y1696417I2003J229D01*
G02X540320Y1696646I2016J0D01*
G01Y1699057D01*
G02X540623Y1699360I303J0D01*
G37*
G36*
G01X560308D02*
X564008D01*
G02X564310Y1699057I-1J-303D01*
G01Y1689051D01*
G02X564008Y1688748I-302J-1D01*
G01X560308D01*
G02X560006Y1689051I1J303D01*
G01Y1691455D01*
G02X559992Y1691692I2002J237D01*
G02X560006Y1691929I2016J0D01*
G01Y1696180D01*
G02X559992Y1696417I2002J237D01*
G02X560006Y1696654I2016J0D01*
G01Y1699057D01*
G02X560308Y1699360I302J1D01*
G37*
G36*
G01X576056D02*
X579756D01*
G02X580058Y1699057I-1J-303D01*
G01Y1689051D01*
G02X579756Y1688748I-302J-1D01*
G01X576056D01*
G02X575754Y1689051I1J303D01*
G01Y1691455D01*
G02X575740Y1691692I2002J237D01*
G02X575754Y1691929I2016J0D01*
G01Y1696180D01*
G02X575740Y1696417I2002J237D01*
G02X575754Y1696654I2016J0D01*
G01Y1699057D01*
G02X576056Y1699360I302J1D01*
G37*
G36*
G01X591804D02*
X595504D01*
G02X595806Y1699057I-1J-303D01*
G01Y1689051D01*
G02X595504Y1688748I-302J-1D01*
G01X591804D01*
G02X591502Y1689051I1J303D01*
G01Y1691455D01*
G02X591488Y1691692I2002J237D01*
G02X591502Y1691929I2016J0D01*
G01Y1696180D01*
G02X591488Y1696417I2002J237D01*
G02X591502Y1696654I2016J0D01*
G01Y1699057D01*
G02X591804Y1699360I302J1D01*
G37*
G36*
G01X607552D02*
X611252D01*
G02X611554Y1699057I-1J-303D01*
G01Y1689051D01*
G02X611252Y1688748I-302J-1D01*
G01X607552D01*
G02X607250Y1689051I1J303D01*
G01Y1691455D01*
G02X607236Y1691692I2002J237D01*
G02X607250Y1691929I2016J0D01*
G01Y1696180D01*
G02X607236Y1696417I2002J237D01*
G02X607250Y1696654I2016J0D01*
G01Y1699057D01*
G02X607552Y1699360I302J1D01*
G37*
G36*
G01X1237080D02*
X1240780D01*
G02X1241082Y1699057I-1J-303D01*
G01Y1689051D01*
G02X1240780Y1688748I-302J-1D01*
G01X1237080D01*
G02X1236778Y1689051I1J303D01*
G01Y1691455D01*
G02X1236764Y1691692I2002J237D01*
G02X1236778Y1691929I2016J0D01*
G01Y1696180D01*
G02X1236764Y1696417I2002J237D01*
G02X1236778Y1696654I2016J0D01*
G01Y1699057D01*
G02X1237080Y1699360I302J1D01*
G37*
G36*
G01X1252828D02*
X1256528D01*
G02X1256830Y1699057I-1J-303D01*
G01Y1689051D01*
G02X1256528Y1688748I-302J-1D01*
G01X1252828D01*
G02X1252526Y1689051I1J303D01*
G01Y1691455D01*
G02X1252512Y1691692I2002J237D01*
G02X1252526Y1691929I2016J0D01*
G01Y1696180D01*
G02X1252512Y1696417I2002J237D01*
G02X1252526Y1696654I2016J0D01*
G01Y1699057D01*
G02X1252828Y1699360I302J1D01*
G37*
G36*
G01X1268576D02*
X1272276D01*
G02X1272578Y1699057I-1J-303D01*
G01Y1689051D01*
G02X1272276Y1688748I-302J-1D01*
G01X1268576D01*
G02X1268274Y1689051I1J303D01*
G01Y1691455D01*
G02X1268260Y1691692I2002J237D01*
G02X1268274Y1691929I2016J0D01*
G01Y1696180D01*
G02X1268260Y1696417I2002J237D01*
G02X1268274Y1696654I2016J0D01*
G01Y1699057D01*
G02X1268576Y1699360I302J1D01*
G37*
G36*
G01X1284324D02*
X1288024D01*
G02X1288326Y1699057I-1J-303D01*
G01Y1689051D01*
G02X1288024Y1688748I-302J-1D01*
G01X1284324D01*
G02X1284022Y1689051I1J303D01*
G01Y1691455D01*
G02X1284008Y1691692I2002J237D01*
G02X1284022Y1691929I2016J0D01*
G01Y1696180D01*
G02X1284008Y1696417I2002J237D01*
G02X1284022Y1696654I2016J0D01*
G01Y1699057D01*
G02X1284324Y1699360I302J1D01*
G37*
G36*
G01X1304009D02*
X1307709D01*
G02X1308012Y1699057I0J-303D01*
G01Y1689051D01*
G02X1307709Y1688748I-303J0D01*
G01X1304009D01*
G02X1303706Y1689051I0J303D01*
G01Y1691463D01*
G02X1303693Y1691692I2003J229D01*
G02X1303706Y1691921I2016J0D01*
G01Y1696188D01*
G02X1303693Y1696417I2003J229D01*
G02X1303706Y1696646I2016J0D01*
G01Y1699057D01*
G02X1304009Y1699360I303J0D01*
G37*
G36*
G01X1319757D02*
X1323457D01*
G02X1323760Y1699057I0J-303D01*
G01Y1689051D01*
G02X1323457Y1688748I-303J0D01*
G01X1319757D01*
G02X1319454Y1689051I0J303D01*
G01Y1691463D01*
G02X1319441Y1691692I2003J229D01*
G02X1319454Y1691921I2016J0D01*
G01Y1696188D01*
G02X1319441Y1696417I2003J229D01*
G02X1319454Y1696646I2016J0D01*
G01Y1699057D01*
G02X1319757Y1699360I303J0D01*
G37*
G36*
G01X1335505D02*
X1339205D01*
G02X1339508Y1699057I0J-303D01*
G01Y1689051D01*
G02X1339205Y1688748I-303J0D01*
G01X1335505D01*
G02X1335202Y1689051I0J303D01*
G01Y1691463D01*
G02X1335189Y1691692I2003J229D01*
G02X1335202Y1691921I2016J0D01*
G01Y1696188D01*
G02X1335189Y1696417I2003J229D01*
G02X1335202Y1696646I2016J0D01*
G01Y1699057D01*
G02X1335505Y1699360I303J0D01*
G37*
G36*
G01X1351253D02*
X1354953D01*
G02X1355256Y1699057I0J-303D01*
G01Y1689051D01*
G02X1354953Y1688748I-303J0D01*
G01X1351253D01*
G02X1350950Y1689051I0J303D01*
G01Y1691463D01*
G02X1350937Y1691692I2003J229D01*
G02X1350950Y1691921I2016J0D01*
G01Y1696188D01*
G02X1350937Y1696417I2003J229D01*
G02X1350950Y1696646I2016J0D01*
G01Y1699057D01*
G02X1351253Y1699360I303J0D01*
G37*
G36*
G01X1501253D02*
X1504953D01*
G02X1505256Y1699057I0J-303D01*
G01Y1689051D01*
G02X1504953Y1688748I-303J0D01*
G01X1501253D01*
G02X1500950Y1689051I0J303D01*
G01Y1691463D01*
G02X1500937Y1691692I2003J229D01*
G02X1500950Y1691921I2016J0D01*
G01Y1696188D01*
G02X1500937Y1696417I2003J229D01*
G02X1500950Y1696646I2016J0D01*
G01Y1699057D01*
G02X1501253Y1699360I303J0D01*
G37*
G36*
G01X1517001D02*
X1520701D01*
G02X1521004Y1699057I0J-303D01*
G01Y1689051D01*
G02X1520701Y1688748I-303J0D01*
G01X1517001D01*
G02X1516698Y1689051I0J303D01*
G01Y1691463D01*
G02X1516685Y1691692I2003J229D01*
G02X1516698Y1691921I2016J0D01*
G01Y1696188D01*
G02X1516685Y1696417I2003J229D01*
G02X1516698Y1696646I2016J0D01*
G01Y1699057D01*
G02X1517001Y1699360I303J0D01*
G37*
G36*
G01X1532749D02*
X1536449D01*
G02X1536752Y1699057I0J-303D01*
G01Y1689051D01*
G02X1536449Y1688748I-303J0D01*
G01X1532749D01*
G02X1532446Y1689051I0J303D01*
G01Y1691463D01*
G02X1532433Y1691692I2003J229D01*
G02X1532446Y1691921I2016J0D01*
G01Y1696188D01*
G02X1532433Y1696417I2003J229D01*
G02X1532446Y1696646I2016J0D01*
G01Y1699057D01*
G02X1532749Y1699360I303J0D01*
G37*
G36*
G01X1548497D02*
X1552197D01*
G02X1552500Y1699057I0J-303D01*
G01Y1689051D01*
G02X1552197Y1688748I-303J0D01*
G01X1548497D01*
G02X1548194Y1689051I0J303D01*
G01Y1691463D01*
G02X1548181Y1691692I2003J229D01*
G02X1548194Y1691921I2016J0D01*
G01Y1696188D01*
G02X1548181Y1696417I2003J229D01*
G02X1548194Y1696646I2016J0D01*
G01Y1699057D01*
G02X1548497Y1699360I303J0D01*
G37*
G36*
G01X1568182D02*
X1571882D01*
G02X1572184Y1699057I-1J-303D01*
G01Y1689051D01*
G02X1571882Y1688748I-302J-1D01*
G01X1568182D01*
G02X1567880Y1689051I1J303D01*
G01Y1691455D01*
G02X1567866Y1691692I2002J237D01*
G02X1567880Y1691929I2016J0D01*
G01Y1696180D01*
G02X1567866Y1696417I2002J237D01*
G02X1567880Y1696654I2016J0D01*
G01Y1699057D01*
G02X1568182Y1699360I302J1D01*
G37*
G36*
G01X1583930D02*
X1587630D01*
G02X1587932Y1699057I-1J-303D01*
G01Y1689051D01*
G02X1587630Y1688748I-302J-1D01*
G01X1583930D01*
G02X1583628Y1689051I1J303D01*
G01Y1691455D01*
G02X1583614Y1691692I2002J237D01*
G02X1583628Y1691929I2016J0D01*
G01Y1696180D01*
G02X1583614Y1696417I2002J237D01*
G02X1583628Y1696654I2016J0D01*
G01Y1699057D01*
G02X1583930Y1699360I302J1D01*
G37*
G36*
G01X1599678D02*
X1603378D01*
G02X1603680Y1699057I-1J-303D01*
G01Y1689051D01*
G02X1603378Y1688748I-302J-1D01*
G01X1599678D01*
G02X1599376Y1689051I1J303D01*
G01Y1691455D01*
G02X1599362Y1691692I2002J237D01*
G02X1599376Y1691929I2016J0D01*
G01Y1696180D01*
G02X1599362Y1696417I2002J237D01*
G02X1599376Y1696654I2016J0D01*
G01Y1699057D01*
G02X1599678Y1699360I302J1D01*
G37*
G36*
G01X1615426D02*
X1619126D01*
G02X1619428Y1699057I-1J-303D01*
G01Y1689051D01*
G02X1619126Y1688748I-302J-1D01*
G01X1615426D01*
G02X1615124Y1689051I1J303D01*
G01Y1691455D01*
G02X1615110Y1691692I2002J237D01*
G02X1615124Y1691929I2016J0D01*
G01Y1696180D01*
G02X1615110Y1696417I2002J237D01*
G02X1615124Y1696654I2016J0D01*
G01Y1699057D01*
G02X1615426Y1699360I302J1D01*
G37*
G36*
G01X237080Y1703296D02*
X240780D01*
G02X241082Y1702994I0J-302D01*
G01Y1692988D01*
G02X240780Y1692686I-302J0D01*
G01X237080D01*
G02X236778Y1692988I0J302D01*
G01Y1695392D01*
G02X236764Y1695629I2002J237D01*
G02X236778Y1695866I2016J0D01*
G01Y1700117D01*
G02X236764Y1700354I2002J237D01*
G02X236778Y1700591I2016J0D01*
G01Y1702994D01*
G02X237080Y1703296I302J0D01*
G37*
G36*
G01X252828D02*
X256528D01*
G02X256830Y1702994I0J-302D01*
G01Y1692988D01*
G02X256528Y1692686I-302J0D01*
G01X252828D01*
G02X252526Y1692988I0J302D01*
G01Y1695392D01*
G02X252512Y1695629I2002J237D01*
G02X252526Y1695866I2016J0D01*
G01Y1700117D01*
G02X252512Y1700354I2002J237D01*
G02X252526Y1700591I2016J0D01*
G01Y1702994D01*
G02X252828Y1703296I302J0D01*
G37*
G36*
G01X268576D02*
X272276D01*
G02X272578Y1702994I0J-302D01*
G01Y1692988D01*
G02X272276Y1692686I-302J0D01*
G01X268576D01*
G02X268274Y1692988I0J302D01*
G01Y1695392D01*
G02X268260Y1695629I2002J237D01*
G02X268274Y1695866I2016J0D01*
G01Y1700117D01*
G02X268260Y1700354I2002J237D01*
G02X268274Y1700591I2016J0D01*
G01Y1702994D01*
G02X268576Y1703296I302J0D01*
G37*
G36*
G01X284324D02*
X288024D01*
G02X288326Y1702994I0J-302D01*
G01Y1692988D01*
G02X288024Y1692686I-302J0D01*
G01X284324D01*
G02X284022Y1692988I0J302D01*
G01Y1695392D01*
G02X284008Y1695629I2002J237D01*
G02X284022Y1695866I2016J0D01*
G01Y1700117D01*
G02X284008Y1700354I2002J237D01*
G02X284022Y1700591I2016J0D01*
G01Y1702994D01*
G02X284324Y1703296I302J0D01*
G37*
G36*
G01X568182D02*
X571882D01*
G02X572184Y1702994I0J-302D01*
G01Y1692988D01*
G02X571882Y1692686I-302J0D01*
G01X568182D01*
G02X567880Y1692988I0J302D01*
G01Y1695392D01*
G02X567866Y1695629I2002J237D01*
G02X567880Y1695866I2016J0D01*
G01Y1700117D01*
G02X567866Y1700354I2002J237D01*
G02X567880Y1700591I2016J0D01*
G01Y1702994D01*
G02X568182Y1703296I302J0D01*
G37*
G36*
G01X583930D02*
X587630D01*
G02X587932Y1702994I0J-302D01*
G01Y1692988D01*
G02X587630Y1692686I-302J0D01*
G01X583930D01*
G02X583628Y1692988I0J302D01*
G01Y1695392D01*
G02X583614Y1695629I2002J237D01*
G02X583628Y1695866I2016J0D01*
G01Y1700117D01*
G02X583614Y1700354I2002J237D01*
G02X583628Y1700591I2016J0D01*
G01Y1702994D01*
G02X583930Y1703296I302J0D01*
G37*
G36*
G01X599678D02*
X603378D01*
G02X603680Y1702994I0J-302D01*
G01Y1692988D01*
G02X603378Y1692686I-302J0D01*
G01X599678D01*
G02X599376Y1692988I0J302D01*
G01Y1695392D01*
G02X599362Y1695629I2002J237D01*
G02X599376Y1695866I2016J0D01*
G01Y1700117D01*
G02X599362Y1700354I2002J237D01*
G02X599376Y1700591I2016J0D01*
G01Y1702994D01*
G02X599678Y1703296I302J0D01*
G37*
G36*
G01X615426D02*
X619126D01*
G02X619428Y1702994I0J-302D01*
G01Y1692988D01*
G02X619126Y1692686I-302J0D01*
G01X615426D01*
G02X615124Y1692988I0J302D01*
G01Y1695392D01*
G02X615110Y1695629I2002J237D01*
G02X615124Y1695866I2016J0D01*
G01Y1700117D01*
G02X615110Y1700354I2002J237D01*
G02X615124Y1700591I2016J0D01*
G01Y1702994D01*
G02X615426Y1703296I302J0D01*
G37*
G36*
G01X1244954D02*
X1248654D01*
G02X1248956Y1702994I0J-302D01*
G01Y1692988D01*
G02X1248654Y1692686I-302J0D01*
G01X1244954D01*
G02X1244652Y1692988I0J302D01*
G01Y1695392D01*
G02X1244638Y1695629I2002J237D01*
G02X1244652Y1695866I2016J0D01*
G01Y1700117D01*
G02X1244638Y1700354I2002J237D01*
G02X1244652Y1700591I2016J0D01*
G01Y1702994D01*
G02X1244954Y1703296I302J0D01*
G37*
G36*
G01X1260702D02*
X1264402D01*
G02X1264704Y1702994I0J-302D01*
G01Y1692988D01*
G02X1264402Y1692686I-302J0D01*
G01X1260702D01*
G02X1260400Y1692988I0J302D01*
G01Y1695392D01*
G02X1260386Y1695629I2002J237D01*
G02X1260400Y1695866I2016J0D01*
G01Y1700117D01*
G02X1260386Y1700354I2002J237D01*
G02X1260400Y1700591I2016J0D01*
G01Y1702994D01*
G02X1260702Y1703296I302J0D01*
G37*
G36*
G01X1276450D02*
X1280150D01*
G02X1280452Y1702994I0J-302D01*
G01Y1692988D01*
G02X1280150Y1692686I-302J0D01*
G01X1276450D01*
G02X1276148Y1692988I0J302D01*
G01Y1695392D01*
G02X1276134Y1695629I2002J237D01*
G02X1276148Y1695866I2016J0D01*
G01Y1700117D01*
G02X1276134Y1700354I2002J237D01*
G02X1276148Y1700591I2016J0D01*
G01Y1702994D01*
G02X1276450Y1703296I302J0D01*
G37*
G36*
G01X1292198D02*
X1295898D01*
G02X1296200Y1702994I0J-302D01*
G01Y1692988D01*
G02X1295898Y1692686I-302J0D01*
G01X1292198D01*
G02X1291896Y1692988I0J302D01*
G01Y1695392D01*
G02X1291882Y1695629I2002J237D01*
G02X1291896Y1695866I2016J0D01*
G01Y1700117D01*
G02X1291882Y1700354I2002J237D01*
G02X1291896Y1700591I2016J0D01*
G01Y1702994D01*
G02X1292198Y1703296I302J0D01*
G37*
G36*
G01X1576056D02*
X1579756D01*
G02X1580058Y1702994I0J-302D01*
G01Y1692988D01*
G02X1579756Y1692686I-302J0D01*
G01X1576056D01*
G02X1575754Y1692988I0J302D01*
G01Y1695392D01*
G02X1575740Y1695629I2002J237D01*
G02X1575754Y1695866I2016J0D01*
G01Y1700117D01*
G02X1575740Y1700354I2002J237D01*
G02X1575754Y1700591I2016J0D01*
G01Y1702994D01*
G02X1576056Y1703296I302J0D01*
G37*
G36*
G01X1591804D02*
X1595504D01*
G02X1595806Y1702994I0J-302D01*
G01Y1692988D01*
G02X1595504Y1692686I-302J0D01*
G01X1591804D01*
G02X1591502Y1692988I0J302D01*
G01Y1695392D01*
G02X1591488Y1695629I2002J237D01*
G02X1591502Y1695866I2016J0D01*
G01Y1700117D01*
G02X1591488Y1700354I2002J237D01*
G02X1591502Y1700591I2016J0D01*
G01Y1702994D01*
G02X1591804Y1703296I302J0D01*
G37*
G36*
G01X1607552D02*
X1611252D01*
G02X1611554Y1702994I0J-302D01*
G01Y1692988D01*
G02X1611252Y1692686I-302J0D01*
G01X1607552D01*
G02X1607250Y1692988I0J302D01*
G01Y1695392D01*
G02X1607236Y1695629I2002J237D01*
G02X1607250Y1695866I2016J0D01*
G01Y1700117D01*
G02X1607236Y1700354I2002J237D01*
G02X1607250Y1700591I2016J0D01*
G01Y1702994D01*
G02X1607552Y1703296I302J0D01*
G37*
G36*
G01X1623300D02*
X1627000D01*
G02X1627302Y1702994I0J-302D01*
G01Y1692988D01*
G02X1627000Y1692686I-302J0D01*
G01X1623300D01*
G02X1622998Y1692988I0J302D01*
G01Y1695392D01*
G02X1622984Y1695629I2002J237D01*
G02X1622998Y1695866I2016J0D01*
G01Y1700117D01*
G02X1622984Y1700354I2002J237D01*
G02X1622998Y1700591I2016J0D01*
G01Y1702994D01*
G02X1623300Y1703296I302J0D01*
G37*
G36*
G01X304009D02*
X307709D01*
G02X308012Y1702994I1J-302D01*
G01Y1692988D01*
G02X307709Y1692686I-303J1D01*
G01X304009D01*
G02X303706Y1692988I-1J302D01*
G01Y1695400D01*
G02X303693Y1695629I2003J229D01*
G02X303706Y1695858I2016J0D01*
G01Y1700125D01*
G02X303693Y1700354I2003J229D01*
G02X303706Y1700583I2016J0D01*
G01Y1702994D01*
G02X304009Y1703296I303J-1D01*
G37*
G36*
G01X319757D02*
X323457D01*
G02X323760Y1702994I1J-302D01*
G01Y1692988D01*
G02X323457Y1692686I-303J1D01*
G01X319757D01*
G02X319454Y1692988I-1J302D01*
G01Y1695400D01*
G02X319441Y1695629I2003J229D01*
G02X319454Y1695858I2016J0D01*
G01Y1700125D01*
G02X319441Y1700354I2003J229D01*
G02X319454Y1700583I2016J0D01*
G01Y1702994D01*
G02X319757Y1703296I303J-1D01*
G37*
G36*
G01X335505D02*
X339205D01*
G02X339508Y1702994I1J-302D01*
G01Y1692988D01*
G02X339205Y1692686I-303J1D01*
G01X335505D01*
G02X335202Y1692988I-1J302D01*
G01Y1695400D01*
G02X335189Y1695629I2003J229D01*
G02X335202Y1695858I2016J0D01*
G01Y1700125D01*
G02X335189Y1700354I2003J229D01*
G02X335202Y1700583I2016J0D01*
G01Y1702994D01*
G02X335505Y1703296I303J-1D01*
G37*
G36*
G01X351253D02*
X354953D01*
G02X355256Y1702994I1J-302D01*
G01Y1692988D01*
G02X354953Y1692686I-303J1D01*
G01X351253D01*
G02X350950Y1692988I-1J302D01*
G01Y1695400D01*
G02X350937Y1695629I2003J229D01*
G02X350950Y1695858I2016J0D01*
G01Y1700125D01*
G02X350937Y1700354I2003J229D01*
G02X350950Y1700583I2016J0D01*
G01Y1702994D01*
G02X351253Y1703296I303J-1D01*
G37*
G36*
G01X501253D02*
X504953D01*
G02X505256Y1702994I1J-302D01*
G01Y1692988D01*
G02X504953Y1692686I-303J1D01*
G01X501253D01*
G02X500950Y1692988I-1J302D01*
G01Y1695400D01*
G02X500937Y1695629I2003J229D01*
G02X500950Y1695858I2016J0D01*
G01Y1700125D01*
G02X500937Y1700354I2003J229D01*
G02X500950Y1700583I2016J0D01*
G01Y1702994D01*
G02X501253Y1703296I303J-1D01*
G37*
G36*
G01X517001D02*
X520701D01*
G02X521004Y1702994I1J-302D01*
G01Y1692988D01*
G02X520701Y1692686I-303J1D01*
G01X517001D01*
G02X516698Y1692988I-1J302D01*
G01Y1695400D01*
G02X516685Y1695629I2003J229D01*
G02X516698Y1695858I2016J0D01*
G01Y1700125D01*
G02X516685Y1700354I2003J229D01*
G02X516698Y1700583I2016J0D01*
G01Y1702994D01*
G02X517001Y1703296I303J-1D01*
G37*
G36*
G01X532749D02*
X536449D01*
G02X536752Y1702994I1J-302D01*
G01Y1692988D01*
G02X536449Y1692686I-303J1D01*
G01X532749D01*
G02X532446Y1692988I-1J302D01*
G01Y1695400D01*
G02X532433Y1695629I2003J229D01*
G02X532446Y1695858I2016J0D01*
G01Y1700125D01*
G02X532433Y1700354I2003J229D01*
G02X532446Y1700583I2016J0D01*
G01Y1702994D01*
G02X532749Y1703296I303J-1D01*
G37*
G36*
G01X548497D02*
X552197D01*
G02X552500Y1702994I1J-302D01*
G01Y1692988D01*
G02X552197Y1692686I-303J1D01*
G01X548497D01*
G02X548194Y1692988I-1J302D01*
G01Y1695400D01*
G02X548181Y1695629I2003J229D01*
G02X548194Y1695858I2016J0D01*
G01Y1700125D01*
G02X548181Y1700354I2003J229D01*
G02X548194Y1700583I2016J0D01*
G01Y1702994D01*
G02X548497Y1703296I303J-1D01*
G37*
G36*
G01X1311883D02*
X1315583D01*
G02X1315886Y1702994I1J-302D01*
G01Y1692988D01*
G02X1315583Y1692686I-303J1D01*
G01X1311883D01*
G02X1311580Y1692988I-1J302D01*
G01Y1695400D01*
G02X1311567Y1695629I2003J229D01*
G02X1311580Y1695858I2016J0D01*
G01Y1700125D01*
G02X1311567Y1700354I2003J229D01*
G02X1311580Y1700583I2016J0D01*
G01Y1702994D01*
G02X1311883Y1703296I303J-1D01*
G37*
G36*
G01X1327631D02*
X1331331D01*
G02X1331634Y1702994I1J-302D01*
G01Y1692988D01*
G02X1331331Y1692686I-303J1D01*
G01X1327631D01*
G02X1327328Y1692988I-1J302D01*
G01Y1695400D01*
G02X1327315Y1695629I2003J229D01*
G02X1327328Y1695858I2016J0D01*
G01Y1700125D01*
G02X1327315Y1700354I2003J229D01*
G02X1327328Y1700583I2016J0D01*
G01Y1702994D01*
G02X1327631Y1703296I303J-1D01*
G37*
G36*
G01X1343379D02*
X1347079D01*
G02X1347382Y1702994I1J-302D01*
G01Y1692988D01*
G02X1347079Y1692686I-303J1D01*
G01X1343379D01*
G02X1343076Y1692988I-1J302D01*
G01Y1695400D01*
G02X1343063Y1695629I2003J229D01*
G02X1343076Y1695858I2016J0D01*
G01Y1700125D01*
G02X1343063Y1700354I2003J229D01*
G02X1343076Y1700583I2016J0D01*
G01Y1702994D01*
G02X1343379Y1703296I303J-1D01*
G37*
G36*
G01X1359127D02*
X1362827D01*
G02X1363130Y1702994I1J-302D01*
G01Y1692988D01*
G02X1362827Y1692686I-303J1D01*
G01X1359127D01*
G02X1358824Y1692988I-1J302D01*
G01Y1695400D01*
G02X1358811Y1695629I2003J229D01*
G02X1358824Y1695858I2016J0D01*
G01Y1700125D01*
G02X1358811Y1700354I2003J229D01*
G02X1358824Y1700583I2016J0D01*
G01Y1702994D01*
G02X1359127Y1703296I303J-1D01*
G37*
G36*
G01X1509127D02*
X1512827D01*
G02X1513130Y1702994I1J-302D01*
G01Y1692988D01*
G02X1512827Y1692686I-303J1D01*
G01X1509127D01*
G02X1508824Y1692988I-1J302D01*
G01Y1695400D01*
G02X1508811Y1695629I2003J229D01*
G02X1508824Y1695858I2016J0D01*
G01Y1700125D01*
G02X1508811Y1700354I2003J229D01*
G02X1508824Y1700583I2016J0D01*
G01Y1702994D01*
G02X1509127Y1703296I303J-1D01*
G37*
G36*
G01X1524875D02*
X1528575D01*
G02X1528878Y1702994I1J-302D01*
G01Y1692988D01*
G02X1528575Y1692686I-303J1D01*
G01X1524875D01*
G02X1524572Y1692988I-1J302D01*
G01Y1695400D01*
G02X1524559Y1695629I2003J229D01*
G02X1524572Y1695858I2016J0D01*
G01Y1700125D01*
G02X1524559Y1700354I2003J229D01*
G02X1524572Y1700583I2016J0D01*
G01Y1702994D01*
G02X1524875Y1703296I303J-1D01*
G37*
G36*
G01X1540623D02*
X1544323D01*
G02X1544626Y1702994I1J-302D01*
G01Y1692988D01*
G02X1544323Y1692686I-303J1D01*
G01X1540623D01*
G02X1540320Y1692988I-1J302D01*
G01Y1695400D01*
G02X1540307Y1695629I2003J229D01*
G02X1540320Y1695858I2016J0D01*
G01Y1700125D01*
G02X1540307Y1700354I2003J229D01*
G02X1540320Y1700583I2016J0D01*
G01Y1702994D01*
G02X1540623Y1703296I303J-1D01*
G37*
G36*
G01X1556371D02*
X1560071D01*
G02X1560374Y1702994I1J-302D01*
G01Y1692988D01*
G02X1560071Y1692686I-303J1D01*
G01X1556371D01*
G02X1556068Y1692988I-1J302D01*
G01Y1695400D01*
G02X1556055Y1695629I2003J229D01*
G02X1556068Y1695858I2016J0D01*
G01Y1700125D01*
G02X1556055Y1700354I2003J229D01*
G02X1556068Y1700583I2016J0D01*
G01Y1702994D01*
G02X1556371Y1703296I303J-1D01*
G37*
G36*
G01X229206Y1713532D02*
X232906D01*
G02X233208Y1713230I0J-302D01*
G01Y1703224D01*
G02X232906Y1702922I-302J0D01*
G01X229206D01*
G02X228904Y1703224I0J302D01*
G01Y1705629D01*
G02X228890Y1705866I2002J237D01*
G02X228904Y1706103I2016J0D01*
G01Y1710353D01*
G02X228890Y1710590I2002J237D01*
G02X228904Y1710827I2016J0D01*
G01Y1713230D01*
G02X229206Y1713532I302J0D01*
G37*
G36*
G01X244954D02*
X248654D01*
G02X248956Y1713230I0J-302D01*
G01Y1703224D01*
G02X248654Y1702922I-302J0D01*
G01X244954D01*
G02X244652Y1703224I0J302D01*
G01Y1705629D01*
G02X244638Y1705866I2002J237D01*
G02X244652Y1706103I2016J0D01*
G01Y1710353D01*
G02X244638Y1710590I2002J237D01*
G02X244652Y1710827I2016J0D01*
G01Y1713230D01*
G02X244954Y1713532I302J0D01*
G37*
G36*
G01X260702D02*
X264402D01*
G02X264704Y1713230I0J-302D01*
G01Y1703224D01*
G02X264402Y1702922I-302J0D01*
G01X260702D01*
G02X260400Y1703224I0J302D01*
G01Y1705629D01*
G02X260386Y1705866I2002J237D01*
G02X260400Y1706103I2016J0D01*
G01Y1710353D01*
G02X260386Y1710590I2002J237D01*
G02X260400Y1710827I2016J0D01*
G01Y1713230D01*
G02X260702Y1713532I302J0D01*
G37*
G36*
G01X276450D02*
X280150D01*
G02X280452Y1713230I0J-302D01*
G01Y1703224D01*
G02X280150Y1702922I-302J0D01*
G01X276450D01*
G02X276148Y1703224I0J302D01*
G01Y1705629D01*
G02X276134Y1705866I2002J237D01*
G02X276148Y1706103I2016J0D01*
G01Y1710353D01*
G02X276134Y1710590I2002J237D01*
G02X276148Y1710827I2016J0D01*
G01Y1713230D01*
G02X276450Y1713532I302J0D01*
G37*
G36*
G01X560308D02*
X564008D01*
G02X564310Y1713230I0J-302D01*
G01Y1703224D01*
G02X564008Y1702922I-302J0D01*
G01X560308D01*
G02X560006Y1703224I0J302D01*
G01Y1705629D01*
G02X559992Y1705866I2002J237D01*
G02X560006Y1706103I2016J0D01*
G01Y1710353D01*
G02X559992Y1710590I2002J237D01*
G02X560006Y1710827I2016J0D01*
G01Y1713230D01*
G02X560308Y1713532I302J0D01*
G37*
G36*
G01X576056D02*
X579756D01*
G02X580058Y1713230I0J-302D01*
G01Y1703224D01*
G02X579756Y1702922I-302J0D01*
G01X576056D01*
G02X575754Y1703224I0J302D01*
G01Y1705629D01*
G02X575740Y1705866I2002J237D01*
G02X575754Y1706103I2016J0D01*
G01Y1710353D01*
G02X575740Y1710590I2002J237D01*
G02X575754Y1710827I2016J0D01*
G01Y1713230D01*
G02X576056Y1713532I302J0D01*
G37*
G36*
G01X591804D02*
X595504D01*
G02X595806Y1713230I0J-302D01*
G01Y1703224D01*
G02X595504Y1702922I-302J0D01*
G01X591804D01*
G02X591502Y1703224I0J302D01*
G01Y1705629D01*
G02X591488Y1705866I2002J237D01*
G02X591502Y1706103I2016J0D01*
G01Y1710353D01*
G02X591488Y1710590I2002J237D01*
G02X591502Y1710827I2016J0D01*
G01Y1713230D01*
G02X591804Y1713532I302J0D01*
G37*
G36*
G01X607552D02*
X611252D01*
G02X611554Y1713230I0J-302D01*
G01Y1703224D01*
G02X611252Y1702922I-302J0D01*
G01X607552D01*
G02X607250Y1703224I0J302D01*
G01Y1705629D01*
G02X607236Y1705866I2002J237D01*
G02X607250Y1706103I2016J0D01*
G01Y1710353D01*
G02X607236Y1710590I2002J237D01*
G02X607250Y1710827I2016J0D01*
G01Y1713230D01*
G02X607552Y1713532I302J0D01*
G37*
G36*
G01X1237080D02*
X1240780D01*
G02X1241082Y1713230I0J-302D01*
G01Y1703224D01*
G02X1240780Y1702922I-302J0D01*
G01X1237080D01*
G02X1236778Y1703224I0J302D01*
G01Y1705629D01*
G02X1236764Y1705866I2002J237D01*
G02X1236778Y1706103I2016J0D01*
G01Y1710353D01*
G02X1236764Y1710590I2002J237D01*
G02X1236778Y1710827I2016J0D01*
G01Y1713230D01*
G02X1237080Y1713532I302J0D01*
G37*
G36*
G01X1252828D02*
X1256528D01*
G02X1256830Y1713230I0J-302D01*
G01Y1703224D01*
G02X1256528Y1702922I-302J0D01*
G01X1252828D01*
G02X1252526Y1703224I0J302D01*
G01Y1705629D01*
G02X1252512Y1705866I2002J237D01*
G02X1252526Y1706103I2016J0D01*
G01Y1710353D01*
G02X1252512Y1710590I2002J237D01*
G02X1252526Y1710827I2016J0D01*
G01Y1713230D01*
G02X1252828Y1713532I302J0D01*
G37*
G36*
G01X1268576D02*
X1272276D01*
G02X1272578Y1713230I0J-302D01*
G01Y1703224D01*
G02X1272276Y1702922I-302J0D01*
G01X1268576D01*
G02X1268274Y1703224I0J302D01*
G01Y1705629D01*
G02X1268260Y1705866I2002J237D01*
G02X1268274Y1706103I2016J0D01*
G01Y1710353D01*
G02X1268260Y1710590I2002J237D01*
G02X1268274Y1710827I2016J0D01*
G01Y1713230D01*
G02X1268576Y1713532I302J0D01*
G37*
G36*
G01X1284324D02*
X1288024D01*
G02X1288326Y1713230I0J-302D01*
G01Y1703224D01*
G02X1288024Y1702922I-302J0D01*
G01X1284324D01*
G02X1284022Y1703224I0J302D01*
G01Y1705629D01*
G02X1284008Y1705866I2002J237D01*
G02X1284022Y1706103I2016J0D01*
G01Y1710353D01*
G02X1284008Y1710590I2002J237D01*
G02X1284022Y1710827I2016J0D01*
G01Y1713230D01*
G02X1284324Y1713532I302J0D01*
G37*
G36*
G01X1568182D02*
X1571882D01*
G02X1572184Y1713230I0J-302D01*
G01Y1703224D01*
G02X1571882Y1702922I-302J0D01*
G01X1568182D01*
G02X1567880Y1703224I0J302D01*
G01Y1705629D01*
G02X1567866Y1705866I2002J237D01*
G02X1567880Y1706103I2016J0D01*
G01Y1710353D01*
G02X1567866Y1710590I2002J237D01*
G02X1567880Y1710827I2016J0D01*
G01Y1713230D01*
G02X1568182Y1713532I302J0D01*
G37*
G36*
G01X1583930D02*
X1587630D01*
G02X1587932Y1713230I0J-302D01*
G01Y1703224D01*
G02X1587630Y1702922I-302J0D01*
G01X1583930D01*
G02X1583628Y1703224I0J302D01*
G01Y1705629D01*
G02X1583614Y1705866I2002J237D01*
G02X1583628Y1706103I2016J0D01*
G01Y1710353D01*
G02X1583614Y1710590I2002J237D01*
G02X1583628Y1710827I2016J0D01*
G01Y1713230D01*
G02X1583930Y1713532I302J0D01*
G37*
G36*
G01X1599678D02*
X1603378D01*
G02X1603680Y1713230I0J-302D01*
G01Y1703224D01*
G02X1603378Y1702922I-302J0D01*
G01X1599678D01*
G02X1599376Y1703224I0J302D01*
G01Y1705629D01*
G02X1599362Y1705866I2002J237D01*
G02X1599376Y1706103I2016J0D01*
G01Y1710353D01*
G02X1599362Y1710590I2002J237D01*
G02X1599376Y1710827I2016J0D01*
G01Y1713230D01*
G02X1599678Y1713532I302J0D01*
G37*
G36*
G01X1615426D02*
X1619126D01*
G02X1619428Y1713230I0J-302D01*
G01Y1703224D01*
G02X1619126Y1702922I-302J0D01*
G01X1615426D01*
G02X1615124Y1703224I0J302D01*
G01Y1705629D01*
G02X1615110Y1705866I2002J237D01*
G02X1615124Y1706103I2016J0D01*
G01Y1710353D01*
G02X1615110Y1710590I2002J237D01*
G02X1615124Y1710827I2016J0D01*
G01Y1713230D01*
G02X1615426Y1713532I302J0D01*
G37*
G36*
G01X296135D02*
X299835D01*
G02X300138Y1713230I1J-302D01*
G01Y1703224D01*
G02X299835Y1702922I-303J1D01*
G01X296135D01*
G02X295832Y1703224I-1J302D01*
G01Y1705637D01*
G02X295819Y1705866I2003J229D01*
G02X295832Y1706095I2016J0D01*
G01Y1710361D01*
G02X295819Y1710590I2003J229D01*
G02X295832Y1710819I2016J0D01*
G01Y1713230D01*
G02X296135Y1713532I303J-1D01*
G37*
G36*
G01X311883D02*
X315583D01*
G02X315886Y1713230I1J-302D01*
G01Y1703224D01*
G02X315583Y1702922I-303J1D01*
G01X311883D01*
G02X311580Y1703224I-1J302D01*
G01Y1705637D01*
G02X311567Y1705866I2003J229D01*
G02X311580Y1706095I2016J0D01*
G01Y1710361D01*
G02X311567Y1710590I2003J229D01*
G02X311580Y1710819I2016J0D01*
G01Y1713230D01*
G02X311883Y1713532I303J-1D01*
G37*
G36*
G01X327631D02*
X331331D01*
G02X331634Y1713230I1J-302D01*
G01Y1703224D01*
G02X331331Y1702922I-303J1D01*
G01X327631D01*
G02X327328Y1703224I-1J302D01*
G01Y1705637D01*
G02X327315Y1705866I2003J229D01*
G02X327328Y1706095I2016J0D01*
G01Y1710361D01*
G02X327315Y1710590I2003J229D01*
G02X327328Y1710819I2016J0D01*
G01Y1713230D01*
G02X327631Y1713532I303J-1D01*
G37*
G36*
G01X343379D02*
X347079D01*
G02X347382Y1713230I1J-302D01*
G01Y1703224D01*
G02X347079Y1702922I-303J1D01*
G01X343379D01*
G02X343076Y1703224I-1J302D01*
G01Y1705637D01*
G02X343063Y1705866I2003J229D01*
G02X343076Y1706095I2016J0D01*
G01Y1710361D01*
G02X343063Y1710590I2003J229D01*
G02X343076Y1710819I2016J0D01*
G01Y1713230D01*
G02X343379Y1713532I303J-1D01*
G37*
G36*
G01X493379D02*
X497079D01*
G02X497382Y1713230I1J-302D01*
G01Y1703224D01*
G02X497079Y1702922I-303J1D01*
G01X493379D01*
G02X493076Y1703224I-1J302D01*
G01Y1705637D01*
G02X493063Y1705866I2003J229D01*
G02X493076Y1706095I2016J0D01*
G01Y1710361D01*
G02X493063Y1710590I2003J229D01*
G02X493076Y1710819I2016J0D01*
G01Y1713230D01*
G02X493379Y1713532I303J-1D01*
G37*
G36*
G01X509127D02*
X512827D01*
G02X513130Y1713230I1J-302D01*
G01Y1703224D01*
G02X512827Y1702922I-303J1D01*
G01X509127D01*
G02X508824Y1703224I-1J302D01*
G01Y1705637D01*
G02X508811Y1705866I2003J229D01*
G02X508824Y1706095I2016J0D01*
G01Y1710361D01*
G02X508811Y1710590I2003J229D01*
G02X508824Y1710819I2016J0D01*
G01Y1713230D01*
G02X509127Y1713532I303J-1D01*
G37*
G36*
G01X524875D02*
X528575D01*
G02X528878Y1713230I1J-302D01*
G01Y1703224D01*
G02X528575Y1702922I-303J1D01*
G01X524875D01*
G02X524572Y1703224I-1J302D01*
G01Y1705637D01*
G02X524559Y1705866I2003J229D01*
G02X524572Y1706095I2016J0D01*
G01Y1710361D01*
G02X524559Y1710590I2003J229D01*
G02X524572Y1710819I2016J0D01*
G01Y1713230D01*
G02X524875Y1713532I303J-1D01*
G37*
G36*
G01X540623D02*
X544323D01*
G02X544626Y1713230I1J-302D01*
G01Y1703224D01*
G02X544323Y1702922I-303J1D01*
G01X540623D01*
G02X540320Y1703224I-1J302D01*
G01Y1705637D01*
G02X540307Y1705866I2003J229D01*
G02X540320Y1706095I2016J0D01*
G01Y1710361D01*
G02X540307Y1710590I2003J229D01*
G02X540320Y1710819I2016J0D01*
G01Y1713230D01*
G02X540623Y1713532I303J-1D01*
G37*
G36*
G01X1304009D02*
X1307709D01*
G02X1308012Y1713230I1J-302D01*
G01Y1703224D01*
G02X1307709Y1702922I-303J1D01*
G01X1304009D01*
G02X1303706Y1703224I-1J302D01*
G01Y1705637D01*
G02X1303693Y1705866I2003J229D01*
G02X1303706Y1706095I2016J0D01*
G01Y1710361D01*
G02X1303693Y1710590I2003J229D01*
G02X1303706Y1710819I2016J0D01*
G01Y1713230D01*
G02X1304009Y1713532I303J-1D01*
G37*
G36*
G01X1319757D02*
X1323457D01*
G02X1323760Y1713230I1J-302D01*
G01Y1703224D01*
G02X1323457Y1702922I-303J1D01*
G01X1319757D01*
G02X1319454Y1703224I-1J302D01*
G01Y1705637D01*
G02X1319441Y1705866I2003J229D01*
G02X1319454Y1706095I2016J0D01*
G01Y1710361D01*
G02X1319441Y1710590I2003J229D01*
G02X1319454Y1710819I2016J0D01*
G01Y1713230D01*
G02X1319757Y1713532I303J-1D01*
G37*
G36*
G01X1335505D02*
X1339205D01*
G02X1339508Y1713230I1J-302D01*
G01Y1703224D01*
G02X1339205Y1702922I-303J1D01*
G01X1335505D01*
G02X1335202Y1703224I-1J302D01*
G01Y1705637D01*
G02X1335189Y1705866I2003J229D01*
G02X1335202Y1706095I2016J0D01*
G01Y1710361D01*
G02X1335189Y1710590I2003J229D01*
G02X1335202Y1710819I2016J0D01*
G01Y1713230D01*
G02X1335505Y1713532I303J-1D01*
G37*
G36*
G01X1351253D02*
X1354953D01*
G02X1355256Y1713230I1J-302D01*
G01Y1703224D01*
G02X1354953Y1702922I-303J1D01*
G01X1351253D01*
G02X1350950Y1703224I-1J302D01*
G01Y1705637D01*
G02X1350937Y1705866I2003J229D01*
G02X1350950Y1706095I2016J0D01*
G01Y1710361D01*
G02X1350937Y1710590I2003J229D01*
G02X1350950Y1710819I2016J0D01*
G01Y1713230D01*
G02X1351253Y1713532I303J-1D01*
G37*
G36*
G01X1501253D02*
X1504953D01*
G02X1505256Y1713230I1J-302D01*
G01Y1703224D01*
G02X1504953Y1702922I-303J1D01*
G01X1501253D01*
G02X1500950Y1703224I-1J302D01*
G01Y1705637D01*
G02X1500937Y1705866I2003J229D01*
G02X1500950Y1706095I2016J0D01*
G01Y1710361D01*
G02X1500937Y1710590I2003J229D01*
G02X1500950Y1710819I2016J0D01*
G01Y1713230D01*
G02X1501253Y1713532I303J-1D01*
G37*
G36*
G01X1517001D02*
X1520701D01*
G02X1521004Y1713230I1J-302D01*
G01Y1703224D01*
G02X1520701Y1702922I-303J1D01*
G01X1517001D01*
G02X1516698Y1703224I-1J302D01*
G01Y1705637D01*
G02X1516685Y1705866I2003J229D01*
G02X1516698Y1706095I2016J0D01*
G01Y1710361D01*
G02X1516685Y1710590I2003J229D01*
G02X1516698Y1710819I2016J0D01*
G01Y1713230D01*
G02X1517001Y1713532I303J-1D01*
G37*
G36*
G01X1532749D02*
X1536449D01*
G02X1536752Y1713230I1J-302D01*
G01Y1703224D01*
G02X1536449Y1702922I-303J1D01*
G01X1532749D01*
G02X1532446Y1703224I-1J302D01*
G01Y1705637D01*
G02X1532433Y1705866I2003J229D01*
G02X1532446Y1706095I2016J0D01*
G01Y1710361D01*
G02X1532433Y1710590I2003J229D01*
G02X1532446Y1710819I2016J0D01*
G01Y1713230D01*
G02X1532749Y1713532I303J-1D01*
G37*
G36*
G01X1548497D02*
X1552197D01*
G02X1552500Y1713230I1J-302D01*
G01Y1703224D01*
G02X1552197Y1702922I-303J1D01*
G01X1548497D01*
G02X1548194Y1703224I-1J302D01*
G01Y1705637D01*
G02X1548181Y1705866I2003J229D01*
G02X1548194Y1706095I2016J0D01*
G01Y1710361D01*
G02X1548181Y1710590I2003J229D01*
G02X1548194Y1710819I2016J0D01*
G01Y1713230D01*
G02X1548497Y1713532I303J-1D01*
G37*
G36*
G01X237080Y1717470D02*
X240780D01*
G02X241082Y1717167I-1J-303D01*
G01Y1707161D01*
G02X240780Y1706858I-302J-1D01*
G01X237080D01*
G02X236778Y1707161I1J303D01*
G01Y1709566D01*
G02X236764Y1709803I2002J237D01*
G02X236778Y1710040I2016J0D01*
G01Y1714290D01*
G02X236764Y1714527I2002J237D01*
G02X236778Y1714764I2016J0D01*
G01Y1717167D01*
G02X237080Y1717470I302J1D01*
G37*
G36*
G01X252828D02*
X256528D01*
G02X256830Y1717167I-1J-303D01*
G01Y1707161D01*
G02X256528Y1706858I-302J-1D01*
G01X252828D01*
G02X252526Y1707161I1J303D01*
G01Y1709566D01*
G02X252512Y1709803I2002J237D01*
G02X252526Y1710040I2016J0D01*
G01Y1714290D01*
G02X252512Y1714527I2002J237D01*
G02X252526Y1714764I2016J0D01*
G01Y1717167D01*
G02X252828Y1717470I302J1D01*
G37*
G36*
G01X268576D02*
X272276D01*
G02X272578Y1717167I-1J-303D01*
G01Y1707161D01*
G02X272276Y1706858I-302J-1D01*
G01X268576D01*
G02X268274Y1707161I1J303D01*
G01Y1709566D01*
G02X268260Y1709803I2002J237D01*
G02X268274Y1710040I2016J0D01*
G01Y1714290D01*
G02X268260Y1714527I2002J237D01*
G02X268274Y1714764I2016J0D01*
G01Y1717167D01*
G02X268576Y1717470I302J1D01*
G37*
G36*
G01X284324D02*
X288024D01*
G02X288326Y1717167I-1J-303D01*
G01Y1707161D01*
G02X288024Y1706858I-302J-1D01*
G01X284324D01*
G02X284022Y1707161I1J303D01*
G01Y1709566D01*
G02X284008Y1709803I2002J237D01*
G02X284022Y1710040I2016J0D01*
G01Y1714290D01*
G02X284008Y1714527I2002J237D01*
G02X284022Y1714764I2016J0D01*
G01Y1717167D01*
G02X284324Y1717470I302J1D01*
G37*
G36*
G01X304009D02*
X307709D01*
G02X308012Y1717167I0J-303D01*
G01Y1707161D01*
G02X307709Y1706858I-303J0D01*
G01X304009D01*
G02X303706Y1707161I0J303D01*
G01Y1709574D01*
G02X303693Y1709803I2003J229D01*
G02X303706Y1710032I2016J0D01*
G01Y1714298D01*
G02X303693Y1714527I2003J229D01*
G02X303706Y1714756I2016J0D01*
G01Y1717167D01*
G02X304009Y1717470I303J0D01*
G37*
G36*
G01X319757D02*
X323457D01*
G02X323760Y1717167I0J-303D01*
G01Y1707161D01*
G02X323457Y1706858I-303J0D01*
G01X319757D01*
G02X319454Y1707161I0J303D01*
G01Y1709574D01*
G02X319441Y1709803I2003J229D01*
G02X319454Y1710032I2016J0D01*
G01Y1714298D01*
G02X319441Y1714527I2003J229D01*
G02X319454Y1714756I2016J0D01*
G01Y1717167D01*
G02X319757Y1717470I303J0D01*
G37*
G36*
G01X335505D02*
X339205D01*
G02X339508Y1717167I0J-303D01*
G01Y1707161D01*
G02X339205Y1706858I-303J0D01*
G01X335505D01*
G02X335202Y1707161I0J303D01*
G01Y1709574D01*
G02X335189Y1709803I2003J229D01*
G02X335202Y1710032I2016J0D01*
G01Y1714298D01*
G02X335189Y1714527I2003J229D01*
G02X335202Y1714756I2016J0D01*
G01Y1717167D01*
G02X335505Y1717470I303J0D01*
G37*
G36*
G01X351253D02*
X354953D01*
G02X355256Y1717167I0J-303D01*
G01Y1707161D01*
G02X354953Y1706858I-303J0D01*
G01X351253D01*
G02X350950Y1707161I0J303D01*
G01Y1709574D01*
G02X350937Y1709803I2003J229D01*
G02X350950Y1710032I2016J0D01*
G01Y1714298D01*
G02X350937Y1714527I2003J229D01*
G02X350950Y1714756I2016J0D01*
G01Y1717167D01*
G02X351253Y1717470I303J0D01*
G37*
G36*
G01X501253D02*
X504953D01*
G02X505256Y1717167I0J-303D01*
G01Y1707161D01*
G02X504953Y1706858I-303J0D01*
G01X501253D01*
G02X500950Y1707161I0J303D01*
G01Y1709574D01*
G02X500937Y1709803I2003J229D01*
G02X500950Y1710032I2016J0D01*
G01Y1714298D01*
G02X500937Y1714527I2003J229D01*
G02X500950Y1714756I2016J0D01*
G01Y1717167D01*
G02X501253Y1717470I303J0D01*
G37*
G36*
G01X517001D02*
X520701D01*
G02X521004Y1717167I0J-303D01*
G01Y1707161D01*
G02X520701Y1706858I-303J0D01*
G01X517001D01*
G02X516698Y1707161I0J303D01*
G01Y1709574D01*
G02X516685Y1709803I2003J229D01*
G02X516698Y1710032I2016J0D01*
G01Y1714298D01*
G02X516685Y1714527I2003J229D01*
G02X516698Y1714756I2016J0D01*
G01Y1717167D01*
G02X517001Y1717470I303J0D01*
G37*
G36*
G01X532749D02*
X536449D01*
G02X536752Y1717167I0J-303D01*
G01Y1707161D01*
G02X536449Y1706858I-303J0D01*
G01X532749D01*
G02X532446Y1707161I0J303D01*
G01Y1709574D01*
G02X532433Y1709803I2003J229D01*
G02X532446Y1710032I2016J0D01*
G01Y1714298D01*
G02X532433Y1714527I2003J229D01*
G02X532446Y1714756I2016J0D01*
G01Y1717167D01*
G02X532749Y1717470I303J0D01*
G37*
G36*
G01X548497D02*
X552197D01*
G02X552500Y1717167I0J-303D01*
G01Y1707161D01*
G02X552197Y1706858I-303J0D01*
G01X548497D01*
G02X548194Y1707161I0J303D01*
G01Y1709574D01*
G02X548181Y1709803I2003J229D01*
G02X548194Y1710032I2016J0D01*
G01Y1714298D01*
G02X548181Y1714527I2003J229D01*
G02X548194Y1714756I2016J0D01*
G01Y1717167D01*
G02X548497Y1717470I303J0D01*
G37*
G36*
G01X568182D02*
X571882D01*
G02X572184Y1717167I-1J-303D01*
G01Y1707161D01*
G02X571882Y1706858I-302J-1D01*
G01X568182D01*
G02X567880Y1707161I1J303D01*
G01Y1709566D01*
G02X567866Y1709803I2002J237D01*
G02X567880Y1710040I2016J0D01*
G01Y1714290D01*
G02X567866Y1714527I2002J237D01*
G02X567880Y1714764I2016J0D01*
G01Y1717167D01*
G02X568182Y1717470I302J1D01*
G37*
G36*
G01X583930D02*
X587630D01*
G02X587932Y1717167I-1J-303D01*
G01Y1707161D01*
G02X587630Y1706858I-302J-1D01*
G01X583930D01*
G02X583628Y1707161I1J303D01*
G01Y1709566D01*
G02X583614Y1709803I2002J237D01*
G02X583628Y1710040I2016J0D01*
G01Y1714290D01*
G02X583614Y1714527I2002J237D01*
G02X583628Y1714764I2016J0D01*
G01Y1717167D01*
G02X583930Y1717470I302J1D01*
G37*
G36*
G01X599678D02*
X603378D01*
G02X603680Y1717167I-1J-303D01*
G01Y1707161D01*
G02X603378Y1706858I-302J-1D01*
G01X599678D01*
G02X599376Y1707161I1J303D01*
G01Y1709566D01*
G02X599362Y1709803I2002J237D01*
G02X599376Y1710040I2016J0D01*
G01Y1714290D01*
G02X599362Y1714527I2002J237D01*
G02X599376Y1714764I2016J0D01*
G01Y1717167D01*
G02X599678Y1717470I302J1D01*
G37*
G36*
G01X615426D02*
X619126D01*
G02X619428Y1717167I-1J-303D01*
G01Y1707161D01*
G02X619126Y1706858I-302J-1D01*
G01X615426D01*
G02X615124Y1707161I1J303D01*
G01Y1709566D01*
G02X615110Y1709803I2002J237D01*
G02X615124Y1710040I2016J0D01*
G01Y1714290D01*
G02X615110Y1714527I2002J237D01*
G02X615124Y1714764I2016J0D01*
G01Y1717167D01*
G02X615426Y1717470I302J1D01*
G37*
G36*
G01X1244954D02*
X1248654D01*
G02X1248956Y1717167I-1J-303D01*
G01Y1707161D01*
G02X1248654Y1706858I-302J-1D01*
G01X1244954D01*
G02X1244652Y1707161I1J303D01*
G01Y1709566D01*
G02X1244638Y1709803I2002J237D01*
G02X1244652Y1710040I2016J0D01*
G01Y1714290D01*
G02X1244638Y1714527I2002J237D01*
G02X1244652Y1714764I2016J0D01*
G01Y1717167D01*
G02X1244954Y1717470I302J1D01*
G37*
G36*
G01X1260702D02*
X1264402D01*
G02X1264704Y1717167I-1J-303D01*
G01Y1707161D01*
G02X1264402Y1706858I-302J-1D01*
G01X1260702D01*
G02X1260400Y1707161I1J303D01*
G01Y1709566D01*
G02X1260386Y1709803I2002J237D01*
G02X1260400Y1710040I2016J0D01*
G01Y1714290D01*
G02X1260386Y1714527I2002J237D01*
G02X1260400Y1714764I2016J0D01*
G01Y1717167D01*
G02X1260702Y1717470I302J1D01*
G37*
G36*
G01X1276450D02*
X1280150D01*
G02X1280452Y1717167I-1J-303D01*
G01Y1707161D01*
G02X1280150Y1706858I-302J-1D01*
G01X1276450D01*
G02X1276148Y1707161I1J303D01*
G01Y1709566D01*
G02X1276134Y1709803I2002J237D01*
G02X1276148Y1710040I2016J0D01*
G01Y1714290D01*
G02X1276134Y1714527I2002J237D01*
G02X1276148Y1714764I2016J0D01*
G01Y1717167D01*
G02X1276450Y1717470I302J1D01*
G37*
G36*
G01X1292198D02*
X1295898D01*
G02X1296200Y1717167I-1J-303D01*
G01Y1707161D01*
G02X1295898Y1706858I-302J-1D01*
G01X1292198D01*
G02X1291896Y1707161I1J303D01*
G01Y1709566D01*
G02X1291882Y1709803I2002J237D01*
G02X1291896Y1710040I2016J0D01*
G01Y1714290D01*
G02X1291882Y1714527I2002J237D01*
G02X1291896Y1714764I2016J0D01*
G01Y1717167D01*
G02X1292198Y1717470I302J1D01*
G37*
G36*
G01X1311883D02*
X1315583D01*
G02X1315886Y1717167I0J-303D01*
G01Y1707161D01*
G02X1315583Y1706858I-303J0D01*
G01X1311883D01*
G02X1311580Y1707161I0J303D01*
G01Y1709574D01*
G02X1311567Y1709803I2003J229D01*
G02X1311580Y1710032I2016J0D01*
G01Y1714298D01*
G02X1311567Y1714527I2003J229D01*
G02X1311580Y1714756I2016J0D01*
G01Y1717167D01*
G02X1311883Y1717470I303J0D01*
G37*
G36*
G01X1327631D02*
X1331331D01*
G02X1331634Y1717167I0J-303D01*
G01Y1707161D01*
G02X1331331Y1706858I-303J0D01*
G01X1327631D01*
G02X1327328Y1707161I0J303D01*
G01Y1709574D01*
G02X1327315Y1709803I2003J229D01*
G02X1327328Y1710032I2016J0D01*
G01Y1714298D01*
G02X1327315Y1714527I2003J229D01*
G02X1327328Y1714756I2016J0D01*
G01Y1717167D01*
G02X1327631Y1717470I303J0D01*
G37*
G36*
G01X1343379D02*
X1347079D01*
G02X1347382Y1717167I0J-303D01*
G01Y1707161D01*
G02X1347079Y1706858I-303J0D01*
G01X1343379D01*
G02X1343076Y1707161I0J303D01*
G01Y1709574D01*
G02X1343063Y1709803I2003J229D01*
G02X1343076Y1710032I2016J0D01*
G01Y1714298D01*
G02X1343063Y1714527I2003J229D01*
G02X1343076Y1714756I2016J0D01*
G01Y1717167D01*
G02X1343379Y1717470I303J0D01*
G37*
G36*
G01X1359127D02*
X1362827D01*
G02X1363130Y1717167I0J-303D01*
G01Y1707161D01*
G02X1362827Y1706858I-303J0D01*
G01X1359127D01*
G02X1358824Y1707161I0J303D01*
G01Y1709574D01*
G02X1358811Y1709803I2003J229D01*
G02X1358824Y1710032I2016J0D01*
G01Y1714298D01*
G02X1358811Y1714527I2003J229D01*
G02X1358824Y1714756I2016J0D01*
G01Y1717167D01*
G02X1359127Y1717470I303J0D01*
G37*
G36*
G01X1509127D02*
X1512827D01*
G02X1513130Y1717167I0J-303D01*
G01Y1707161D01*
G02X1512827Y1706858I-303J0D01*
G01X1509127D01*
G02X1508824Y1707161I0J303D01*
G01Y1709574D01*
G02X1508811Y1709803I2003J229D01*
G02X1508824Y1710032I2016J0D01*
G01Y1714298D01*
G02X1508811Y1714527I2003J229D01*
G02X1508824Y1714756I2016J0D01*
G01Y1717167D01*
G02X1509127Y1717470I303J0D01*
G37*
G36*
G01X1524875D02*
X1528575D01*
G02X1528878Y1717167I0J-303D01*
G01Y1707161D01*
G02X1528575Y1706858I-303J0D01*
G01X1524875D01*
G02X1524572Y1707161I0J303D01*
G01Y1709574D01*
G02X1524559Y1709803I2003J229D01*
G02X1524572Y1710032I2016J0D01*
G01Y1714298D01*
G02X1524559Y1714527I2003J229D01*
G02X1524572Y1714756I2016J0D01*
G01Y1717167D01*
G02X1524875Y1717470I303J0D01*
G37*
G36*
G01X1540623D02*
X1544323D01*
G02X1544626Y1717167I0J-303D01*
G01Y1707161D01*
G02X1544323Y1706858I-303J0D01*
G01X1540623D01*
G02X1540320Y1707161I0J303D01*
G01Y1709574D01*
G02X1540307Y1709803I2003J229D01*
G02X1540320Y1710032I2016J0D01*
G01Y1714298D01*
G02X1540307Y1714527I2003J229D01*
G02X1540320Y1714756I2016J0D01*
G01Y1717167D01*
G02X1540623Y1717470I303J0D01*
G37*
G36*
G01X1556371D02*
X1560071D01*
G02X1560374Y1717167I0J-303D01*
G01Y1707161D01*
G02X1560071Y1706858I-303J0D01*
G01X1556371D01*
G02X1556068Y1707161I0J303D01*
G01Y1709574D01*
G02X1556055Y1709803I2003J229D01*
G02X1556068Y1710032I2016J0D01*
G01Y1714298D01*
G02X1556055Y1714527I2003J229D01*
G02X1556068Y1714756I2016J0D01*
G01Y1717167D01*
G02X1556371Y1717470I303J0D01*
G37*
G36*
G01X1576056D02*
X1579756D01*
G02X1580058Y1717167I-1J-303D01*
G01Y1707161D01*
G02X1579756Y1706858I-302J-1D01*
G01X1576056D01*
G02X1575754Y1707161I1J303D01*
G01Y1709566D01*
G02X1575740Y1709803I2002J237D01*
G02X1575754Y1710040I2016J0D01*
G01Y1714290D01*
G02X1575740Y1714527I2002J237D01*
G02X1575754Y1714764I2016J0D01*
G01Y1717167D01*
G02X1576056Y1717470I302J1D01*
G37*
G36*
G01X1591804D02*
X1595504D01*
G02X1595806Y1717167I-1J-303D01*
G01Y1707161D01*
G02X1595504Y1706858I-302J-1D01*
G01X1591804D01*
G02X1591502Y1707161I1J303D01*
G01Y1709566D01*
G02X1591488Y1709803I2002J237D01*
G02X1591502Y1710040I2016J0D01*
G01Y1714290D01*
G02X1591488Y1714527I2002J237D01*
G02X1591502Y1714764I2016J0D01*
G01Y1717167D01*
G02X1591804Y1717470I302J1D01*
G37*
G36*
G01X1607552D02*
X1611252D01*
G02X1611554Y1717167I-1J-303D01*
G01Y1707161D01*
G02X1611252Y1706858I-302J-1D01*
G01X1607552D01*
G02X1607250Y1707161I1J303D01*
G01Y1709566D01*
G02X1607236Y1709803I2002J237D01*
G02X1607250Y1710040I2016J0D01*
G01Y1714290D01*
G02X1607236Y1714527I2002J237D01*
G02X1607250Y1714764I2016J0D01*
G01Y1717167D01*
G02X1607552Y1717470I302J1D01*
G37*
G36*
G01X1623300D02*
X1627000D01*
G02X1627302Y1717167I-1J-303D01*
G01Y1707161D01*
G02X1627000Y1706858I-302J-1D01*
G01X1623300D01*
G02X1622998Y1707161I1J303D01*
G01Y1709566D01*
G02X1622984Y1709803I2002J237D01*
G02X1622998Y1710040I2016J0D01*
G01Y1714290D01*
G02X1622984Y1714527I2002J237D01*
G02X1622998Y1714764I2016J0D01*
G01Y1717167D01*
G02X1623300Y1717470I302J1D01*
G37*
G36*
G01X229206Y1727706D02*
X232906D01*
G02X233208Y1727404I0J-302D01*
G01Y1717398D01*
G02X232906Y1717096I-302J0D01*
G01X229206D01*
G02X228904Y1717398I0J302D01*
G01Y1719802D01*
G02X228890Y1720039I2002J237D01*
G02X228904Y1720276I2016J0D01*
G01Y1724526D01*
G02X228890Y1724763I2002J237D01*
G02X228904Y1725000I2016J0D01*
G01Y1727404D01*
G02X229206Y1727706I302J0D01*
G37*
G36*
G01X244954D02*
X248654D01*
G02X248956Y1727404I0J-302D01*
G01Y1717398D01*
G02X248654Y1717096I-302J0D01*
G01X244954D01*
G02X244652Y1717398I0J302D01*
G01Y1719802D01*
G02X244638Y1720039I2002J237D01*
G02X244652Y1720276I2016J0D01*
G01Y1724526D01*
G02X244638Y1724763I2002J237D01*
G02X244652Y1725000I2016J0D01*
G01Y1727404D01*
G02X244954Y1727706I302J0D01*
G37*
G36*
G01X260702D02*
X264402D01*
G02X264704Y1727404I0J-302D01*
G01Y1717398D01*
G02X264402Y1717096I-302J0D01*
G01X260702D01*
G02X260400Y1717398I0J302D01*
G01Y1719802D01*
G02X260386Y1720039I2002J237D01*
G02X260400Y1720276I2016J0D01*
G01Y1724526D01*
G02X260386Y1724763I2002J237D01*
G02X260400Y1725000I2016J0D01*
G01Y1727404D01*
G02X260702Y1727706I302J0D01*
G37*
G36*
G01X276450D02*
X280150D01*
G02X280452Y1727404I0J-302D01*
G01Y1717398D01*
G02X280150Y1717096I-302J0D01*
G01X276450D01*
G02X276148Y1717398I0J302D01*
G01Y1719802D01*
G02X276134Y1720039I2002J237D01*
G02X276148Y1720276I2016J0D01*
G01Y1724526D01*
G02X276134Y1724763I2002J237D01*
G02X276148Y1725000I2016J0D01*
G01Y1727404D01*
G02X276450Y1727706I302J0D01*
G37*
G36*
G01X560308D02*
X564008D01*
G02X564310Y1727404I0J-302D01*
G01Y1717398D01*
G02X564008Y1717096I-302J0D01*
G01X560308D01*
G02X560006Y1717398I0J302D01*
G01Y1719802D01*
G02X559992Y1720039I2002J237D01*
G02X560006Y1720276I2016J0D01*
G01Y1724526D01*
G02X559992Y1724763I2002J237D01*
G02X560006Y1725000I2016J0D01*
G01Y1727404D01*
G02X560308Y1727706I302J0D01*
G37*
G36*
G01X576056D02*
X579756D01*
G02X580058Y1727404I0J-302D01*
G01Y1717398D01*
G02X579756Y1717096I-302J0D01*
G01X576056D01*
G02X575754Y1717398I0J302D01*
G01Y1719802D01*
G02X575740Y1720039I2002J237D01*
G02X575754Y1720276I2016J0D01*
G01Y1724526D01*
G02X575740Y1724763I2002J237D01*
G02X575754Y1725000I2016J0D01*
G01Y1727404D01*
G02X576056Y1727706I302J0D01*
G37*
G36*
G01X591804D02*
X595504D01*
G02X595806Y1727404I0J-302D01*
G01Y1717398D01*
G02X595504Y1717096I-302J0D01*
G01X591804D01*
G02X591502Y1717398I0J302D01*
G01Y1719802D01*
G02X591488Y1720039I2002J237D01*
G02X591502Y1720276I2016J0D01*
G01Y1724526D01*
G02X591488Y1724763I2002J237D01*
G02X591502Y1725000I2016J0D01*
G01Y1727404D01*
G02X591804Y1727706I302J0D01*
G37*
G36*
G01X607552D02*
X611252D01*
G02X611554Y1727404I0J-302D01*
G01Y1717398D01*
G02X611252Y1717096I-302J0D01*
G01X607552D01*
G02X607250Y1717398I0J302D01*
G01Y1719802D01*
G02X607236Y1720039I2002J237D01*
G02X607250Y1720276I2016J0D01*
G01Y1724526D01*
G02X607236Y1724763I2002J237D01*
G02X607250Y1725000I2016J0D01*
G01Y1727404D01*
G02X607552Y1727706I302J0D01*
G37*
G36*
G01X1237080D02*
X1240780D01*
G02X1241082Y1727404I0J-302D01*
G01Y1717398D01*
G02X1240780Y1717096I-302J0D01*
G01X1237080D01*
G02X1236778Y1717398I0J302D01*
G01Y1719802D01*
G02X1236764Y1720039I2002J237D01*
G02X1236778Y1720276I2016J0D01*
G01Y1724526D01*
G02X1236764Y1724763I2002J237D01*
G02X1236778Y1725000I2016J0D01*
G01Y1727404D01*
G02X1237080Y1727706I302J0D01*
G37*
G36*
G01X1252828D02*
X1256528D01*
G02X1256830Y1727404I0J-302D01*
G01Y1717398D01*
G02X1256528Y1717096I-302J0D01*
G01X1252828D01*
G02X1252526Y1717398I0J302D01*
G01Y1719802D01*
G02X1252512Y1720039I2002J237D01*
G02X1252526Y1720276I2016J0D01*
G01Y1724526D01*
G02X1252512Y1724763I2002J237D01*
G02X1252526Y1725000I2016J0D01*
G01Y1727404D01*
G02X1252828Y1727706I302J0D01*
G37*
G36*
G01X1268576D02*
X1272276D01*
G02X1272578Y1727404I0J-302D01*
G01Y1717398D01*
G02X1272276Y1717096I-302J0D01*
G01X1268576D01*
G02X1268274Y1717398I0J302D01*
G01Y1719802D01*
G02X1268260Y1720039I2002J237D01*
G02X1268274Y1720276I2016J0D01*
G01Y1724526D01*
G02X1268260Y1724763I2002J237D01*
G02X1268274Y1725000I2016J0D01*
G01Y1727404D01*
G02X1268576Y1727706I302J0D01*
G37*
G36*
G01X1284324D02*
X1288024D01*
G02X1288326Y1727404I0J-302D01*
G01Y1717398D01*
G02X1288024Y1717096I-302J0D01*
G01X1284324D01*
G02X1284022Y1717398I0J302D01*
G01Y1719802D01*
G02X1284008Y1720039I2002J237D01*
G02X1284022Y1720276I2016J0D01*
G01Y1724526D01*
G02X1284008Y1724763I2002J237D01*
G02X1284022Y1725000I2016J0D01*
G01Y1727404D01*
G02X1284324Y1727706I302J0D01*
G37*
G36*
G01X1568182D02*
X1571882D01*
G02X1572184Y1727404I0J-302D01*
G01Y1717398D01*
G02X1571882Y1717096I-302J0D01*
G01X1568182D01*
G02X1567880Y1717398I0J302D01*
G01Y1719802D01*
G02X1567866Y1720039I2002J237D01*
G02X1567880Y1720276I2016J0D01*
G01Y1724526D01*
G02X1567866Y1724763I2002J237D01*
G02X1567880Y1725000I2016J0D01*
G01Y1727404D01*
G02X1568182Y1727706I302J0D01*
G37*
G36*
G01X1583930D02*
X1587630D01*
G02X1587932Y1727404I0J-302D01*
G01Y1717398D01*
G02X1587630Y1717096I-302J0D01*
G01X1583930D01*
G02X1583628Y1717398I0J302D01*
G01Y1719802D01*
G02X1583614Y1720039I2002J237D01*
G02X1583628Y1720276I2016J0D01*
G01Y1724526D01*
G02X1583614Y1724763I2002J237D01*
G02X1583628Y1725000I2016J0D01*
G01Y1727404D01*
G02X1583930Y1727706I302J0D01*
G37*
G36*
G01X1599678D02*
X1603378D01*
G02X1603680Y1727404I0J-302D01*
G01Y1717398D01*
G02X1603378Y1717096I-302J0D01*
G01X1599678D01*
G02X1599376Y1717398I0J302D01*
G01Y1719802D01*
G02X1599362Y1720039I2002J237D01*
G02X1599376Y1720276I2016J0D01*
G01Y1724526D01*
G02X1599362Y1724763I2002J237D01*
G02X1599376Y1725000I2016J0D01*
G01Y1727404D01*
G02X1599678Y1727706I302J0D01*
G37*
G36*
G01X1615426D02*
X1619126D01*
G02X1619428Y1727404I0J-302D01*
G01Y1717398D01*
G02X1619126Y1717096I-302J0D01*
G01X1615426D01*
G02X1615124Y1717398I0J302D01*
G01Y1719802D01*
G02X1615110Y1720039I2002J237D01*
G02X1615124Y1720276I2016J0D01*
G01Y1724526D01*
G02X1615110Y1724763I2002J237D01*
G02X1615124Y1725000I2016J0D01*
G01Y1727404D01*
G02X1615426Y1727706I302J0D01*
G37*
G36*
G01X296135D02*
X299835D01*
G02X300138Y1727404I1J-302D01*
G01Y1717398D01*
G02X299835Y1717096I-303J1D01*
G01X296135D01*
G02X295832Y1717398I-1J302D01*
G01Y1719810D01*
G02X295819Y1720039I2003J229D01*
G02X295832Y1720268I2016J0D01*
G01Y1724534D01*
G02X295819Y1724763I2003J229D01*
G02X295832Y1724992I2016J0D01*
G01Y1727404D01*
G02X296135Y1727706I303J-1D01*
G37*
G36*
G01X311883D02*
X315583D01*
G02X315886Y1727404I1J-302D01*
G01Y1717398D01*
G02X315583Y1717096I-303J1D01*
G01X311883D01*
G02X311580Y1717398I-1J302D01*
G01Y1719810D01*
G02X311567Y1720039I2003J229D01*
G02X311580Y1720268I2016J0D01*
G01Y1724534D01*
G02X311567Y1724763I2003J229D01*
G02X311580Y1724992I2016J0D01*
G01Y1727404D01*
G02X311883Y1727706I303J-1D01*
G37*
G36*
G01X327631D02*
X331331D01*
G02X331634Y1727404I1J-302D01*
G01Y1717398D01*
G02X331331Y1717096I-303J1D01*
G01X327631D01*
G02X327328Y1717398I-1J302D01*
G01Y1719810D01*
G02X327315Y1720039I2003J229D01*
G02X327328Y1720268I2016J0D01*
G01Y1724534D01*
G02X327315Y1724763I2003J229D01*
G02X327328Y1724992I2016J0D01*
G01Y1727404D01*
G02X327631Y1727706I303J-1D01*
G37*
G36*
G01X343379D02*
X347079D01*
G02X347382Y1727404I1J-302D01*
G01Y1717398D01*
G02X347079Y1717096I-303J1D01*
G01X343379D01*
G02X343076Y1717398I-1J302D01*
G01Y1719810D01*
G02X343063Y1720039I2003J229D01*
G02X343076Y1720268I2016J0D01*
G01Y1724534D01*
G02X343063Y1724763I2003J229D01*
G02X343076Y1724992I2016J0D01*
G01Y1727404D01*
G02X343379Y1727706I303J-1D01*
G37*
G36*
G01X493379D02*
X497079D01*
G02X497382Y1727404I1J-302D01*
G01Y1717398D01*
G02X497079Y1717096I-303J1D01*
G01X493379D01*
G02X493076Y1717398I-1J302D01*
G01Y1719810D01*
G02X493063Y1720039I2003J229D01*
G02X493076Y1720268I2016J0D01*
G01Y1724534D01*
G02X493063Y1724763I2003J229D01*
G02X493076Y1724992I2016J0D01*
G01Y1727404D01*
G02X493379Y1727706I303J-1D01*
G37*
G36*
G01X509127D02*
X512827D01*
G02X513130Y1727404I1J-302D01*
G01Y1717398D01*
G02X512827Y1717096I-303J1D01*
G01X509127D01*
G02X508824Y1717398I-1J302D01*
G01Y1719810D01*
G02X508811Y1720039I2003J229D01*
G02X508824Y1720268I2016J0D01*
G01Y1724534D01*
G02X508811Y1724763I2003J229D01*
G02X508824Y1724992I2016J0D01*
G01Y1727404D01*
G02X509127Y1727706I303J-1D01*
G37*
G36*
G01X524875D02*
X528575D01*
G02X528878Y1727404I1J-302D01*
G01Y1717398D01*
G02X528575Y1717096I-303J1D01*
G01X524875D01*
G02X524572Y1717398I-1J302D01*
G01Y1719810D01*
G02X524559Y1720039I2003J229D01*
G02X524572Y1720268I2016J0D01*
G01Y1724534D01*
G02X524559Y1724763I2003J229D01*
G02X524572Y1724992I2016J0D01*
G01Y1727404D01*
G02X524875Y1727706I303J-1D01*
G37*
G36*
G01X540623D02*
X544323D01*
G02X544626Y1727404I1J-302D01*
G01Y1717398D01*
G02X544323Y1717096I-303J1D01*
G01X540623D01*
G02X540320Y1717398I-1J302D01*
G01Y1719810D01*
G02X540307Y1720039I2003J229D01*
G02X540320Y1720268I2016J0D01*
G01Y1724534D01*
G02X540307Y1724763I2003J229D01*
G02X540320Y1724992I2016J0D01*
G01Y1727404D01*
G02X540623Y1727706I303J-1D01*
G37*
G36*
G01X1304009D02*
X1307709D01*
G02X1308012Y1727404I1J-302D01*
G01Y1717398D01*
G02X1307709Y1717096I-303J1D01*
G01X1304009D01*
G02X1303706Y1717398I-1J302D01*
G01Y1719810D01*
G02X1303693Y1720039I2003J229D01*
G02X1303706Y1720268I2016J0D01*
G01Y1724534D01*
G02X1303693Y1724763I2003J229D01*
G02X1303706Y1724992I2016J0D01*
G01Y1727404D01*
G02X1304009Y1727706I303J-1D01*
G37*
G36*
G01X1319757D02*
X1323457D01*
G02X1323760Y1727404I1J-302D01*
G01Y1717398D01*
G02X1323457Y1717096I-303J1D01*
G01X1319757D01*
G02X1319454Y1717398I-1J302D01*
G01Y1719810D01*
G02X1319441Y1720039I2003J229D01*
G02X1319454Y1720268I2016J0D01*
G01Y1724534D01*
G02X1319441Y1724763I2003J229D01*
G02X1319454Y1724992I2016J0D01*
G01Y1727404D01*
G02X1319757Y1727706I303J-1D01*
G37*
G36*
G01X1335505D02*
X1339205D01*
G02X1339508Y1727404I1J-302D01*
G01Y1717398D01*
G02X1339205Y1717096I-303J1D01*
G01X1335505D01*
G02X1335202Y1717398I-1J302D01*
G01Y1719810D01*
G02X1335189Y1720039I2003J229D01*
G02X1335202Y1720268I2016J0D01*
G01Y1724534D01*
G02X1335189Y1724763I2003J229D01*
G02X1335202Y1724992I2016J0D01*
G01Y1727404D01*
G02X1335505Y1727706I303J-1D01*
G37*
G36*
G01X1351253D02*
X1354953D01*
G02X1355256Y1727404I1J-302D01*
G01Y1717398D01*
G02X1354953Y1717096I-303J1D01*
G01X1351253D01*
G02X1350950Y1717398I-1J302D01*
G01Y1719810D01*
G02X1350937Y1720039I2003J229D01*
G02X1350950Y1720268I2016J0D01*
G01Y1724534D01*
G02X1350937Y1724763I2003J229D01*
G02X1350950Y1724992I2016J0D01*
G01Y1727404D01*
G02X1351253Y1727706I303J-1D01*
G37*
G36*
G01X1501253D02*
X1504953D01*
G02X1505256Y1727404I1J-302D01*
G01Y1717398D01*
G02X1504953Y1717096I-303J1D01*
G01X1501253D01*
G02X1500950Y1717398I-1J302D01*
G01Y1719810D01*
G02X1500937Y1720039I2003J229D01*
G02X1500950Y1720268I2016J0D01*
G01Y1724534D01*
G02X1500937Y1724763I2003J229D01*
G02X1500950Y1724992I2016J0D01*
G01Y1727404D01*
G02X1501253Y1727706I303J-1D01*
G37*
G36*
G01X1517001D02*
X1520701D01*
G02X1521004Y1727404I1J-302D01*
G01Y1717398D01*
G02X1520701Y1717096I-303J1D01*
G01X1517001D01*
G02X1516698Y1717398I-1J302D01*
G01Y1719810D01*
G02X1516685Y1720039I2003J229D01*
G02X1516698Y1720268I2016J0D01*
G01Y1724534D01*
G02X1516685Y1724763I2003J229D01*
G02X1516698Y1724992I2016J0D01*
G01Y1727404D01*
G02X1517001Y1727706I303J-1D01*
G37*
G36*
G01X1532749D02*
X1536449D01*
G02X1536752Y1727404I1J-302D01*
G01Y1717398D01*
G02X1536449Y1717096I-303J1D01*
G01X1532749D01*
G02X1532446Y1717398I-1J302D01*
G01Y1719810D01*
G02X1532433Y1720039I2003J229D01*
G02X1532446Y1720268I2016J0D01*
G01Y1724534D01*
G02X1532433Y1724763I2003J229D01*
G02X1532446Y1724992I2016J0D01*
G01Y1727404D01*
G02X1532749Y1727706I303J-1D01*
G37*
G36*
G01X1548497D02*
X1552197D01*
G02X1552500Y1727404I1J-302D01*
G01Y1717398D01*
G02X1552197Y1717096I-303J1D01*
G01X1548497D01*
G02X1548194Y1717398I-1J302D01*
G01Y1719810D01*
G02X1548181Y1720039I2003J229D01*
G02X1548194Y1720268I2016J0D01*
G01Y1724534D01*
G02X1548181Y1724763I2003J229D01*
G02X1548194Y1724992I2016J0D01*
G01Y1727404D01*
G02X1548497Y1727706I303J-1D01*
G37*
G36*
G01X237080Y1731644D02*
X240780D01*
G02X241082Y1731341I-1J-303D01*
G01Y1721335D01*
G02X240780Y1721032I-302J-1D01*
G01X237080D01*
G02X236778Y1721335I1J303D01*
G01Y1723739D01*
G02X236764Y1723976I2002J237D01*
G02X236778Y1724213I2016J0D01*
G01Y1728463D01*
G02X236764Y1728700I2002J237D01*
G02X236778Y1728937I2016J0D01*
G01Y1731341D01*
G02X237080Y1731644I302J1D01*
G37*
G36*
G01X252828D02*
X256528D01*
G02X256830Y1731341I-1J-303D01*
G01Y1721335D01*
G02X256528Y1721032I-302J-1D01*
G01X252828D01*
G02X252526Y1721335I1J303D01*
G01Y1723739D01*
G02X252512Y1723976I2002J237D01*
G02X252526Y1724213I2016J0D01*
G01Y1728463D01*
G02X252512Y1728700I2002J237D01*
G02X252526Y1728937I2016J0D01*
G01Y1731341D01*
G02X252828Y1731644I302J1D01*
G37*
G36*
G01X268576D02*
X272276D01*
G02X272578Y1731341I-1J-303D01*
G01Y1721335D01*
G02X272276Y1721032I-302J-1D01*
G01X268576D01*
G02X268274Y1721335I1J303D01*
G01Y1723739D01*
G02X268260Y1723976I2002J237D01*
G02X268274Y1724213I2016J0D01*
G01Y1728463D01*
G02X268260Y1728700I2002J237D01*
G02X268274Y1728937I2016J0D01*
G01Y1731341D01*
G02X268576Y1731644I302J1D01*
G37*
G36*
G01X284324D02*
X288024D01*
G02X288326Y1731341I-1J-303D01*
G01Y1721335D01*
G02X288024Y1721032I-302J-1D01*
G01X284324D01*
G02X284022Y1721335I1J303D01*
G01Y1723739D01*
G02X284008Y1723976I2002J237D01*
G02X284022Y1724213I2016J0D01*
G01Y1728463D01*
G02X284008Y1728700I2002J237D01*
G02X284022Y1728937I2016J0D01*
G01Y1731341D01*
G02X284324Y1731644I302J1D01*
G37*
G36*
G01X304009D02*
X307709D01*
G02X308012Y1731341I0J-303D01*
G01Y1721335D01*
G02X307709Y1721032I-303J0D01*
G01X304009D01*
G02X303706Y1721335I0J303D01*
G01Y1723747D01*
G02X303693Y1723976I2003J229D01*
G02X303706Y1724205I2016J0D01*
G01Y1728471D01*
G02X303693Y1728700I2003J229D01*
G02X303706Y1728929I2016J0D01*
G01Y1731341D01*
G02X304009Y1731644I303J0D01*
G37*
G36*
G01X319757D02*
X323457D01*
G02X323760Y1731341I0J-303D01*
G01Y1721335D01*
G02X323457Y1721032I-303J0D01*
G01X319757D01*
G02X319454Y1721335I0J303D01*
G01Y1723747D01*
G02X319441Y1723976I2003J229D01*
G02X319454Y1724205I2016J0D01*
G01Y1728471D01*
G02X319441Y1728700I2003J229D01*
G02X319454Y1728929I2016J0D01*
G01Y1731341D01*
G02X319757Y1731644I303J0D01*
G37*
G36*
G01X335505D02*
X339205D01*
G02X339508Y1731341I0J-303D01*
G01Y1721335D01*
G02X339205Y1721032I-303J0D01*
G01X335505D01*
G02X335202Y1721335I0J303D01*
G01Y1723747D01*
G02X335189Y1723976I2003J229D01*
G02X335202Y1724205I2016J0D01*
G01Y1728471D01*
G02X335189Y1728700I2003J229D01*
G02X335202Y1728929I2016J0D01*
G01Y1731341D01*
G02X335505Y1731644I303J0D01*
G37*
G36*
G01X351253D02*
X354953D01*
G02X355256Y1731341I0J-303D01*
G01Y1721335D01*
G02X354953Y1721032I-303J0D01*
G01X351253D01*
G02X350950Y1721335I0J303D01*
G01Y1723747D01*
G02X350937Y1723976I2003J229D01*
G02X350950Y1724205I2016J0D01*
G01Y1728471D01*
G02X350937Y1728700I2003J229D01*
G02X350950Y1728929I2016J0D01*
G01Y1731341D01*
G02X351253Y1731644I303J0D01*
G37*
G36*
G01X501253D02*
X504953D01*
G02X505256Y1731341I0J-303D01*
G01Y1721335D01*
G02X504953Y1721032I-303J0D01*
G01X501253D01*
G02X500950Y1721335I0J303D01*
G01Y1723747D01*
G02X500937Y1723976I2003J229D01*
G02X500950Y1724205I2016J0D01*
G01Y1728471D01*
G02X500937Y1728700I2003J229D01*
G02X500950Y1728929I2016J0D01*
G01Y1731341D01*
G02X501253Y1731644I303J0D01*
G37*
G36*
G01X517001D02*
X520701D01*
G02X521004Y1731341I0J-303D01*
G01Y1721335D01*
G02X520701Y1721032I-303J0D01*
G01X517001D01*
G02X516698Y1721335I0J303D01*
G01Y1723747D01*
G02X516685Y1723976I2003J229D01*
G02X516698Y1724205I2016J0D01*
G01Y1728471D01*
G02X516685Y1728700I2003J229D01*
G02X516698Y1728929I2016J0D01*
G01Y1731341D01*
G02X517001Y1731644I303J0D01*
G37*
G36*
G01X532749D02*
X536449D01*
G02X536752Y1731341I0J-303D01*
G01Y1721335D01*
G02X536449Y1721032I-303J0D01*
G01X532749D01*
G02X532446Y1721335I0J303D01*
G01Y1723747D01*
G02X532433Y1723976I2003J229D01*
G02X532446Y1724205I2016J0D01*
G01Y1728471D01*
G02X532433Y1728700I2003J229D01*
G02X532446Y1728929I2016J0D01*
G01Y1731341D01*
G02X532749Y1731644I303J0D01*
G37*
G36*
G01X548497D02*
X552197D01*
G02X552500Y1731341I0J-303D01*
G01Y1721335D01*
G02X552197Y1721032I-303J0D01*
G01X548497D01*
G02X548194Y1721335I0J303D01*
G01Y1723747D01*
G02X548181Y1723976I2003J229D01*
G02X548194Y1724205I2016J0D01*
G01Y1728471D01*
G02X548181Y1728700I2003J229D01*
G02X548194Y1728929I2016J0D01*
G01Y1731341D01*
G02X548497Y1731644I303J0D01*
G37*
G36*
G01X568182D02*
X571882D01*
G02X572184Y1731341I-1J-303D01*
G01Y1721335D01*
G02X571882Y1721032I-302J-1D01*
G01X568182D01*
G02X567880Y1721335I1J303D01*
G01Y1723739D01*
G02X567866Y1723976I2002J237D01*
G02X567880Y1724213I2016J0D01*
G01Y1728463D01*
G02X567866Y1728700I2002J237D01*
G02X567880Y1728937I2016J0D01*
G01Y1731341D01*
G02X568182Y1731644I302J1D01*
G37*
G36*
G01X583930D02*
X587630D01*
G02X587932Y1731341I-1J-303D01*
G01Y1721335D01*
G02X587630Y1721032I-302J-1D01*
G01X583930D01*
G02X583628Y1721335I1J303D01*
G01Y1723739D01*
G02X583614Y1723976I2002J237D01*
G02X583628Y1724213I2016J0D01*
G01Y1728463D01*
G02X583614Y1728700I2002J237D01*
G02X583628Y1728937I2016J0D01*
G01Y1731341D01*
G02X583930Y1731644I302J1D01*
G37*
G36*
G01X599678D02*
X603378D01*
G02X603680Y1731341I-1J-303D01*
G01Y1721335D01*
G02X603378Y1721032I-302J-1D01*
G01X599678D01*
G02X599376Y1721335I1J303D01*
G01Y1723739D01*
G02X599362Y1723976I2002J237D01*
G02X599376Y1724213I2016J0D01*
G01Y1728463D01*
G02X599362Y1728700I2002J237D01*
G02X599376Y1728937I2016J0D01*
G01Y1731341D01*
G02X599678Y1731644I302J1D01*
G37*
G36*
G01X615426D02*
X619126D01*
G02X619428Y1731341I-1J-303D01*
G01Y1721335D01*
G02X619126Y1721032I-302J-1D01*
G01X615426D01*
G02X615124Y1721335I1J303D01*
G01Y1723739D01*
G02X615110Y1723976I2002J237D01*
G02X615124Y1724213I2016J0D01*
G01Y1728463D01*
G02X615110Y1728700I2002J237D01*
G02X615124Y1728937I2016J0D01*
G01Y1731341D01*
G02X615426Y1731644I302J1D01*
G37*
G36*
G01X1244954D02*
X1248654D01*
G02X1248956Y1731341I-1J-303D01*
G01Y1721335D01*
G02X1248654Y1721032I-302J-1D01*
G01X1244954D01*
G02X1244652Y1721335I1J303D01*
G01Y1723739D01*
G02X1244638Y1723976I2002J237D01*
G02X1244652Y1724213I2016J0D01*
G01Y1728463D01*
G02X1244638Y1728700I2002J237D01*
G02X1244652Y1728937I2016J0D01*
G01Y1731341D01*
G02X1244954Y1731644I302J1D01*
G37*
G36*
G01X1260702D02*
X1264402D01*
G02X1264704Y1731341I-1J-303D01*
G01Y1721335D01*
G02X1264402Y1721032I-302J-1D01*
G01X1260702D01*
G02X1260400Y1721335I1J303D01*
G01Y1723739D01*
G02X1260386Y1723976I2002J237D01*
G02X1260400Y1724213I2016J0D01*
G01Y1728463D01*
G02X1260386Y1728700I2002J237D01*
G02X1260400Y1728937I2016J0D01*
G01Y1731341D01*
G02X1260702Y1731644I302J1D01*
G37*
G36*
G01X1276450D02*
X1280150D01*
G02X1280452Y1731341I-1J-303D01*
G01Y1721335D01*
G02X1280150Y1721032I-302J-1D01*
G01X1276450D01*
G02X1276148Y1721335I1J303D01*
G01Y1723739D01*
G02X1276134Y1723976I2002J237D01*
G02X1276148Y1724213I2016J0D01*
G01Y1728463D01*
G02X1276134Y1728700I2002J237D01*
G02X1276148Y1728937I2016J0D01*
G01Y1731341D01*
G02X1276450Y1731644I302J1D01*
G37*
G36*
G01X1292198D02*
X1295898D01*
G02X1296200Y1731341I-1J-303D01*
G01Y1721335D01*
G02X1295898Y1721032I-302J-1D01*
G01X1292198D01*
G02X1291896Y1721335I1J303D01*
G01Y1723739D01*
G02X1291882Y1723976I2002J237D01*
G02X1291896Y1724213I2016J0D01*
G01Y1728463D01*
G02X1291882Y1728700I2002J237D01*
G02X1291896Y1728937I2016J0D01*
G01Y1731341D01*
G02X1292198Y1731644I302J1D01*
G37*
G36*
G01X1311883D02*
X1315583D01*
G02X1315886Y1731341I0J-303D01*
G01Y1721335D01*
G02X1315583Y1721032I-303J0D01*
G01X1311883D01*
G02X1311580Y1721335I0J303D01*
G01Y1723747D01*
G02X1311567Y1723976I2003J229D01*
G02X1311580Y1724205I2016J0D01*
G01Y1728471D01*
G02X1311567Y1728700I2003J229D01*
G02X1311580Y1728929I2016J0D01*
G01Y1731341D01*
G02X1311883Y1731644I303J0D01*
G37*
G36*
G01X1327631D02*
X1331331D01*
G02X1331634Y1731341I0J-303D01*
G01Y1721335D01*
G02X1331331Y1721032I-303J0D01*
G01X1327631D01*
G02X1327328Y1721335I0J303D01*
G01Y1723747D01*
G02X1327315Y1723976I2003J229D01*
G02X1327328Y1724205I2016J0D01*
G01Y1728471D01*
G02X1327315Y1728700I2003J229D01*
G02X1327328Y1728929I2016J0D01*
G01Y1731341D01*
G02X1327631Y1731644I303J0D01*
G37*
G36*
G01X1343379D02*
X1347079D01*
G02X1347382Y1731341I0J-303D01*
G01Y1721335D01*
G02X1347079Y1721032I-303J0D01*
G01X1343379D01*
G02X1343076Y1721335I0J303D01*
G01Y1723747D01*
G02X1343063Y1723976I2003J229D01*
G02X1343076Y1724205I2016J0D01*
G01Y1728471D01*
G02X1343063Y1728700I2003J229D01*
G02X1343076Y1728929I2016J0D01*
G01Y1731341D01*
G02X1343379Y1731644I303J0D01*
G37*
G36*
G01X1359127D02*
X1362827D01*
G02X1363130Y1731341I0J-303D01*
G01Y1721335D01*
G02X1362827Y1721032I-303J0D01*
G01X1359127D01*
G02X1358824Y1721335I0J303D01*
G01Y1723747D01*
G02X1358811Y1723976I2003J229D01*
G02X1358824Y1724205I2016J0D01*
G01Y1728471D01*
G02X1358811Y1728700I2003J229D01*
G02X1358824Y1728929I2016J0D01*
G01Y1731341D01*
G02X1359127Y1731644I303J0D01*
G37*
G36*
G01X1509127D02*
X1512827D01*
G02X1513130Y1731341I0J-303D01*
G01Y1721335D01*
G02X1512827Y1721032I-303J0D01*
G01X1509127D01*
G02X1508824Y1721335I0J303D01*
G01Y1723747D01*
G02X1508811Y1723976I2003J229D01*
G02X1508824Y1724205I2016J0D01*
G01Y1728471D01*
G02X1508811Y1728700I2003J229D01*
G02X1508824Y1728929I2016J0D01*
G01Y1731341D01*
G02X1509127Y1731644I303J0D01*
G37*
G36*
G01X1524875D02*
X1528575D01*
G02X1528878Y1731341I0J-303D01*
G01Y1721335D01*
G02X1528575Y1721032I-303J0D01*
G01X1524875D01*
G02X1524572Y1721335I0J303D01*
G01Y1723747D01*
G02X1524559Y1723976I2003J229D01*
G02X1524572Y1724205I2016J0D01*
G01Y1728471D01*
G02X1524559Y1728700I2003J229D01*
G02X1524572Y1728929I2016J0D01*
G01Y1731341D01*
G02X1524875Y1731644I303J0D01*
G37*
G36*
G01X1540623D02*
X1544323D01*
G02X1544626Y1731341I0J-303D01*
G01Y1721335D01*
G02X1544323Y1721032I-303J0D01*
G01X1540623D01*
G02X1540320Y1721335I0J303D01*
G01Y1723747D01*
G02X1540307Y1723976I2003J229D01*
G02X1540320Y1724205I2016J0D01*
G01Y1728471D01*
G02X1540307Y1728700I2003J229D01*
G02X1540320Y1728929I2016J0D01*
G01Y1731341D01*
G02X1540623Y1731644I303J0D01*
G37*
G36*
G01X1556371D02*
X1560071D01*
G02X1560374Y1731341I0J-303D01*
G01Y1721335D01*
G02X1560071Y1721032I-303J0D01*
G01X1556371D01*
G02X1556068Y1721335I0J303D01*
G01Y1723747D01*
G02X1556055Y1723976I2003J229D01*
G02X1556068Y1724205I2016J0D01*
G01Y1728471D01*
G02X1556055Y1728700I2003J229D01*
G02X1556068Y1728929I2016J0D01*
G01Y1731341D01*
G02X1556371Y1731644I303J0D01*
G37*
G36*
G01X1576056D02*
X1579756D01*
G02X1580058Y1731341I-1J-303D01*
G01Y1721335D01*
G02X1579756Y1721032I-302J-1D01*
G01X1576056D01*
G02X1575754Y1721335I1J303D01*
G01Y1723739D01*
G02X1575740Y1723976I2002J237D01*
G02X1575754Y1724213I2016J0D01*
G01Y1728463D01*
G02X1575740Y1728700I2002J237D01*
G02X1575754Y1728937I2016J0D01*
G01Y1731341D01*
G02X1576056Y1731644I302J1D01*
G37*
G36*
G01X1591804D02*
X1595504D01*
G02X1595806Y1731341I-1J-303D01*
G01Y1721335D01*
G02X1595504Y1721032I-302J-1D01*
G01X1591804D01*
G02X1591502Y1721335I1J303D01*
G01Y1723739D01*
G02X1591488Y1723976I2002J237D01*
G02X1591502Y1724213I2016J0D01*
G01Y1728463D01*
G02X1591488Y1728700I2002J237D01*
G02X1591502Y1728937I2016J0D01*
G01Y1731341D01*
G02X1591804Y1731644I302J1D01*
G37*
G36*
G01X1607552D02*
X1611252D01*
G02X1611554Y1731341I-1J-303D01*
G01Y1721335D01*
G02X1611252Y1721032I-302J-1D01*
G01X1607552D01*
G02X1607250Y1721335I1J303D01*
G01Y1723739D01*
G02X1607236Y1723976I2002J237D01*
G02X1607250Y1724213I2016J0D01*
G01Y1728463D01*
G02X1607236Y1728700I2002J237D01*
G02X1607250Y1728937I2016J0D01*
G01Y1731341D01*
G02X1607552Y1731644I302J1D01*
G37*
G36*
G01X1623300D02*
X1627000D01*
G02X1627302Y1731341I-1J-303D01*
G01Y1721335D01*
G02X1627000Y1721032I-302J-1D01*
G01X1623300D01*
G02X1622998Y1721335I1J303D01*
G01Y1723739D01*
G02X1622984Y1723976I2002J237D01*
G02X1622998Y1724213I2016J0D01*
G01Y1728463D01*
G02X1622984Y1728700I2002J237D01*
G02X1622998Y1728937I2016J0D01*
G01Y1731341D01*
G02X1623300Y1731644I302J1D01*
G37*
G36*
G01X105651Y1575002D02*
X102251D01*
G02Y1578006I0J1502D01*
G01X105651D01*
G02Y1575002I0J-1502D01*
G37*
G36*
G01X74218Y1574006D02*
X77618D01*
G02Y1571002I0J-1502D01*
G01X74218D01*
G02Y1574006I0J1502D01*
G37*
G36*
G01X76369Y1508958D02*
X79769D01*
G02Y1505954I0J-1502D01*
G01X76369D01*
G02Y1508958I0J1502D01*
G37*
G36*
G01X391330Y1583652D02*
X387930D01*
G02Y1586658I0J1503D01*
G01X391330D01*
G02Y1583652I0J-1503D01*
G37*
G36*
G01X148938Y1515872D02*
X145538D01*
G02Y1518876I0J1502D01*
G01X148938D01*
G02Y1515872I0J-1502D01*
G37*
G36*
G01X164710Y1519516D02*
X168110D01*
G02Y1516512I0J-1502D01*
G01X164710D01*
G02Y1519516I0J1502D01*
G37*
G36*
G01X89264Y1509114D02*
X92664D01*
G02Y1506108I0J-1503D01*
G01X89264D01*
G02Y1509114I0J1503D01*
G37*
G36*
G01X167266Y1571470D02*
X170666D01*
G02Y1568466I0J-1502D01*
G01X167266D01*
G02Y1571470I0J1502D01*
G37*
G36*
G01X1346792Y1615794D02*
X1350192D01*
G02Y1612790I0J-1502D01*
G01X1346792D01*
G02Y1615794I0J1502D01*
G37*
G36*
G01X1358852D02*
X1362252D01*
G02Y1612790I0J-1502D01*
G01X1358852D01*
G02Y1615794I0J1502D01*
G37*
G36*
G01X1365612Y1591596D02*
X1369012D01*
G02Y1588592I0J-1502D01*
G01X1365612D01*
G02Y1591596I0J1502D01*
G37*
G36*
G01Y1579684D02*
X1369012D01*
G02Y1576680I0J-1502D01*
G01X1365612D01*
G02Y1579684I0J1502D01*
G37*
G36*
G01X1305312D02*
X1308712D01*
G02Y1576680I0J-1502D01*
G01X1305312D01*
G02Y1579684I0J1502D01*
G37*
G36*
G01X1293252Y1591596D02*
X1296652D01*
G02Y1588592I0J-1502D01*
G01X1293252D01*
G02Y1591596I0J1502D01*
G37*
G36*
G01X1310612Y1615794D02*
X1314012D01*
G02Y1612790I0J-1502D01*
G01X1310612D01*
G02Y1615794I0J1502D01*
G37*
G36*
G01X1262372Y1603882D02*
X1265772D01*
G02Y1600878I0J-1502D01*
G01X1262372D01*
G02Y1603882I0J1502D01*
G37*
G36*
G01X1286492Y1615794D02*
X1289892D01*
G02Y1612790I0J-1502D01*
G01X1286492D01*
G02Y1615794I0J1502D01*
G37*
G36*
G01X1262372D02*
X1265772D01*
G02Y1612790I0J-1502D01*
G01X1262372D01*
G02Y1615794I0J1502D01*
G37*
G36*
G01X1334732Y1603882D02*
X1338132D01*
G02Y1600878I0J-1502D01*
G01X1334732D01*
G02Y1603882I0J1502D01*
G37*
G36*
G01X1220892Y1579684D02*
X1224292D01*
G02Y1576680I0J-1502D01*
G01X1220892D01*
G02Y1579684I0J1502D01*
G37*
G36*
G01X1334732Y1615794D02*
X1338132D01*
G02Y1612790I0J-1502D01*
G01X1334732D01*
G02Y1615794I0J1502D01*
G37*
G36*
G01X1370912Y1603882D02*
X1374312D01*
G02Y1600878I0J-1502D01*
G01X1370912D01*
G02Y1603882I0J1502D01*
G37*
G36*
G01X1214132D02*
X1217532D01*
G02Y1600878I0J-1502D01*
G01X1214132D01*
G02Y1603882I0J1502D01*
G37*
G36*
G01X1286492D02*
X1289892D01*
G02Y1600878I0J-1502D01*
G01X1286492D01*
G02Y1603882I0J1502D01*
G37*
G36*
G01X1298552D02*
X1301952D01*
G02Y1600878I0J-1502D01*
G01X1298552D01*
G02Y1603882I0J1502D01*
G37*
G36*
G01X1353552Y1579684D02*
X1356952D01*
G02Y1576680I0J-1502D01*
G01X1353552D01*
G02Y1579684I0J1502D01*
G37*
G36*
G01X1341492Y1591596D02*
X1344892D01*
G02Y1588592I0J-1502D01*
G01X1341492D01*
G02Y1591596I0J1502D01*
G37*
G36*
G01X1370912Y1615794D02*
X1374312D01*
G02Y1612790I0J-1502D01*
G01X1370912D01*
G02Y1615794I0J1502D01*
G37*
G36*
G01X1269132Y1591596D02*
X1272532D01*
G02Y1588592I0J-1502D01*
G01X1269132D01*
G02Y1591596I0J1502D01*
G37*
G36*
G01X1238252Y1603882D02*
X1241652D01*
G02Y1600878I0J-1502D01*
G01X1238252D01*
G02Y1603882I0J1502D01*
G37*
G36*
G01X1353552Y1591596D02*
X1356952D01*
G02Y1588592I0J-1502D01*
G01X1353552D01*
G02Y1591596I0J1502D01*
G37*
G36*
G01X1214132Y1615794D02*
X1217532D01*
G02Y1612790I0J-1502D01*
G01X1214132D01*
G02Y1615794I0J1502D01*
G37*
G36*
G01X1226192Y1603882D02*
X1229592D01*
G02Y1600878I0J-1502D01*
G01X1226192D01*
G02Y1603882I0J1502D01*
G37*
G36*
G01X1208832Y1579684D02*
X1212232D01*
G02Y1576680I0J-1502D01*
G01X1208832D01*
G02Y1579684I0J1502D01*
G37*
G36*
G01Y1591596D02*
X1212232D01*
G02Y1588592I0J-1502D01*
G01X1208832D01*
G02Y1591596I0J1502D01*
G37*
G36*
G01X1341492Y1579684D02*
X1344892D01*
G02Y1576680I0J-1502D01*
G01X1341492D01*
G02Y1579684I0J1502D01*
G37*
G36*
G01X1250312Y1615794D02*
X1253712D01*
G02Y1612790I0J-1502D01*
G01X1250312D01*
G02Y1615794I0J1502D01*
G37*
G36*
G01X1232952Y1579684D02*
X1236352D01*
G02Y1576680I0J-1502D01*
G01X1232952D01*
G02Y1579684I0J1502D01*
G37*
G36*
G01Y1591596D02*
X1236352D01*
G02Y1588592I0J-1502D01*
G01X1232952D01*
G02Y1591596I0J1502D01*
G37*
G36*
G01X1196772Y1579684D02*
X1200172D01*
G02Y1576680I0J-1502D01*
G01X1196772D01*
G02Y1579684I0J1502D01*
G37*
G36*
G01X1257072D02*
X1260472D01*
G02Y1576680I0J-1502D01*
G01X1257072D01*
G02Y1579684I0J1502D01*
G37*
G36*
G01X1220892Y1591596D02*
X1224292D01*
G02Y1588592I0J-1502D01*
G01X1220892D01*
G02Y1591596I0J1502D01*
G37*
G36*
G01X1269132Y1579684D02*
X1272532D01*
G02Y1576680I0J-1502D01*
G01X1269132D01*
G02Y1579684I0J1502D01*
G37*
G36*
G01X1305312Y1591596D02*
X1308712D01*
G02Y1588592I0J-1502D01*
G01X1305312D01*
G02Y1591596I0J1502D01*
G37*
G36*
G01X1245012D02*
X1248412D01*
G02Y1588592I0J-1502D01*
G01X1245012D01*
G02Y1591596I0J1502D01*
G37*
G36*
G01X1250312Y1603882D02*
X1253712D01*
G02Y1600878I0J-1502D01*
G01X1250312D01*
G02Y1603882I0J1502D01*
G37*
G36*
G01X1317372Y1579684D02*
X1320772D01*
G02Y1576680I0J-1502D01*
G01X1317372D01*
G02Y1579684I0J1502D01*
G37*
G36*
G01X1358852Y1603882D02*
X1362252D01*
G02Y1600878I0J-1502D01*
G01X1358852D01*
G02Y1603882I0J1502D01*
G37*
G36*
G01X1202072D02*
X1205472D01*
G02Y1600878I0J-1502D01*
G01X1202072D01*
G02Y1603882I0J1502D01*
G37*
G36*
G01Y1615794D02*
X1205472D01*
G02Y1612790I0J-1502D01*
G01X1202072D01*
G02Y1615794I0J1502D01*
G37*
G36*
G01X1322672Y1603882D02*
X1326072D01*
G02Y1600878I0J-1502D01*
G01X1322672D01*
G02Y1603882I0J1502D01*
G37*
G36*
G01X1310612D02*
X1314012D01*
G02Y1600878I0J-1502D01*
G01X1310612D01*
G02Y1603882I0J1502D01*
G37*
G36*
G01X1274432Y1615794D02*
X1277832D01*
G02Y1612790I0J-1502D01*
G01X1274432D01*
G02Y1615794I0J1502D01*
G37*
G36*
G01X1329432Y1579684D02*
X1332832D01*
G02Y1576680I0J-1502D01*
G01X1329432D01*
G02Y1579684I0J1502D01*
G37*
G36*
G01X1346792Y1603882D02*
X1350192D01*
G02Y1600878I0J-1502D01*
G01X1346792D01*
G02Y1603882I0J1502D01*
G37*
G36*
G01X1317372Y1591596D02*
X1320772D01*
G02Y1588592I0J-1502D01*
G01X1317372D01*
G02Y1591596I0J1502D01*
G37*
G36*
G01X1329432D02*
X1332832D01*
G02Y1588592I0J-1502D01*
G01X1329432D01*
G02Y1591596I0J1502D01*
G37*
G36*
G01X1322672Y1615794D02*
X1326072D01*
G02Y1612790I0J-1502D01*
G01X1322672D01*
G02Y1615794I0J1502D01*
G37*
G36*
G01X1281192Y1591596D02*
X1284592D01*
G02Y1588592I0J-1502D01*
G01X1281192D01*
G02Y1591596I0J1502D01*
G37*
G36*
G01X1196772D02*
X1200172D01*
G02Y1588592I0J-1502D01*
G01X1196772D01*
G02Y1591596I0J1502D01*
G37*
G36*
G01X1226192Y1615794D02*
X1229592D01*
G02Y1612790I0J-1502D01*
G01X1226192D01*
G02Y1615794I0J1502D01*
G37*
G36*
G01X1293252Y1579684D02*
X1296652D01*
G02Y1576680I0J-1502D01*
G01X1293252D01*
G02Y1579684I0J1502D01*
G37*
G36*
G01X1298552Y1615794D02*
X1301952D01*
G02Y1612790I0J-1502D01*
G01X1298552D01*
G02Y1615794I0J1502D01*
G37*
G36*
G01X1281192Y1579684D02*
X1284592D01*
G02Y1576680I0J-1502D01*
G01X1281192D01*
G02Y1579684I0J1502D01*
G37*
G36*
G01X1245012D02*
X1248412D01*
G02Y1576680I0J-1502D01*
G01X1245012D01*
G02Y1579684I0J1502D01*
G37*
G36*
G01X1257072Y1591596D02*
X1260472D01*
G02Y1588592I0J-1502D01*
G01X1257072D01*
G02Y1591596I0J1502D01*
G37*
G36*
G01X1274432Y1603882D02*
X1277832D01*
G02Y1600878I0J-1502D01*
G01X1274432D01*
G02Y1603882I0J1502D01*
G37*
G36*
G01X1238252Y1615794D02*
X1241652D01*
G02Y1612790I0J-1502D01*
G01X1238252D01*
G02Y1615794I0J1502D01*
G37*
G36*
G01X146312Y1571028D02*
X149712D01*
G02Y1568022I0J-1503D01*
G01X146312D01*
G02Y1571028I0J1503D01*
G37*
G36*
G01X1701934Y76800D02*
X1705334D01*
G02Y73794I0J-1503D01*
G01X1701934D01*
G02Y76800I0J1503D01*
G37*
G36*
G01X1690934Y70800D02*
X1694334D01*
G02Y67794I0J-1503D01*
G01X1690934D01*
G02Y70800I0J1503D01*
G37*
G36*
G01X1679934Y76800D02*
X1683334D01*
G02Y73794I0J-1503D01*
G01X1679934D01*
G02Y76800I0J1503D01*
G37*
G36*
G01X1657800D02*
X1661200D01*
G02Y73794I0J-1503D01*
G01X1657800D01*
G02Y76800I0J1503D01*
G37*
G36*
G01X1668800Y70800D02*
X1672200D01*
G02Y67794I0J-1503D01*
G01X1668800D01*
G02Y70800I0J1503D01*
G37*
G36*
G01X1646800D02*
X1650200D01*
G02Y67794I0J-1503D01*
G01X1646800D01*
G02Y70800I0J1503D01*
G37*
G36*
G01X1635800Y76800D02*
X1639200D01*
G02Y73794I0J-1503D01*
G01X1635800D01*
G02Y76800I0J1503D01*
G37*
G36*
G01X1612596D02*
X1615996D01*
G02Y73794I0J-1503D01*
G01X1612596D01*
G02Y76800I0J1503D01*
G37*
G36*
G01X1623596Y70800D02*
X1626996D01*
G02Y67794I0J-1503D01*
G01X1623596D01*
G02Y70800I0J1503D01*
G37*
G36*
G01X1601596D02*
X1604996D01*
G02Y67794I0J-1503D01*
G01X1601596D01*
G02Y70800I0J1503D01*
G37*
G36*
G01X1590596Y76800D02*
X1593996D01*
G02Y73794I0J-1503D01*
G01X1590596D01*
G02Y76800I0J1503D01*
G37*
G36*
G01X1579596Y70800D02*
X1582996D01*
G02Y67794I0J-1503D01*
G01X1579596D01*
G02Y70800I0J1503D01*
G37*
G36*
G01X1568596Y76800D02*
X1571996D01*
G02Y73794I0J-1503D01*
G01X1568596D01*
G02Y76800I0J1503D01*
G37*
G36*
G01X1546596D02*
X1549996D01*
G02Y73794I0J-1503D01*
G01X1546596D01*
G02Y76800I0J1503D01*
G37*
G36*
G01X1557596Y70800D02*
X1560996D01*
G02Y67794I0J-1503D01*
G01X1557596D01*
G02Y70800I0J1503D01*
G37*
G36*
G01X1535596D02*
X1538996D01*
G02Y67794I0J-1503D01*
G01X1535596D01*
G02Y70800I0J1503D01*
G37*
G36*
G01X230895Y73838D02*
X227495D01*
G02Y76842I0J1502D01*
G01X230895D01*
G02Y73838I0J-1502D01*
G37*
G36*
G01X219895Y67838D02*
X216495D01*
G02Y70842I0J1502D01*
G01X219895D01*
G02Y67838I0J-1502D01*
G37*
G36*
G01X208895Y73838D02*
X205495D01*
G02Y76842I0J1502D01*
G01X208895D01*
G02Y73838I0J-1502D01*
G37*
G36*
G01X194361Y70842D02*
X197761D01*
G02Y67838I0J-1502D01*
G01X194361D01*
G02Y70842I0J1502D01*
G37*
G36*
G01X183361Y76842D02*
X186761D01*
G02Y73838I0J-1502D01*
G01X183361D01*
G02Y76842I0J1502D01*
G37*
G36*
G01X161361D02*
X164761D01*
G02Y73838I0J-1502D01*
G01X161361D01*
G02Y76842I0J1502D01*
G37*
G36*
G01X172361Y70842D02*
X175761D01*
G02Y67838I0J-1502D01*
G01X172361D01*
G02Y70842I0J1502D01*
G37*
G36*
G01X149157D02*
X152557D01*
G02Y67838I0J-1502D01*
G01X149157D01*
G02Y70842I0J1502D01*
G37*
G36*
G01X138157Y76842D02*
X141557D01*
G02Y73838I0J-1502D01*
G01X138157D01*
G02Y76842I0J1502D01*
G37*
G36*
G01X116157D02*
X119557D01*
G02Y73838I0J-1502D01*
G01X116157D01*
G02Y76842I0J1502D01*
G37*
G36*
G01X127157Y70842D02*
X130557D01*
G02Y67838I0J-1502D01*
G01X127157D01*
G02Y70842I0J1502D01*
G37*
G36*
G01X105157D02*
X108557D01*
G02Y67838I0J-1502D01*
G01X105157D01*
G02Y70842I0J1502D01*
G37*
G36*
G01X94157Y76842D02*
X97557D01*
G02Y73838I0J-1502D01*
G01X94157D01*
G02Y76842I0J1502D01*
G37*
G36*
G01X83157Y70842D02*
X86557D01*
G02Y67838I0J-1502D01*
G01X83157D01*
G02Y70842I0J1502D01*
G37*
G36*
G01X72157Y76842D02*
X75557D01*
G02Y73838I0J-1502D01*
G01X72157D01*
G02Y76842I0J1502D01*
G37*
G36*
G01X61157Y70842D02*
X64557D01*
G02Y67838I0J-1502D01*
G01X61157D01*
G02Y70842I0J1502D01*
G37*
G36*
G01X1619075Y1579684D02*
X1622475D01*
G02Y1576680I0J-1502D01*
G01X1619075D01*
G02Y1579684I0J1502D01*
G37*
G36*
G01X326857Y1603882D02*
X330257D01*
G02Y1600878I0J-1502D01*
G01X326857D01*
G02Y1603882I0J1502D01*
G37*
G36*
G01X363037Y1615794D02*
X366437D01*
G02Y1612790I0J-1502D01*
G01X363037D01*
G02Y1615794I0J1502D01*
G37*
G36*
G01X545411Y1579684D02*
X548811D01*
G02Y1576680I0J-1502D01*
G01X545411D01*
G02Y1579684I0J1502D01*
G37*
G36*
G01Y1591596D02*
X548811D01*
G02Y1588592I0J-1502D01*
G01X545411D01*
G02Y1591596I0J1502D01*
G37*
G36*
G01X1377672D02*
X1381072D01*
G02Y1588592I0J-1502D01*
G01X1377672D01*
G02Y1591596I0J1502D01*
G37*
G36*
G01X533351D02*
X536751D01*
G02Y1588592I0J-1502D01*
G01X533351D01*
G02Y1591596I0J1502D01*
G37*
G36*
G01Y1579684D02*
X536751D01*
G02Y1576680I0J-1502D01*
G01X533351D01*
G02Y1579684I0J1502D01*
G37*
G36*
G01X1594955Y1591596D02*
X1598355D01*
G02Y1588592I0J-1502D01*
G01X1594955D01*
G02Y1591596I0J1502D01*
G37*
G36*
G01X581591D02*
X584991D01*
G02Y1588592I0J-1502D01*
G01X581591D01*
G02Y1591596I0J1502D01*
G37*
G36*
G01Y1579684D02*
X584991D01*
G02Y1576680I0J-1502D01*
G01X581591D01*
G02Y1579684I0J1502D01*
G37*
G36*
G01X1594955D02*
X1598355D01*
G02Y1576680I0J-1502D01*
G01X1594955D01*
G02Y1579684I0J1502D01*
G37*
G36*
G01X605711Y1591596D02*
X609111D01*
G02Y1588592I0J-1502D01*
G01X605711D01*
G02Y1591596I0J1502D01*
G37*
G36*
G01X333617Y1579684D02*
X337017D01*
G02Y1576680I0J-1502D01*
G01X333617D01*
G02Y1579684I0J1502D01*
G37*
G36*
G01X345677D02*
X349077D01*
G02Y1576680I0J-1502D01*
G01X345677D01*
G02Y1579684I0J1502D01*
G37*
G36*
G01X617771D02*
X621171D01*
G02Y1576680I0J-1502D01*
G01X617771D01*
G02Y1579684I0J1502D01*
G37*
G36*
G01Y1591596D02*
X621171D01*
G02Y1588592I0J-1502D01*
G01X617771D01*
G02Y1591596I0J1502D01*
G37*
G36*
G01X629831Y1579684D02*
X633231D01*
G02Y1576680I0J-1502D01*
G01X629831D01*
G02Y1579684I0J1502D01*
G37*
G36*
G01X1582895D02*
X1586295D01*
G02Y1576680I0J-1502D01*
G01X1582895D01*
G02Y1579684I0J1502D01*
G37*
G36*
G01X1570835D02*
X1574235D01*
G02Y1576680I0J-1502D01*
G01X1570835D01*
G02Y1579684I0J1502D01*
G37*
G36*
G01X1558775D02*
X1562175D01*
G02Y1576680I0J-1502D01*
G01X1558775D01*
G02Y1579684I0J1502D01*
G37*
G36*
G01X321557D02*
X324957D01*
G02Y1576680I0J-1502D01*
G01X321557D01*
G02Y1579684I0J1502D01*
G37*
G36*
G01X278617Y1603882D02*
X282017D01*
G02Y1600878I0J-1502D01*
G01X278617D01*
G02Y1603882I0J1502D01*
G37*
G36*
G01X1534655Y1591596D02*
X1538055D01*
G02Y1588592I0J-1502D01*
G01X1534655D01*
G02Y1591596I0J1502D01*
G37*
G36*
G01Y1579684D02*
X1538055D01*
G02Y1576680I0J-1502D01*
G01X1534655D01*
G02Y1579684I0J1502D01*
G37*
G36*
G01X1510535Y1591596D02*
X1513935D01*
G02Y1588592I0J-1502D01*
G01X1510535D01*
G02Y1591596I0J1502D01*
G37*
G36*
G01X1522595D02*
X1525995D01*
G02Y1588592I0J-1502D01*
G01X1522595D01*
G02Y1591596I0J1502D01*
G37*
G36*
G01X309497Y1579684D02*
X312897D01*
G02Y1576680I0J-1502D01*
G01X309497D01*
G02Y1579684I0J1502D01*
G37*
G36*
G01X302737Y1603882D02*
X306137D01*
G02Y1600878I0J-1502D01*
G01X302737D01*
G02Y1603882I0J1502D01*
G37*
G36*
G01X1498475Y1579684D02*
X1501875D01*
G02Y1576680I0J-1502D01*
G01X1498475D01*
G02Y1579684I0J1502D01*
G37*
G36*
G01X314797Y1615794D02*
X318197D01*
G02Y1612790I0J-1502D01*
G01X314797D01*
G02Y1615794I0J1502D01*
G37*
G36*
G01X278617D02*
X282017D01*
G02Y1612790I0J-1502D01*
G01X278617D01*
G02Y1615794I0J1502D01*
G37*
G36*
G01X497171Y1591596D02*
X500571D01*
G02Y1588592I0J-1502D01*
G01X497171D01*
G02Y1591596I0J1502D01*
G37*
G36*
G01X509231D02*
X512631D01*
G02Y1588592I0J-1502D01*
G01X509231D01*
G02Y1591596I0J1502D01*
G37*
G36*
G01Y1579684D02*
X512631D01*
G02Y1576680I0J-1502D01*
G01X509231D01*
G02Y1579684I0J1502D01*
G37*
G36*
G01X1486415Y1591596D02*
X1489815D01*
G02Y1588592I0J-1502D01*
G01X1486415D01*
G02Y1591596I0J1502D01*
G37*
G36*
G01Y1579684D02*
X1489815D01*
G02Y1576680I0J-1502D01*
G01X1486415D01*
G02Y1579684I0J1502D01*
G37*
G36*
G01X321557Y1591596D02*
X324957D01*
G02Y1588592I0J-1502D01*
G01X321557D01*
G02Y1591596I0J1502D01*
G37*
G36*
G01X1462295D02*
X1465695D01*
G02Y1588592I0J-1502D01*
G01X1462295D01*
G02Y1591596I0J1502D01*
G37*
G36*
G01X1474355D02*
X1477755D01*
G02Y1588592I0J-1502D01*
G01X1474355D01*
G02Y1591596I0J1502D01*
G37*
G36*
G01X641891Y1579684D02*
X645291D01*
G02Y1576680I0J-1502D01*
G01X641891D01*
G02Y1579684I0J1502D01*
G37*
G36*
G01Y1591596D02*
X645291D01*
G02Y1588592I0J-1502D01*
G01X641891D01*
G02Y1591596I0J1502D01*
G37*
G36*
G01X285377Y1579684D02*
X288777D01*
G02Y1576680I0J-1502D01*
G01X285377D01*
G02Y1579684I0J1502D01*
G37*
G36*
G01X1462295D02*
X1465695D01*
G02Y1576680I0J-1502D01*
G01X1462295D01*
G02Y1579684I0J1502D01*
G37*
G36*
G01X206257Y1615794D02*
X209657D01*
G02Y1612790I0J-1502D01*
G01X206257D01*
G02Y1615794I0J1502D01*
G37*
G36*
G01X338917D02*
X342317D01*
G02Y1612790I0J-1502D01*
G01X338917D01*
G02Y1615794I0J1502D01*
G37*
G36*
G01X1474355Y1579684D02*
X1477755D01*
G02Y1576680I0J-1502D01*
G01X1474355D01*
G02Y1579684I0J1502D01*
G37*
G36*
G01X261257D02*
X264657D01*
G02Y1576680I0J-1502D01*
G01X261257D01*
G02Y1579684I0J1502D01*
G37*
G36*
G01X485111D02*
X488511D01*
G02Y1576680I0J-1502D01*
G01X485111D01*
G02Y1579684I0J1502D01*
G37*
G36*
G01Y1591596D02*
X488511D01*
G02Y1588592I0J-1502D01*
G01X485111D01*
G02Y1591596I0J1502D01*
G37*
G36*
G01X338917Y1603882D02*
X342317D01*
G02Y1600878I0J-1502D01*
G01X338917D01*
G02Y1603882I0J1502D01*
G37*
G36*
G01X1648495Y1615794D02*
X1651895D01*
G02Y1612790I0J-1502D01*
G01X1648495D01*
G02Y1615794I0J1502D01*
G37*
G36*
G01Y1603882D02*
X1651895D01*
G02Y1600878I0J-1502D01*
G01X1648495D01*
G02Y1603882I0J1502D01*
G37*
G36*
G01X1624375Y1615794D02*
X1627775D01*
G02Y1612790I0J-1502D01*
G01X1624375D01*
G02Y1615794I0J1502D01*
G37*
G36*
G01X266557D02*
X269957D01*
G02Y1612790I0J-1502D01*
G01X266557D01*
G02Y1615794I0J1502D01*
G37*
G36*
G01X254497Y1603882D02*
X257897D01*
G02Y1600878I0J-1502D01*
G01X254497D01*
G02Y1603882I0J1502D01*
G37*
G36*
G01X653951Y1591596D02*
X657351D01*
G02Y1588592I0J-1502D01*
G01X653951D01*
G02Y1591596I0J1502D01*
G37*
G36*
G01Y1579684D02*
X657351D01*
G02Y1576680I0J-1502D01*
G01X653951D01*
G02Y1579684I0J1502D01*
G37*
G36*
G01X369797Y1591596D02*
X373197D01*
G02Y1588592I0J-1502D01*
G01X369797D01*
G02Y1591596I0J1502D01*
G37*
G36*
G01X1636435Y1603882D02*
X1639835D01*
G02Y1600878I0J-1502D01*
G01X1636435D01*
G02Y1603882I0J1502D01*
G37*
G36*
G01X266557D02*
X269957D01*
G02Y1600878I0J-1502D01*
G01X266557D01*
G02Y1603882I0J1502D01*
G37*
G36*
G01X1624375D02*
X1627775D01*
G02Y1600878I0J-1502D01*
G01X1624375D01*
G02Y1603882I0J1502D01*
G37*
G36*
G01X254497Y1615794D02*
X257897D01*
G02Y1612790I0J-1502D01*
G01X254497D01*
G02Y1615794I0J1502D01*
G37*
G36*
G01X194197Y1603882D02*
X197597D01*
G02Y1600878I0J-1502D01*
G01X194197D01*
G02Y1603882I0J1502D01*
G37*
G36*
G01X242437D02*
X245837D01*
G02Y1600878I0J-1502D01*
G01X242437D01*
G02Y1603882I0J1502D01*
G37*
G36*
G01X1612315D02*
X1615715D01*
G02Y1600878I0J-1502D01*
G01X1612315D01*
G02Y1603882I0J1502D01*
G37*
G36*
G01Y1615794D02*
X1615715D01*
G02Y1612790I0J-1502D01*
G01X1612315D01*
G02Y1615794I0J1502D01*
G37*
G36*
G01X230377D02*
X233777D01*
G02Y1612790I0J-1502D01*
G01X230377D01*
G02Y1615794I0J1502D01*
G37*
G36*
G01X521291Y1579684D02*
X524691D01*
G02Y1576680I0J-1502D01*
G01X521291D01*
G02Y1579684I0J1502D01*
G37*
G36*
G01Y1591596D02*
X524691D01*
G02Y1588592I0J-1502D01*
G01X521291D01*
G02Y1591596I0J1502D01*
G37*
G36*
G01X497171Y1579684D02*
X500571D01*
G02Y1576680I0J-1502D01*
G01X497171D01*
G02Y1579684I0J1502D01*
G37*
G36*
G01X593651D02*
X597051D01*
G02Y1576680I0J-1502D01*
G01X593651D01*
G02Y1579684I0J1502D01*
G37*
G36*
G01Y1591596D02*
X597051D01*
G02Y1588592I0J-1502D01*
G01X593651D01*
G02Y1591596I0J1502D01*
G37*
G36*
G01X1600255Y1603882D02*
X1603655D01*
G02Y1600878I0J-1502D01*
G01X1600255D01*
G02Y1603882I0J1502D01*
G37*
G36*
G01Y1615794D02*
X1603655D01*
G02Y1612790I0J-1502D01*
G01X1600255D01*
G02Y1615794I0J1502D01*
G37*
G36*
G01X557471Y1579684D02*
X560871D01*
G02Y1576680I0J-1502D01*
G01X557471D01*
G02Y1579684I0J1502D01*
G37*
G36*
G01X569531D02*
X572931D01*
G02Y1576680I0J-1502D01*
G01X569531D01*
G02Y1579684I0J1502D01*
G37*
G36*
G01Y1591596D02*
X572931D01*
G02Y1588592I0J-1502D01*
G01X569531D01*
G02Y1591596I0J1502D01*
G37*
G36*
G01X557471D02*
X560871D01*
G02Y1588592I0J-1502D01*
G01X557471D01*
G02Y1591596I0J1502D01*
G37*
G36*
G01X333617D02*
X337017D01*
G02Y1588592I0J-1502D01*
G01X333617D01*
G02Y1591596I0J1502D01*
G37*
G36*
G01X345677D02*
X349077D01*
G02Y1588592I0J-1502D01*
G01X345677D01*
G02Y1591596I0J1502D01*
G37*
G36*
G01X1607015Y1579684D02*
X1610415D01*
G02Y1576680I0J-1502D01*
G01X1607015D01*
G02Y1579684I0J1502D01*
G37*
G36*
G01X1576135Y1615794D02*
X1579535D01*
G02Y1612790I0J-1502D01*
G01X1576135D01*
G02Y1615794I0J1502D01*
G37*
G36*
G01X314797Y1603882D02*
X318197D01*
G02Y1600878I0J-1502D01*
G01X314797D01*
G02Y1603882I0J1502D01*
G37*
G36*
G01X1576135D02*
X1579535D01*
G02Y1600878I0J-1502D01*
G01X1576135D01*
G02Y1603882I0J1502D01*
G37*
G36*
G01X261257Y1591596D02*
X264657D01*
G02Y1588592I0J-1502D01*
G01X261257D01*
G02Y1591596I0J1502D01*
G37*
G36*
G01X357737Y1579684D02*
X361137D01*
G02Y1576680I0J-1502D01*
G01X357737D01*
G02Y1579684I0J1502D01*
G37*
G36*
G01X1546715Y1591596D02*
X1550115D01*
G02Y1588592I0J-1502D01*
G01X1546715D01*
G02Y1591596I0J1502D01*
G37*
G36*
G01Y1579684D02*
X1550115D01*
G02Y1576680I0J-1502D01*
G01X1546715D01*
G02Y1579684I0J1502D01*
G37*
G36*
G01X326857Y1615794D02*
X330257D01*
G02Y1612790I0J-1502D01*
G01X326857D01*
G02Y1615794I0J1502D01*
G37*
G36*
G01X249197Y1591596D02*
X252597D01*
G02Y1588592I0J-1502D01*
G01X249197D01*
G02Y1591596I0J1502D01*
G37*
G36*
G01X309497D02*
X312897D01*
G02Y1588592I0J-1502D01*
G01X309497D01*
G02Y1591596I0J1502D01*
G37*
G36*
G01X1564075Y1603882D02*
X1567475D01*
G02Y1600878I0J-1502D01*
G01X1564075D01*
G02Y1603882I0J1502D01*
G37*
G36*
G01Y1615794D02*
X1567475D01*
G02Y1612790I0J-1502D01*
G01X1564075D01*
G02Y1615794I0J1502D01*
G37*
G36*
G01X1552015D02*
X1555415D01*
G02Y1612790I0J-1502D01*
G01X1552015D01*
G02Y1615794I0J1502D01*
G37*
G36*
G01X1503775D02*
X1507175D01*
G02Y1612790I0J-1502D01*
G01X1503775D01*
G02Y1615794I0J1502D01*
G37*
G36*
G01X1552015Y1603882D02*
X1555415D01*
G02Y1600878I0J-1502D01*
G01X1552015D01*
G02Y1603882I0J1502D01*
G37*
G36*
G01X629831Y1591596D02*
X633231D01*
G02Y1588592I0J-1502D01*
G01X629831D01*
G02Y1591596I0J1502D01*
G37*
G36*
G01X1377672Y1579684D02*
X1381072D01*
G02Y1576680I0J-1502D01*
G01X1377672D01*
G02Y1579684I0J1502D01*
G37*
G36*
G01X218317Y1603882D02*
X221717D01*
G02Y1600878I0J-1502D01*
G01X218317D01*
G02Y1603882I0J1502D01*
G37*
G36*
G01X206257D02*
X209657D01*
G02Y1600878I0J-1502D01*
G01X206257D01*
G02Y1603882I0J1502D01*
G37*
G36*
G01X1527895Y1615794D02*
X1531295D01*
G02Y1612790I0J-1502D01*
G01X1527895D01*
G02Y1615794I0J1502D01*
G37*
G36*
G01X200957Y1591596D02*
X204357D01*
G02Y1588592I0J-1502D01*
G01X200957D01*
G02Y1591596I0J1502D01*
G37*
G36*
G01X1631135D02*
X1634535D01*
G02Y1588592I0J-1502D01*
G01X1631135D01*
G02Y1591596I0J1502D01*
G37*
G36*
G01X1539955Y1615794D02*
X1543355D01*
G02Y1612790I0J-1502D01*
G01X1539955D01*
G02Y1615794I0J1502D01*
G37*
G36*
G01Y1603882D02*
X1543355D01*
G02Y1600878I0J-1502D01*
G01X1539955D01*
G02Y1603882I0J1502D01*
G37*
G36*
G01X1527895D02*
X1531295D01*
G02Y1600878I0J-1502D01*
G01X1527895D01*
G02Y1603882I0J1502D01*
G37*
G36*
G01X302737Y1615794D02*
X306137D01*
G02Y1612790I0J-1502D01*
G01X302737D01*
G02Y1615794I0J1502D01*
G37*
G36*
G01X1522595Y1579684D02*
X1525995D01*
G02Y1576680I0J-1502D01*
G01X1522595D01*
G02Y1579684I0J1502D01*
G37*
G36*
G01X1515835Y1615794D02*
X1519235D01*
G02Y1612790I0J-1502D01*
G01X1515835D01*
G02Y1615794I0J1502D01*
G37*
G36*
G01X1636435D02*
X1639835D01*
G02Y1612790I0J-1502D01*
G01X1636435D01*
G02Y1615794I0J1502D01*
G37*
G36*
G01X1498475Y1591596D02*
X1501875D01*
G02Y1588592I0J-1502D01*
G01X1498475D01*
G02Y1591596I0J1502D01*
G37*
G36*
G01X1643195D02*
X1646595D01*
G02Y1588592I0J-1502D01*
G01X1643195D01*
G02Y1591596I0J1502D01*
G37*
G36*
G01X1515835Y1603882D02*
X1519235D01*
G02Y1600878I0J-1502D01*
G01X1515835D01*
G02Y1603882I0J1502D01*
G37*
G36*
G01X357737Y1591596D02*
X361137D01*
G02Y1588592I0J-1502D01*
G01X357737D01*
G02Y1591596I0J1502D01*
G37*
G36*
G01X194197Y1615794D02*
X197597D01*
G02Y1612790I0J-1502D01*
G01X194197D01*
G02Y1615794I0J1502D01*
G37*
G36*
G01X1510535Y1579684D02*
X1513935D01*
G02Y1576680I0J-1502D01*
G01X1510535D01*
G02Y1579684I0J1502D01*
G37*
G36*
G01X1570835Y1591596D02*
X1574235D01*
G02Y1588592I0J-1502D01*
G01X1570835D01*
G02Y1591596I0J1502D01*
G37*
G36*
G01X273317D02*
X276717D01*
G02Y1588592I0J-1502D01*
G01X273317D01*
G02Y1591596I0J1502D01*
G37*
G36*
G01Y1579684D02*
X276717D01*
G02Y1576680I0J-1502D01*
G01X273317D01*
G02Y1579684I0J1502D01*
G37*
G36*
G01X1491715Y1603882D02*
X1495115D01*
G02Y1600878I0J-1502D01*
G01X1491715D01*
G02Y1603882I0J1502D01*
G37*
G36*
G01Y1615794D02*
X1495115D01*
G02Y1612790I0J-1502D01*
G01X1491715D01*
G02Y1615794I0J1502D01*
G37*
G36*
G01X1631135Y1579684D02*
X1634535D01*
G02Y1576680I0J-1502D01*
G01X1631135D01*
G02Y1579684I0J1502D01*
G37*
G36*
G01X213017Y1591596D02*
X216417D01*
G02Y1588592I0J-1502D01*
G01X213017D01*
G02Y1591596I0J1502D01*
G37*
G36*
G01X188897Y1579684D02*
X192297D01*
G02Y1576680I0J-1502D01*
G01X188897D01*
G02Y1579684I0J1502D01*
G37*
G36*
G01X1503775Y1603882D02*
X1507175D01*
G02Y1600878I0J-1502D01*
G01X1503775D01*
G02Y1603882I0J1502D01*
G37*
G36*
G01X200957Y1579684D02*
X204357D01*
G02Y1576680I0J-1502D01*
G01X200957D01*
G02Y1579684I0J1502D01*
G37*
G36*
G01X605711D02*
X609111D01*
G02Y1576680I0J-1502D01*
G01X605711D01*
G02Y1579684I0J1502D01*
G37*
G36*
G01X1479655Y1603882D02*
X1483055D01*
G02Y1600878I0J-1502D01*
G01X1479655D01*
G02Y1603882I0J1502D01*
G37*
G36*
G01Y1615794D02*
X1483055D01*
G02Y1612790I0J-1502D01*
G01X1479655D01*
G02Y1615794I0J1502D01*
G37*
G36*
G01X249197Y1579684D02*
X252597D01*
G02Y1576680I0J-1502D01*
G01X249197D01*
G02Y1579684I0J1502D01*
G37*
G36*
G01X1467595Y1615794D02*
X1470995D01*
G02Y1612790I0J-1502D01*
G01X1467595D01*
G02Y1615794I0J1502D01*
G37*
G36*
G01Y1603882D02*
X1470995D01*
G02Y1600878I0J-1502D01*
G01X1467595D01*
G02Y1603882I0J1502D01*
G37*
G36*
G01X1558775Y1591596D02*
X1562175D01*
G02Y1588592I0J-1502D01*
G01X1558775D01*
G02Y1591596I0J1502D01*
G37*
G36*
G01X1643195Y1579684D02*
X1646595D01*
G02Y1576680I0J-1502D01*
G01X1643195D01*
G02Y1579684I0J1502D01*
G37*
G36*
G01X188897Y1591596D02*
X192297D01*
G02Y1588592I0J-1502D01*
G01X188897D01*
G02Y1591596I0J1502D01*
G37*
G36*
G01X1607015D02*
X1610415D01*
G02Y1588592I0J-1502D01*
G01X1607015D01*
G02Y1591596I0J1502D01*
G37*
G36*
G01X1582895D02*
X1586295D01*
G02Y1588592I0J-1502D01*
G01X1582895D01*
G02Y1591596I0J1502D01*
G37*
G36*
G01X225077Y1579684D02*
X228477D01*
G02Y1576680I0J-1502D01*
G01X225077D01*
G02Y1579684I0J1502D01*
G37*
G36*
G01Y1591596D02*
X228477D01*
G02Y1588592I0J-1502D01*
G01X225077D01*
G02Y1591596I0J1502D01*
G37*
G36*
G01X218317Y1615794D02*
X221717D01*
G02Y1612790I0J-1502D01*
G01X218317D01*
G02Y1615794I0J1502D01*
G37*
G36*
G01X290677Y1603882D02*
X294077D01*
G02Y1600878I0J-1502D01*
G01X290677D01*
G02Y1603882I0J1502D01*
G37*
G36*
G01Y1615794D02*
X294077D01*
G02Y1612790I0J-1502D01*
G01X290677D01*
G02Y1615794I0J1502D01*
G37*
G36*
G01X237137Y1579684D02*
X240537D01*
G02Y1576680I0J-1502D01*
G01X237137D01*
G02Y1579684I0J1502D01*
G37*
G36*
G01X213017D02*
X216417D01*
G02Y1576680I0J-1502D01*
G01X213017D01*
G02Y1579684I0J1502D01*
G37*
G36*
G01X230377Y1603882D02*
X233777D01*
G02Y1600878I0J-1502D01*
G01X230377D01*
G02Y1603882I0J1502D01*
G37*
G36*
G01X1619075Y1591596D02*
X1622475D01*
G02Y1588592I0J-1502D01*
G01X1619075D01*
G02Y1591596I0J1502D01*
G37*
G36*
G01X242437Y1615794D02*
X245837D01*
G02Y1612790I0J-1502D01*
G01X242437D01*
G02Y1615794I0J1502D01*
G37*
G36*
G01X369797Y1579684D02*
X373197D01*
G02Y1576680I0J-1502D01*
G01X369797D01*
G02Y1579684I0J1502D01*
G37*
G36*
G01X473051Y1591596D02*
X476451D01*
G02Y1588592I0J-1502D01*
G01X473051D01*
G02Y1591596I0J1502D01*
G37*
G36*
G01Y1579684D02*
X476451D01*
G02Y1576680I0J-1502D01*
G01X473051D01*
G02Y1579684I0J1502D01*
G37*
G36*
G01X1588195Y1603882D02*
X1591595D01*
G02Y1600878I0J-1502D01*
G01X1588195D01*
G02Y1603882I0J1502D01*
G37*
G36*
G01Y1615794D02*
X1591595D01*
G02Y1612790I0J-1502D01*
G01X1588195D01*
G02Y1615794I0J1502D01*
G37*
G36*
G01X61470Y86124D02*
X64870D01*
G02Y83120I0J-1502D01*
G01X61470D01*
G02Y86124I0J1502D01*
G37*
G36*
G01X297437Y1579684D02*
X300837D01*
G02Y1576680I0J-1502D01*
G01X297437D01*
G02Y1579684I0J1502D01*
G37*
G36*
G01X350977Y1615794D02*
X354377D01*
G02Y1612790I0J-1502D01*
G01X350977D01*
G02Y1615794I0J1502D01*
G37*
G36*
G01X375097Y1603882D02*
X378497D01*
G02Y1600878I0J-1502D01*
G01X375097D01*
G02Y1603882I0J1502D01*
G37*
G36*
G01Y1615794D02*
X378497D01*
G02Y1612790I0J-1502D01*
G01X375097D01*
G02Y1615794I0J1502D01*
G37*
G36*
G01X363037Y1603882D02*
X366437D01*
G02Y1600878I0J-1502D01*
G01X363037D01*
G02Y1603882I0J1502D01*
G37*
G36*
G01X1330101Y541552D02*
X1333143D01*
G02Y538546I0J-1503D01*
G01X1330101D01*
G02Y541552I0J1503D01*
G37*
G36*
G01X64571Y427304D02*
X61171D01*
G02Y430308I0J1502D01*
G01X64571D01*
G02Y427304I0J-1502D01*
G37*
G36*
G01X423180Y1601300D02*
X419780D01*
G02Y1604304I0J1502D01*
G01X423180D01*
G02Y1601300I0J-1502D01*
G37*
G36*
G01X49360Y427304D02*
X45960D01*
G02Y430308I0J1502D01*
G01X49360D01*
G02Y427304I0J-1502D01*
G37*
G36*
G01X930731Y531982D02*
X933773D01*
G02Y528976I0J-1503D01*
G01X930731D01*
G02Y531982I0J1503D01*
G37*
G36*
G01X285377Y1591596D02*
X288777D01*
G02Y1588592I0J-1502D01*
G01X285377D01*
G02Y1591596I0J1502D01*
G37*
G36*
G01X229131Y49144D02*
X225731D01*
G02Y52148I0J1502D01*
G01X229131D01*
G02Y49144I0J-1502D01*
G37*
G36*
G01X284230D02*
X280830D01*
G02Y52148I0J1502D01*
G01X284230D01*
G02Y49144I0J-1502D01*
G37*
G36*
G01X1755272Y27934D02*
X1758672D01*
G02Y24928I0J-1503D01*
G01X1755272D01*
G02Y27934I0J1503D01*
G37*
G36*
G01X1530660Y101664D02*
X1534060D01*
G02Y98660I0J-1502D01*
G01X1530660D01*
G02Y101664I0J1502D01*
G37*
G36*
G01X1549308Y27934D02*
X1552708D01*
G02Y24928I0J-1503D01*
G01X1549308D01*
G02Y27934I0J1503D01*
G37*
G36*
G01X1556413Y20998D02*
X1559813D01*
G02Y17992I0J-1503D01*
G01X1556413D01*
G02Y20998I0J1503D01*
G37*
G36*
G01X1563481Y27934D02*
X1566881D01*
G02Y24928I0J-1503D01*
G01X1563481D01*
G02Y27934I0J1503D01*
G37*
G36*
G01X1570586Y20998D02*
X1573986D01*
G02Y17992I0J-1503D01*
G01X1570586D01*
G02Y20998I0J1503D01*
G37*
G36*
G01X1577654Y27934D02*
X1581054D01*
G02Y24928I0J-1503D01*
G01X1577654D01*
G02Y27934I0J1503D01*
G37*
G36*
G01X1584759Y20998D02*
X1588159D01*
G02Y17992I0J-1503D01*
G01X1584759D01*
G02Y20998I0J1503D01*
G37*
G36*
G01X1591828Y27934D02*
X1595228D01*
G02Y24928I0J-1503D01*
G01X1591828D01*
G02Y27934I0J1503D01*
G37*
G36*
G01X1598933Y20998D02*
X1602333D01*
G02Y17992I0J-1503D01*
G01X1598933D01*
G02Y20998I0J1503D01*
G37*
G36*
G01X1627694Y27934D02*
X1631094D01*
G02Y24928I0J-1503D01*
G01X1627694D01*
G02Y27934I0J1503D01*
G37*
G36*
G01X1634799Y20998D02*
X1638199D01*
G02Y17992I0J-1503D01*
G01X1634799D01*
G02Y20998I0J1503D01*
G37*
G36*
G01X218667Y21040D02*
X222067D01*
G02Y18036I0J-1502D01*
G01X218667D01*
G02Y21040I0J1502D01*
G37*
G36*
G01X211562Y27976D02*
X214962D01*
G02Y24972I0J-1502D01*
G01X211562D01*
G02Y27976I0J1502D01*
G37*
G36*
G01X204494Y21040D02*
X207894D01*
G02Y18036I0J-1502D01*
G01X204494D01*
G02Y21040I0J1502D01*
G37*
G36*
G01X197389Y27976D02*
X200789D01*
G02Y24972I0J-1502D01*
G01X197389D01*
G02Y27976I0J1502D01*
G37*
G36*
G01X167428D02*
X170828D01*
G02Y24972I0J-1502D01*
G01X167428D01*
G02Y27976I0J1502D01*
G37*
G36*
G01X174533Y21040D02*
X177933D01*
G02Y18036I0J-1502D01*
G01X174533D01*
G02Y21040I0J1502D01*
G37*
G36*
G01X153255Y27976D02*
X156655D01*
G02Y24972I0J-1502D01*
G01X153255D01*
G02Y27976I0J1502D01*
G37*
G36*
G01X160360Y21040D02*
X163760D01*
G02Y18036I0J-1502D01*
G01X160360D01*
G02Y21040I0J1502D01*
G37*
G36*
G01X124494D02*
X127894D01*
G02Y18036I0J-1502D01*
G01X124494D01*
G02Y21040I0J1502D01*
G37*
G36*
G01X117389Y27976D02*
X120789D01*
G02Y24972I0J-1502D01*
G01X117389D01*
G02Y27976I0J1502D01*
G37*
G36*
G01X103215D02*
X106615D01*
G02Y24972I0J-1502D01*
G01X103215D01*
G02Y27976I0J1502D01*
G37*
G36*
G01X110320Y21040D02*
X113720D01*
G02Y18036I0J-1502D01*
G01X110320D01*
G02Y21040I0J1502D01*
G37*
G36*
G01X89042Y27976D02*
X92442D01*
G02Y24972I0J-1502D01*
G01X89042D01*
G02Y27976I0J1502D01*
G37*
G36*
G01X96147Y21040D02*
X99547D01*
G02Y18036I0J-1502D01*
G01X96147D01*
G02Y21040I0J1502D01*
G37*
G36*
G01X74869Y27976D02*
X78269D01*
G02Y24972I0J-1502D01*
G01X74869D01*
G02Y27976I0J1502D01*
G37*
G36*
G01X81974Y21040D02*
X85374D01*
G02Y18036I0J-1502D01*
G01X81974D01*
G02Y21040I0J1502D01*
G37*
G36*
G01X1641867Y27934D02*
X1645267D01*
G02Y24928I0J-1503D01*
G01X1641867D01*
G02Y27934I0J1503D01*
G37*
G36*
G01X1648972Y20998D02*
X1652372D01*
G02Y17992I0J-1503D01*
G01X1648972D01*
G02Y20998I0J1503D01*
G37*
G36*
G01X1671828Y27934D02*
X1675228D01*
G02Y24928I0J-1503D01*
G01X1671828D01*
G02Y27934I0J1503D01*
G37*
G36*
G01X1678933Y20998D02*
X1682333D01*
G02Y17992I0J-1503D01*
G01X1678933D01*
G02Y20998I0J1503D01*
G37*
G36*
G01X1686001Y27934D02*
X1689401D01*
G02Y24928I0J-1503D01*
G01X1686001D01*
G02Y27934I0J1503D01*
G37*
G36*
G01X1693106Y20998D02*
X1696506D01*
G02Y17992I0J-1503D01*
G01X1693106D01*
G02Y20998I0J1503D01*
G37*
G36*
G01X1700217Y27962D02*
X1703617D01*
G02Y24956I0J-1503D01*
G01X1700217D01*
G02Y27962I0J1503D01*
G37*
G36*
G01X1700170Y52152D02*
X1703570D01*
G02Y49146I0J-1503D01*
G01X1700170D01*
G02Y52152I0J1503D01*
G37*
G36*
G01X670612Y48766D02*
X674012D01*
G02Y45762I0J-1502D01*
G01X670612D01*
G02Y48766I0J1502D01*
G37*
G36*
G01X284233Y24972D02*
X280833D01*
G02Y27976I0J1502D01*
G01X284233D01*
G02Y24972I0J-1502D01*
G37*
G36*
G01X1382972Y1603882D02*
X1386372D01*
G02Y1600878I0J-1502D01*
G01X1382972D01*
G02Y1603882I0J1502D01*
G37*
G36*
G01Y1615794D02*
X1386372D01*
G02Y1612790I0J-1502D01*
G01X1382972D01*
G02Y1615794I0J1502D01*
G37*
G36*
G01X229135Y24972D02*
X225735D01*
G02Y27976I0J1502D01*
G01X229135D01*
G02Y24972I0J-1502D01*
G37*
G36*
G01X350977Y1603882D02*
X354377D01*
G02Y1600878I0J-1502D01*
G01X350977D01*
G02Y1603882I0J1502D01*
G37*
G36*
G01X405990Y1617450D02*
X402590D01*
G02Y1620454I0J1502D01*
G01X405990D01*
G02Y1617450I0J-1502D01*
G37*
G36*
G01X441740Y1650764D02*
X438340D01*
G02Y1653768I0J1502D01*
G01X441740D01*
G02Y1650764I0J-1502D01*
G37*
G36*
G01X49212Y450100D02*
X45812D01*
G02Y453104I0J1502D01*
G01X49212D01*
G02Y450100I0J-1502D01*
G37*
G36*
G01X862930Y71574D02*
X866330D01*
G02Y68570I0J-1502D01*
G01X862930D01*
G02Y71574I0J1502D01*
G37*
G36*
G01X1169820Y637554D02*
X1173220D01*
G02Y634550I0J-1502D01*
G01X1169820D01*
G02Y637554I0J1502D01*
G37*
G36*
G01X519764Y41830D02*
X523164D01*
G02Y38826I0J-1502D01*
G01X519764D01*
G02Y41830I0J1502D01*
G37*
G36*
G01X732793Y72938D02*
X736193D01*
G02Y69934I0J-1502D01*
G01X732793D01*
G02Y72938I0J1502D01*
G37*
G36*
G01X1161860Y643614D02*
X1165260D01*
G02Y640610I0J-1502D01*
G01X1161860D01*
G02Y643614I0J1502D01*
G37*
G36*
G01X663543Y44830D02*
X666943D01*
G02Y41826I0J-1502D01*
G01X663543D01*
G02Y44830I0J1502D01*
G37*
G36*
G01X656439Y48766D02*
X659839D01*
G02Y45762I0J-1502D01*
G01X656439D01*
G02Y48766I0J1502D01*
G37*
G36*
G01X562771Y1603882D02*
X566171D01*
G02Y1600878I0J-1502D01*
G01X562771D01*
G02Y1603882I0J1502D01*
G37*
G36*
G01X538651D02*
X542051D01*
G02Y1600878I0J-1502D01*
G01X538651D01*
G02Y1603882I0J1502D01*
G37*
G36*
G01X555175Y72938D02*
X558575D01*
G02Y69934I0J-1502D01*
G01X555175D01*
G02Y72938I0J1502D01*
G37*
G36*
G01X541002D02*
X544402D01*
G02Y69934I0J-1502D01*
G01X541002D01*
G02Y72938I0J1502D01*
G37*
G36*
G01X519742D02*
X523142D01*
G02Y69934I0J-1502D01*
G01X519742D01*
G02Y72938I0J1502D01*
G37*
G36*
G01X533915Y61324D02*
X537315D01*
G02Y58320I0J-1502D01*
G01X533915D01*
G02Y61324I0J1502D01*
G37*
G36*
G01X538651Y1615794D02*
X542051D01*
G02Y1612790I0J-1502D01*
G01X538651D01*
G02Y1615794I0J1502D01*
G37*
G36*
G01X526591Y1603882D02*
X529991D01*
G02Y1600878I0J-1502D01*
G01X526591D01*
G02Y1603882I0J1502D01*
G37*
G36*
G01X514531D02*
X517931D01*
G02Y1600878I0J-1502D01*
G01X514531D01*
G02Y1603882I0J1502D01*
G37*
G36*
G01X526591Y1615794D02*
X529991D01*
G02Y1612790I0J-1502D01*
G01X526591D01*
G02Y1615794I0J1502D01*
G37*
G36*
G01X514531D02*
X517931D01*
G02Y1612790I0J-1502D01*
G01X514531D01*
G02Y1615794I0J1502D01*
G37*
G36*
G01X490411Y1603882D02*
X493811D01*
G02Y1600878I0J-1502D01*
G01X490411D01*
G02Y1603882I0J1502D01*
G37*
G36*
G01X478351Y1615794D02*
X481751D01*
G02Y1612790I0J-1502D01*
G01X478351D01*
G02Y1615794I0J1502D01*
G37*
G36*
G01X502471D02*
X505871D01*
G02Y1612790I0J-1502D01*
G01X502471D01*
G02Y1615794I0J1502D01*
G37*
G36*
G01X478351Y1603882D02*
X481751D01*
G02Y1600878I0J-1502D01*
G01X478351D01*
G02Y1603882I0J1502D01*
G37*
G36*
G01X598951D02*
X602351D01*
G02Y1600878I0J-1502D01*
G01X598951D01*
G02Y1603882I0J1502D01*
G37*
G36*
G01Y1615794D02*
X602351D01*
G02Y1612790I0J-1502D01*
G01X598951D01*
G02Y1615794I0J1502D01*
G37*
G36*
G01X586891Y1603882D02*
X590291D01*
G02Y1600878I0J-1502D01*
G01X586891D01*
G02Y1603882I0J1502D01*
G37*
G36*
G01X647191D02*
X650591D01*
G02Y1600878I0J-1502D01*
G01X647191D01*
G02Y1603882I0J1502D01*
G37*
G36*
G01X635131Y1615794D02*
X638531D01*
G02Y1612790I0J-1502D01*
G01X635131D01*
G02Y1615794I0J1502D01*
G37*
G36*
G01X647191D02*
X650591D01*
G02Y1612790I0J-1502D01*
G01X647191D01*
G02Y1615794I0J1502D01*
G37*
G36*
G01X623071D02*
X626471D01*
G02Y1612790I0J-1502D01*
G01X623071D01*
G02Y1615794I0J1502D01*
G37*
G36*
G01X550711Y1603882D02*
X554111D01*
G02Y1600878I0J-1502D01*
G01X550711D01*
G02Y1603882I0J1502D01*
G37*
G36*
G01X502471D02*
X505871D01*
G02Y1600878I0J-1502D01*
G01X502471D01*
G02Y1603882I0J1502D01*
G37*
G36*
G01X490411Y1615794D02*
X493811D01*
G02Y1612790I0J-1502D01*
G01X490411D01*
G02Y1615794I0J1502D01*
G37*
G36*
G01X550711D02*
X554111D01*
G02Y1612790I0J-1502D01*
G01X550711D01*
G02Y1615794I0J1502D01*
G37*
G36*
G01X635131Y1603882D02*
X638531D01*
G02Y1600878I0J-1502D01*
G01X635131D01*
G02Y1603882I0J1502D01*
G37*
G36*
G01X913394Y523164D02*
X916794D01*
G02Y520160I0J-1502D01*
G01X913394D01*
G02Y523164I0J1502D01*
G37*
G36*
G01X574831Y1603882D02*
X578231D01*
G02Y1600878I0J-1502D01*
G01X574831D01*
G02Y1603882I0J1502D01*
G37*
G36*
G01X659251D02*
X662651D01*
G02Y1600878I0J-1502D01*
G01X659251D01*
G02Y1603882I0J1502D01*
G37*
G36*
G01X1153370Y639694D02*
X1156770D01*
G02Y636690I0J-1502D01*
G01X1153370D01*
G02Y639694I0J1502D01*
G37*
G36*
G01X611011Y1615794D02*
X614411D01*
G02Y1612790I0J-1502D01*
G01X611011D01*
G02Y1615794I0J1502D01*
G37*
G36*
G01Y1603882D02*
X614411D01*
G02Y1600878I0J-1502D01*
G01X611011D01*
G02Y1603882I0J1502D01*
G37*
G36*
G01X586891Y1615794D02*
X590291D01*
G02Y1612790I0J-1502D01*
G01X586891D01*
G02Y1615794I0J1502D01*
G37*
G36*
G01X659251D02*
X662651D01*
G02Y1612790I0J-1502D01*
G01X659251D01*
G02Y1615794I0J1502D01*
G37*
G36*
G01X574831D02*
X578231D01*
G02Y1612790I0J-1502D01*
G01X574831D01*
G02Y1615794I0J1502D01*
G37*
G36*
G01X1183360Y643564D02*
X1186760D01*
G02Y640560I0J-1502D01*
G01X1183360D01*
G02Y643564I0J1502D01*
G37*
G36*
G01X562771Y1615794D02*
X566171D01*
G02Y1612790I0J-1502D01*
G01X562771D01*
G02Y1615794I0J1502D01*
G37*
G36*
G01X901230Y533114D02*
X904630D01*
G02Y530110I0J-1502D01*
G01X901230D01*
G02Y533114I0J1502D01*
G37*
G36*
G01X954390Y529098D02*
X957790D01*
G02Y526094I0J-1502D01*
G01X954390D01*
G02Y529098I0J1502D01*
G37*
G36*
G01X963930Y534864D02*
X967330D01*
G02Y531860I0J-1502D01*
G01X963930D01*
G02Y534864I0J1502D01*
G37*
G36*
G01X548070Y80874D02*
X551470D01*
G02Y77870I0J-1502D01*
G01X548070D01*
G02Y80874I0J1502D01*
G37*
G36*
G01X623071Y1603882D02*
X626471D01*
G02Y1600878I0J-1502D01*
G01X623071D01*
G02Y1603882I0J1502D01*
G37*
G36*
G01X888130Y534114D02*
X891530D01*
G02Y531110I0J-1502D01*
G01X888130D01*
G02Y534114I0J1502D01*
G37*
G36*
G01X297437Y1591596D02*
X300837D01*
G02Y1588592I0J-1502D01*
G01X297437D01*
G02Y1591596I0J1502D01*
G37*
G36*
G01X237137D02*
X240537D01*
G02Y1588592I0J-1502D01*
G01X237137D01*
G02Y1591596I0J1502D01*
G37*
G36*
G01X50772Y120610D02*
X55372Y124913D01*
G02X66448Y113076I5538J-5919D01*
G01X61848Y108773D01*
G02X50772Y120610I-5538J5918D01*
G37*
G36*
G01X1077740Y219698D02*
X1071093Y226345D01*
G02X1070800Y227052I706J707D01*
G01Y300248D01*
X1069686Y301362D01*
X1015593D01*
G02X1015520Y301360I-78J1500D01*
G02X1015447Y301362I5J1502D01*
G01X933091D01*
G02X928739Y300900I-4355J20291D01*
G02X924387Y301362I3J20753D01*
G01X839354D01*
X831168Y293176D01*
X831190Y293070D01*
G02X831222Y292762I-1470J-308D01*
G02X830355Y291401I-1502J0D01*
G01X830240Y291347D01*
Y281713D01*
G02X831122Y280345I-620J-1368D01*
G02X830682Y279283I-1502J0D01*
G03X830703Y278698I283J-283D01*
G02X831222Y277562I-984J-1136D01*
G02X830884Y276613I-1501J0D01*
G03X830905Y276084I310J-253D01*
G02X831322Y275045I-1086J-1039D01*
G02X830367Y273646I-1502J0D01*
G01X830240Y273596D01*
Y273004D01*
X830365Y272954D01*
G02Y270170I-565J-1392D01*
G01X830240Y270120D01*
Y265979D01*
X830351Y265924D01*
G02Y263236I-671J-1344D01*
G01X830240Y263181D01*
Y241842D01*
G02X829947Y241135I-999J0D01*
G01X824867Y236055D01*
G02X824160Y235762I-707J706D01*
G01X649014D01*
X637500Y224248D01*
Y127862D01*
G02X637207Y127155I-999J0D01*
G01X632907Y122855D01*
G02X632200Y122562I-707J706D01*
G01X552738D01*
X552708Y122398D01*
G02X549754I-1477J273D01*
G01X549724Y122562D01*
X384310D01*
G02X383603Y122855I0J999D01*
G01X383579Y122879D01*
G02X383160Y122820I-417J1443D01*
G02X381658Y124322I0J1502D01*
G02X381691Y124637I1502J2D01*
G01X381714Y124744D01*
X359876Y146582D01*
X128360D01*
G02X127653Y146875I0J999D01*
G01X98533Y175995D01*
G02X98240Y176702I706J707D01*
G01Y499112D01*
G02X98533Y499819I999J0D01*
G01X117963Y519249D01*
G02X118670Y519542I707J-706D01*
G01X152944D01*
G02X153651Y519249I0J-999D01*
G01X159637Y513263D01*
X161455D01*
G02X164045I1295J-761D01*
G01X244188D01*
X244209Y513439D01*
G02X247191I1491J-176D01*
G01X247212Y513263D01*
X429984D01*
G02X432456I1236J-640D01*
G01X593504D01*
X593547Y513286D01*
G02X594240Y513455I692J-1333D01*
G02X594933Y513286I1J-1502D01*
G01X594976Y513263D01*
X610543D01*
G02X613197I1327J-702D01*
G01X782763D01*
X782801Y513280D01*
G02X783400Y513404I598J-1378D01*
G02X783999Y513280I1J-1502D01*
G01X784037Y513263D01*
X792219D01*
X792268Y513392D01*
G02X795078I1405J-529D01*
G01X795127Y513263D01*
X796124D01*
G02X798716I1296J-761D01*
G01X800092D01*
X800137Y513402D01*
G02X802997I1430J-460D01*
G01X803042Y513263D01*
X831129D01*
X831176Y513395D01*
G02X832590Y514390I1414J-507D01*
G02X834058Y513207I0J-1502D01*
G02X834436Y512970I-328J-944D01*
G01X878754Y468652D01*
X945333D01*
X1004990Y528309D01*
G02X1005697Y528602I707J-706D01*
G01X1171413D01*
G02X1174027I1307J-740D01*
G01X1314600D01*
G02X1315307Y528309I0J-999D01*
G01X1435374Y408242D01*
X1448090D01*
G02X1450502I1206J-895D01*
G01X1489367D01*
G02X1491401I1017J-949D01*
G01X1503340D01*
G02X1504047Y407949I0J-999D01*
G01X1539617Y372379D01*
G02X1539910Y371672I-706J-707D01*
G01Y308096D01*
X1562194Y285812D01*
X1658640D01*
Y294362D01*
G02X1702014I21687J0D01*
G01Y285812D01*
X1775460D01*
G02X1776167Y285519I0J-999D01*
G01X1781717Y279969D01*
G02X1782010Y279262I-706J-707D01*
G01Y161902D01*
G02X1781717Y161195I-999J0D01*
G01X1765087Y144565D01*
G02X1764380Y144272I-707J706D01*
G01X1692912D01*
G02X1686380I-3266J1397D01*
G01X1682912D01*
G02X1676380I-3266J1397D01*
G01X1520834D01*
X1469387Y92825D01*
G02X1468680Y92532I-707J706D01*
G01X1393821D01*
X1393784Y92517D01*
G02X1393250Y92410I-535J1285D01*
G02X1392716Y92517I1J1392D01*
G01X1392679Y92532D01*
X1317921D01*
X1317870Y92407D01*
G02X1315086I-1392J562D01*
G01X1315035Y92532D01*
X1314729D01*
X1314689Y92514D01*
G02X1314059Y92375I-631J1363D01*
G02X1313429Y92514I1J1502D01*
G01X1313389Y92532D01*
X1299933D01*
X1299877Y92424D01*
G02X1297403I-1237J638D01*
G01X1297347Y92532D01*
X1294121D01*
G02X1291639I-1241J630D01*
G01X1266118D01*
X1266082Y92378D01*
G02X1263158I-1462J347D01*
G01X1263122Y92532D01*
X1131400D01*
G02X1130693Y92825I0J999D01*
G01X1078033Y145485D01*
G02X1077740Y146192I706J707D01*
G01Y196975D01*
G03X1076968Y197122I-400J0D01*
G02X1057658Y183972I-19310J7603D01*
G02Y225476I0J20752D01*
G02X1076968Y212326I0J-20753D01*
G03X1077740Y212473I372J147D01*
G01Y219698D01*
G37*
G36*
G01X669778Y758427D02*
G02X669015Y758635I0J1502D01*
G01X601187D01*
X387120Y544568D01*
G02X386413Y544275I-707J706D01*
G01X196107D01*
G02X195400Y544568I0J999D01*
G01X192750Y547218D01*
G02X192457Y547925I706J707D01*
G01Y621189D01*
X188324Y625322D01*
X128223D01*
G03X128037Y624568I0J-400D01*
G02X139620Y605378I-10105J-19190D01*
G02X96246I-21687J0D01*
G02X107829Y624568I21688J0D01*
G03X107643Y625322I-186J354D01*
G01X70000D01*
G02X69293Y625615I0J999D01*
G01X62135Y632773D01*
G03X61452Y632479I-283J-283D01*
G02X61460Y631890I-20744J-576D01*
G02X40708Y652642I-20752J0D01*
G01X40711D01*
G02X49360Y650753I-2J-20752D01*
G03X49927Y651116I167J363D01*
G01Y695234D01*
X27191Y739605D01*
X27190Y739606D01*
Y739607D01*
X24839Y744227D01*
X24275Y745298D01*
X24264Y745313D01*
G02X24069Y745726I783J622D01*
G02X24023Y746026I955J300D01*
G02X24043Y746225I1000J0D01*
G01X24047Y746245D01*
Y764247D01*
G02Y766953I654J1353D01*
G01Y1289920D01*
G02X24045Y1289977I998J64D01*
G01Y1318873D01*
G02X24338Y1319580I999J0D01*
G01X33930Y1329172D01*
G02X34637Y1329465I707J-706D01*
G01X87493D01*
X97697Y1339669D01*
Y1369764D01*
G02X97990Y1370471I999J0D01*
G01X144891Y1417372D01*
G02X145598Y1417665I707J-706D01*
G01X222743D01*
G02X225411I1334J-690D01*
G01X338257D01*
G02X338964Y1417372I0J-999D01*
G01X344544Y1411792D01*
G02X344837Y1411085I-706J-707D01*
G01Y1400759D01*
X347741Y1397855D01*
X391435D01*
X391459Y1398028D01*
G02X394435I1488J-200D01*
G01X394459Y1397855D01*
X399939D01*
X409734Y1407650D01*
X409703Y1407762D01*
G02X409648Y1408163I1447J403D01*
G02X411150Y1409665I1502J0D01*
G02X411888Y1409471I0J-1501D01*
G02X411973Y1409475I89J-995D01*
G01X454108D01*
X454155Y1409610D01*
G02X456997I1421J-484D01*
G01X457044Y1409475D01*
X506873D01*
G03X507273Y1409878I0J400D01*
G01Y1409889D01*
G02X508775Y1411391I1502J0D01*
G01X508776D01*
G02X509128Y1411349I-1J-1502D01*
G01X509237Y1411323D01*
X522203Y1424289D01*
G02X522910Y1424582I707J-706D01*
G01X570111D01*
X570140Y1424748D01*
G02X573100I1480J-256D01*
G01X573129Y1424582D01*
X574902D01*
G02X577538I1318J-720D01*
G01X653193D01*
X653243Y1424710D01*
G02X655837I1297J-505D01*
G01X655887Y1424582D01*
X690341D01*
G02X691129Y1424805I788J-1279D01*
G02X691917Y1424582I0J-1502D01*
G01X693341D01*
G02X694129Y1424805I788J-1279D01*
G02X694917Y1424582I0J-1502D01*
G01X820928D01*
G02X841240Y1441082I20312J-4252D01*
G02X861992Y1420330I0J-20752D01*
G01Y1420329D01*
G02X856135Y1405880I-20752J0D01*
G01X855998Y1405738D01*
X858164Y1403572D01*
G02X858457Y1402865I-706J-707D01*
G01Y765455D01*
G02X858164Y764748I-999J0D01*
G01X855936Y762520D01*
G02X856189Y761686I-1249J-834D01*
G01Y761685D01*
G02X854687Y760183I-1502J0D01*
G01X854686D01*
G02X853852Y760436I0J1502D01*
G01X852344Y758928D01*
G02X851637Y758635I-707J706D01*
G01X838484D01*
X838436Y758503D01*
G02X835818I-1309J473D01*
G01X835770Y758635D01*
X764106D01*
X764066Y758488D01*
G02X761168I-1449J398D01*
G01X761128Y758635D01*
X670541D01*
G02X669778Y758427I-763J1294D01*
G37*
G36*
G01X1004455Y1403249D02*
G02X995488Y1420330I11785J17081D01*
G02X1016240Y1441082I20752J0D01*
G02X1035543Y1427949I0J-20752D01*
G01X1133482D01*
G02X1135376I947J-1119D01*
G01X1136082D01*
G02X1137976I947J-1119D01*
G01X1144558D01*
G02X1146526I984J-1088D01*
G01X1171625D01*
G02X1173519I947J-1119D01*
G01X1174225D01*
G02X1176119I947J-1119D01*
G01X1182701D01*
G02X1184669I984J-1088D01*
G01X1304043D01*
G02X1304750Y1427656I0J-999D01*
G01X1330651Y1401755D01*
X1367884D01*
X1389137Y1423008D01*
G02X1388778Y1423940I1033J933D01*
G01Y1423942D01*
G02X1390170Y1425334I1392J0D01*
G01X1390172D01*
G02X1391104Y1424975I-1J-1392D01*
G01X1392204Y1426075D01*
X1392176Y1426186D01*
G02X1392128Y1426562I1454J377D01*
G02X1393630Y1428064I1502J0D01*
G02X1394006Y1428016I-1J-1502D01*
G01X1394117Y1427988D01*
X1394371Y1428242D01*
G02X1395078Y1428535I707J-706D01*
G01X1430517D01*
G02X1432917I1200J-903D01*
G01X1510870D01*
G02X1513484I1307J-740D01*
G01X1631275D01*
G02X1632516Y1429220I1241J-782D01*
G02X1633486Y1428853I-1J-1467D01*
G03X1634016I265J300D01*
G02X1634986Y1429220I971J-1100D01*
G02X1635941Y1428867I0J-1468D01*
G03X1636461I260J304D01*
G02X1637416Y1429220I955J-1115D01*
G02X1638657Y1428535I0J-1467D01*
G01X1669418D01*
G02X1670659Y1429220I1241J-782D01*
G02X1671629Y1428853I-1J-1467D01*
G03X1672159I265J300D01*
G02X1673129Y1429220I971J-1100D01*
G02X1674084Y1428867I0J-1468D01*
G03X1674604I260J304D01*
G02X1675559Y1429220I955J-1115D01*
G02X1676800Y1428535I0J-1467D01*
G01X1698090D01*
X1698123Y1428694D01*
G02X1701063I1470J-310D01*
G01X1701096Y1428535D01*
X1735227D01*
G02X1735934Y1428242I0J-999D01*
G01X1754194Y1409982D01*
G02X1754487Y1409275I-706J-707D01*
G01Y1322499D01*
X1756251Y1320735D01*
X1785450D01*
G02X1785639Y1320717I0J-1001D01*
G02X1785856Y1320741I218J-976D01*
G02X1786563Y1320448I0J-999D01*
G01X1788954Y1318057D01*
G02X1789247Y1317350I-706J-707D01*
G01Y1295535D01*
G02X1788954Y1294828I-999J0D01*
G01X1785267Y1291141D01*
Y1268455D01*
G02X1784974Y1267748I-999J0D01*
G01X1783664Y1266438D01*
G02X1782957Y1266145I-707J706D01*
G01X1691712D01*
X1690478Y1264911D01*
G02X1690414Y1264852I-709J705D01*
G01Y1234093D01*
X1690505Y1234033D01*
G02X1690668Y1233901I-544J-839D01*
G01X1691904Y1232665D01*
X1701074D01*
G02X1703492I1209J-710D01*
G01X1709774D01*
G02X1712192I1209J-710D01*
G01X1714762D01*
G02X1716920I1079J-709D01*
G01X1730774D01*
G02X1733192I1209J-710D01*
G01X1739474D01*
G02X1741892I1209J-710D01*
G01X1742447D01*
G02X1743154Y1232372I0J-999D01*
G01X1746164Y1229362D01*
G02X1746457Y1228655I-706J-707D01*
G01Y1226324D01*
G02Y1224202I-915J-1061D01*
G01Y1219631D01*
G02Y1217509I-915J-1061D01*
G01Y1212938D01*
G02Y1210816I-915J-1061D01*
G01Y1206245D01*
G02Y1204123I-915J-1061D01*
G01Y1199552D01*
G02Y1197430I-915J-1061D01*
G01Y1189513D01*
G02Y1187391I-915J-1061D01*
G01Y1182820D01*
G02Y1180698I-915J-1061D01*
G01Y1176127D01*
G02Y1174005I-915J-1061D01*
G01Y1169434D01*
G02Y1167312I-915J-1061D01*
G01Y1162741D01*
G02Y1160619I-915J-1061D01*
G01Y1152702D01*
G02Y1150580I-915J-1061D01*
G01Y1146009D01*
G02Y1143887I-915J-1061D01*
G01Y1139316D01*
G02Y1137194I-915J-1061D01*
G01Y1132623D01*
G02Y1130501I-915J-1061D01*
G01Y1125930D01*
G02Y1123808I-915J-1061D01*
G01Y1115890D01*
G02Y1113768I-915J-1061D01*
G01Y1109198D01*
G02Y1107076I-915J-1061D01*
G01Y1102505D01*
G02Y1100383I-915J-1061D01*
G01Y1095812D01*
G02Y1093690I-915J-1061D01*
G01Y1089119D01*
G02Y1086997I-915J-1061D01*
G01Y1079079D01*
G02Y1076957I-915J-1061D01*
G01Y1072387D01*
G02Y1070265I-915J-1061D01*
G01Y1065694D01*
G02Y1063572I-915J-1061D01*
G01Y1059001D01*
G02Y1056879I-915J-1061D01*
G01Y1055504D01*
G02Y1053682I-916J-911D01*
G01Y1052308D01*
G02Y1050186I-915J-1061D01*
G01Y1045615D01*
G02Y1043493I-915J-1061D01*
G01Y1038922D01*
G02Y1036800I-915J-1061D01*
G01Y1032229D01*
G02Y1030107I-915J-1061D01*
G01Y1025536D01*
G02Y1023414I-915J-1061D01*
G01Y1018843D01*
G02Y1016721I-915J-1061D01*
G01Y992072D01*
G02Y989950I-915J-1061D01*
G01Y985379D01*
G02Y983257I-915J-1061D01*
G01Y978686D01*
G02Y976564I-915J-1061D01*
G01Y971993D01*
G02Y969871I-915J-1061D01*
G01Y968496D01*
G02Y966674I-916J-911D01*
G01Y965300D01*
G02Y963178I-915J-1061D01*
G01Y961803D01*
G02Y959981I-916J-911D01*
G01Y958457D01*
G02Y956635I-916J-911D01*
G01Y955261D01*
G02Y953139I-915J-1061D01*
G01Y948568D01*
G02Y946446I-915J-1061D01*
G01Y941875D01*
G02Y939753I-915J-1061D01*
G01Y931835D01*
G02Y929713I-915J-1061D01*
G01Y925142D01*
G02Y923020I-915J-1061D01*
G01Y918450D01*
G02Y916328I-915J-1061D01*
G01Y911757D01*
G02Y909635I-915J-1061D01*
G01Y905064D01*
G02Y902942I-915J-1061D01*
G01Y895024D01*
G02Y892902I-915J-1061D01*
G01Y888331D01*
G02Y886209I-915J-1061D01*
G01Y881638D01*
G02Y879516I-915J-1061D01*
G01Y874946D01*
G02Y872824I-915J-1061D01*
G01Y868253D01*
G02Y866131I-915J-1061D01*
G01Y858213D01*
G02Y856091I-915J-1061D01*
G01Y851520D01*
G02Y849398I-915J-1061D01*
G01Y844827D01*
G02Y842705I-915J-1061D01*
G01Y838135D01*
G02Y836013I-915J-1061D01*
G01Y831442D01*
G02Y829320I-915J-1061D01*
G01Y821402D01*
G02Y819280I-915J-1061D01*
G01Y814709D01*
G02Y812587I-915J-1061D01*
G01Y808016D01*
G02Y805894I-915J-1061D01*
G01Y801324D01*
G02Y799202I-915J-1061D01*
G01Y794631D01*
G02Y792509I-915J-1061D01*
G01Y784591D01*
G02Y782469I-915J-1061D01*
G01Y777898D01*
G02Y775776I-915J-1061D01*
G01Y771205D01*
G02Y769083I-915J-1061D01*
G01Y767859D01*
G02Y765737I-915J-1061D01*
G01Y671405D01*
G02X1746164Y670698I-999J0D01*
G01X1743810Y668343D01*
X1743800Y668329D01*
G02X1743693Y668204I-811J586D01*
G01X1743647Y668158D01*
G02X1742940Y667865I-707J706D01*
G01X1686156D01*
G02X1679608I-3274J1245D01*
G01X1659822D01*
X1658702Y666745D01*
Y640880D01*
G02Y638142I-616J-1369D01*
G01Y620907D01*
X1658704Y620892D01*
G02X1658722Y620662I-1484J-232D01*
G02X1658704Y620432I-1502J2D01*
G01X1658702Y620417D01*
Y592480D01*
G02X1658409Y591773I-999J0D01*
G01X1650028Y583392D01*
G02X1649321Y583099I-707J706D01*
G01X1616953D01*
G02X1614647I-1153J964D01*
G01X1608429D01*
G02X1605971I-1229J862D01*
G01X1562407D01*
G02X1560581I-913J1194D01*
G01X1401283D01*
G02X1400576Y583392I0J999D01*
G01X1252513Y731455D01*
G02X1252220Y732162I706J707D01*
G01Y763305D01*
X1002267D01*
G02X1001560Y763598I0J999D01*
G01X998500Y766658D01*
G02X998207Y767365I706J707D01*
G01Y1395919D01*
G02X998500Y1396626I999J0D01*
G01X1004511Y1402637D01*
G03X1004455Y1403249I-283J283D01*
G37*
G36*
G01X1143020Y1540382D02*
G03X1143411Y1540758I-8J400D01*
G02X1145410Y1542642I1999J-119D01*
G02X1147412Y1540640I0J-2002D01*
G02X1145450Y1538638I-2002J0D01*
G03X1145059Y1538262I8J-400D01*
G02X1143060Y1536378I-1999J119D01*
G02X1141058Y1538380I0J2002D01*
G02X1143020Y1540382I2002J0D01*
G37*
G36*
G01X1162980Y1551449D02*
G03X1163635I328J229D01*
G02X1166917I1641J-1147D01*
G03X1167572I327J229D01*
G02X1169213Y1552304I1641J-1147D01*
G02Y1548298I0J-2003D01*
G02X1167572Y1549153I0J2002D01*
G03X1166917I-328J-229D01*
G02X1163635I-1641J1147D01*
G03X1162980I-327J-229D01*
G02X1159698I-1641J1147D01*
G03X1159043I-328J-229D01*
G02X1155761I-1641J1147D01*
G03X1155106I-328J-229D01*
G02X1151824I-1641J1147D01*
G03X1151169I-328J-229D01*
G02X1149528Y1548298I-1641J1147D01*
G02Y1552304I0J2003D01*
G02X1151169Y1551449I0J-2002D01*
G03X1151824I327J229D01*
G02X1155106I1641J-1147D01*
G03X1155761I328J229D01*
G02X1159043I1641J-1147D01*
G03X1159698I327J229D01*
G02X1162980I1641J-1147D01*
G37*
G36*
G01X1139652Y1550301D02*
Y1550302D01*
G02X1140157Y1551631I2002J0D01*
G02X1139688Y1552918I1533J1288D01*
G01Y1552920D01*
G02X1143692I2002J0D01*
G01Y1552919D01*
G02X1143187Y1551590I-2002J0D01*
G02X1143656Y1550303I-1533J-1288D01*
G01Y1550301D01*
G02X1139652I-2002J0D01*
G37*
G36*
G01X1101405Y1550386D02*
G03X1101083Y1550900I-382J119D01*
G02X1098098Y1554364I517J3464D01*
G02X1105102I3502J0D01*
G02X1104945Y1553324I-3502J-3D01*
G03X1105267Y1552810I382J-119D01*
G02X1108252Y1549346I-517J-3464D01*
G02X1101248I-3502J0D01*
G02X1101405Y1550386I3502J3D01*
G37*
G36*
G01X1143823Y1573272D02*
G03X1143551I-136J-147D01*
G02X1142188Y1572736I-1363J1466D01*
G01X1142187D01*
G02Y1576740I0J2002D01*
G01X1142188D01*
G02X1143551Y1576204I0J-2002D01*
G03X1143823I136J147D01*
G02X1145186Y1576740I1363J-1466D01*
G01X1145187D01*
G02Y1572736I0J-2002D01*
G01X1145186D01*
G02X1143823Y1573272I0J2002D01*
G37*
G36*
G01X1153823D02*
G03X1153551I-136J-147D01*
G02X1152188Y1572736I-1363J1466D01*
G01X1152187D01*
G02Y1576740I0J2002D01*
G01X1152188D01*
G02X1153551Y1576204I0J-2002D01*
G03X1153823I136J147D01*
G02X1155186Y1576740I1363J-1466D01*
G01X1155187D01*
G02Y1572736I0J-2002D01*
G01X1155186D01*
G02X1153823Y1573272I0J2002D01*
G37*
G36*
G01X1163231D02*
G03X1162959I-136J-147D01*
G02X1161596Y1572736I-1363J1466D01*
G01X1161595D01*
G02Y1576740I0J2002D01*
G01X1161596D01*
G02X1162959Y1576204I0J-2002D01*
G03X1163231I136J147D01*
G02X1164594Y1576740I1363J-1466D01*
G01X1164595D01*
G02Y1572736I0J-2002D01*
G01X1164594D01*
G02X1163231Y1573272I0J2002D01*
G37*
G36*
G01X1173231D02*
G03X1172959I-136J-147D01*
G02X1171596Y1572736I-1363J1466D01*
G01X1171595D01*
G02Y1576740I0J2002D01*
G01X1171596D01*
G02X1172959Y1576204I0J-2002D01*
G03X1173231I136J147D01*
G02X1174594Y1576740I1363J-1466D01*
G01X1174595D01*
G02Y1572736I0J-2002D01*
G01X1174594D01*
G02X1173231Y1573272I0J2002D01*
G37*
G36*
G01X1133823Y1581272D02*
G03X1133551I-136J-147D01*
G02X1132188Y1580736I-1363J1466D01*
G01X1132187D01*
G02Y1584740I0J2002D01*
G01X1132188D01*
G02X1133551Y1584204I0J-2002D01*
G03X1133823I136J147D01*
G02X1135186Y1584740I1363J-1466D01*
G01X1135187D01*
G02Y1580736I0J-2002D01*
G01X1135186D01*
G02X1133823Y1581272I0J2002D01*
G37*
G36*
G01X1143823D02*
G03X1143551I-136J-147D01*
G02X1142188Y1580736I-1363J1466D01*
G01X1142187D01*
G02Y1584740I0J2002D01*
G01X1142188D01*
G02X1143551Y1584204I0J-2002D01*
G03X1143823I136J147D01*
G02X1145186Y1584740I1363J-1466D01*
G01X1145187D01*
G02Y1580736I0J-2002D01*
G01X1145186D01*
G02X1143823Y1581272I0J2002D01*
G37*
G36*
G01X1153823D02*
G03X1153551I-136J-147D01*
G02X1152188Y1580736I-1363J1466D01*
G01X1152187D01*
G02Y1584740I0J2002D01*
G01X1152188D01*
G02X1153551Y1584204I0J-2002D01*
G03X1153823I136J147D01*
G02X1155186Y1584740I1363J-1466D01*
G01X1155187D01*
G02Y1580736I0J-2002D01*
G01X1155186D01*
G02X1153823Y1581272I0J2002D01*
G37*
G36*
G01X1163231D02*
G03X1162959I-136J-147D01*
G02X1161596Y1580736I-1363J1466D01*
G01X1161595D01*
G02Y1584740I0J2002D01*
G01X1161596D01*
G02X1162959Y1584204I0J-2002D01*
G03X1163231I136J147D01*
G02X1164594Y1584740I1363J-1466D01*
G01X1164595D01*
G02Y1580736I0J-2002D01*
G01X1164594D01*
G02X1163231Y1581272I0J2002D01*
G37*
G36*
G01X1173231D02*
G03X1172959I-136J-147D01*
G02X1171596Y1580736I-1363J1466D01*
G01X1171595D01*
G02Y1584740I0J2002D01*
G01X1171596D01*
G02X1172959Y1584204I0J-2002D01*
G03X1173231I136J147D01*
G02X1174594Y1584740I1363J-1466D01*
G01X1174595D01*
G02Y1580736I0J-2002D01*
G01X1174594D01*
G02X1173231Y1581272I0J2002D01*
G37*
G36*
G01X1133823Y1589272D02*
G03X1133551I-136J-147D01*
G02X1132188Y1588736I-1363J1466D01*
G01X1132187D01*
G02Y1592740I0J2002D01*
G01X1132188D01*
G02X1133551Y1592204I0J-2002D01*
G03X1133823I136J147D01*
G02X1135186Y1592740I1363J-1466D01*
G01X1135187D01*
G02Y1588736I0J-2002D01*
G01X1135186D01*
G02X1133823Y1589272I0J2002D01*
G37*
G36*
G01X1143823D02*
G03X1143551I-136J-147D01*
G02X1142188Y1588736I-1363J1466D01*
G01X1142187D01*
G02Y1592740I0J2002D01*
G01X1142188D01*
G02X1143551Y1592204I0J-2002D01*
G03X1143823I136J147D01*
G02X1145186Y1592740I1363J-1466D01*
G01X1145187D01*
G02Y1588736I0J-2002D01*
G01X1145186D01*
G02X1143823Y1589272I0J2002D01*
G37*
G36*
G01X1153823D02*
G03X1153551I-136J-147D01*
G02X1152188Y1588736I-1363J1466D01*
G01X1152187D01*
G02Y1592740I0J2002D01*
G01X1152188D01*
G02X1153551Y1592204I0J-2002D01*
G03X1153823I136J147D01*
G02X1155186Y1592740I1363J-1466D01*
G01X1155187D01*
G02Y1588736I0J-2002D01*
G01X1155186D01*
G02X1153823Y1589272I0J2002D01*
G37*
G36*
G01X1163231D02*
G03X1162959I-136J-147D01*
G02X1161596Y1588736I-1363J1466D01*
G01X1161595D01*
G02Y1592740I0J2002D01*
G01X1161596D01*
G02X1162959Y1592204I0J-2002D01*
G03X1163231I136J147D01*
G02X1164594Y1592740I1363J-1466D01*
G01X1164595D01*
G02Y1588736I0J-2002D01*
G01X1164594D01*
G02X1163231Y1589272I0J2002D01*
G37*
G36*
G01X1173231D02*
G03X1172959I-136J-147D01*
G02X1171596Y1588736I-1363J1466D01*
G01X1171595D01*
G02Y1592740I0J2002D01*
G01X1171596D01*
G02X1172959Y1592204I0J-2002D01*
G03X1173231I136J147D01*
G02X1174594Y1592740I1363J-1466D01*
G01X1174595D01*
G02Y1588736I0J-2002D01*
G01X1174594D01*
G02X1173231Y1589272I0J2002D01*
G37*
G54D91*
X1137717Y1558020D03*
G54D89*
X479646Y1421784D03*
G54D92*
X1074010Y1510650D03*
X1066462Y1520088D03*
G54D90*
X1175215Y1532913D03*
X1131715D03*
G54D77*
X1307572Y-26511D03*
X1040152Y-16511D03*
X1015152D03*
X1307572Y13489D03*
X1282572Y23489D03*
X1307572D03*
X1282572Y13489D03*
X1040152Y23489D03*
Y13489D03*
X973180Y-6500D03*
X998180D03*
X1015152Y13489D03*
X1282572Y-16511D03*
X973180Y-26500D03*
X998180D03*
Y-16500D03*
X1015152Y23489D03*
X1307572Y-16511D03*
X973180Y-16500D03*
X1474931Y23489D03*
X1499931D03*
X705760Y-26500D03*
X730760D03*
X705760Y-6500D03*
Y-16500D03*
X730760D03*
Y-6500D03*
X1474931Y13489D03*
X998180Y3500D03*
X973180D03*
X1499931Y13489D03*
X998180Y13500D03*
Y23500D03*
X973180D03*
Y13500D03*
X1499931Y-16511D03*
X1474931D03*
X1324471Y23489D03*
X1349471D03*
X822720Y3500D03*
X847720D03*
X822720Y23500D03*
Y13500D03*
X847720D03*
Y23500D03*
X1324471Y-16511D03*
X1349471D03*
X1324471Y13489D03*
X1349471D03*
X1307572Y-36511D03*
X1282572D03*
Y-26511D03*
X1307572Y-6511D03*
Y3489D03*
X1282572D03*
Y-6511D03*
X1015152Y-36511D03*
Y-26511D03*
X1040152D03*
Y-36511D03*
X1015152Y3489D03*
Y-6511D03*
X1040152D03*
Y3489D03*
X1499931Y-26511D03*
Y-36511D03*
X1474931D03*
Y-26511D03*
X1499931Y-6511D03*
Y3489D03*
X1474931D03*
Y-6511D03*
X1324471Y-36511D03*
Y-26511D03*
X1349471D03*
Y-36511D03*
X1324471Y3489D03*
Y-6511D03*
X1349471D03*
Y3489D03*
G54D82*
X70472Y173228D03*
Y236220D03*
G54D85*
X929331Y160413D03*
X922441Y237697D03*
G54D84*
X676508Y224606D03*
G54D83*
Y145866D03*
G54D81*
X1829725Y130315D03*
G54D99*
X791280Y1704890D03*
X1066280D03*
G54D76*
X1341752Y-31511D03*
Y-21511D03*
Y-11511D03*
Y-1511D03*
X1482650Y-31511D03*
Y-21511D03*
Y-11511D03*
Y-1511D03*
X90998Y1517237D03*
X78120Y1517136D03*
X99750Y1563678D03*
X75922Y1560674D03*
X404030Y1593690D03*
X957156Y228863D03*
X899830Y973184D03*
X397406Y1634842D03*
X736710Y605542D03*
X527310Y96447D03*
X414406Y1626692D03*
X460910Y1627472D03*
X64410Y1600802D03*
X1340420Y540122D03*
X704770Y204921D03*
X896060Y482922D03*
X716698Y210721D03*
X704770Y216732D03*
X895340Y499582D03*
X907470Y213680D03*
X902350Y220768D03*
X953970Y206575D03*
X716698Y198887D03*
X704770Y193110D03*
Y181299D03*
X947496Y227835D03*
X705800Y169488D03*
X947496Y213697D03*
X907470Y227854D03*
X941050Y530552D03*
X716698Y175387D03*
X902350Y206594D03*
X716698Y187387D03*
X944250Y196189D03*
X954420Y512952D03*
Y498852D03*
G54D75*
X723041Y-11500D03*
Y-21500D03*
X840001Y8500D03*
Y18500D03*
X980899Y-21500D03*
Y-11500D03*
Y8500D03*
Y18500D03*
X1032433Y-31511D03*
Y-21511D03*
Y-11511D03*
Y-1511D03*
X1290291Y-31511D03*
Y-21511D03*
Y-11511D03*
Y-1511D03*
X62813Y414300D03*
X47619Y417205D03*
X901829Y514430D03*
X889439Y491299D03*
X922879Y530276D03*
X946727Y506252D03*
G54D87*
X373622Y87795D03*
X1829921D03*
X1499606D03*
X931692Y757874D03*
X1271260Y631890D03*
X661023D03*
X931692Y1072834D03*
X27559Y87795D03*
X800787D03*
X40708Y1368897D03*
X931692Y1387795D03*
X805690Y204724D03*
G54D86*
X38346Y1420330D03*
G54D78*
X19685Y-29134D03*
X1837795D03*
X1808192Y1569255D03*
X41870Y1511291D03*
X1812980Y502472D03*
X49280Y337402D03*
X2081889Y1803261D03*
Y-29134D03*
G54D88*
X763602Y605413D03*
X1739744D03*
X1094075Y605378D03*
G54D79*
X177311Y1657953D03*
G54D80*
X1680232D03*
%LPC*%
G75*
G36*
G01X84334Y1252861D02*
G03X84941Y1252999I0J1402D01*
G01X84982Y1253019D01*
X120659D01*
X122963Y1250715D01*
G03X122973Y1250705I712J702D01*
G01Y862229D01*
G03X123266Y861522I999J0D01*
G01X124207Y860581D01*
Y860498D01*
G03X125498Y859207I1292J1D01*
G01X125581D01*
X125952Y858836D01*
G03X126659Y858543I707J706D01*
G01X237535D01*
X239710Y856368D01*
Y669204D01*
X239708Y669191D01*
G03Y668933I991J-129D01*
G01X239710Y668920D01*
Y639057D01*
X239695Y639020D01*
G03Y637960I1298J-530D01*
G01X239710Y637923D01*
Y631387D01*
X239695Y631350D01*
G03Y630290I1298J-530D01*
G01X239710Y630253D01*
Y628787D01*
X239695Y628750D01*
G03Y627690I1298J-530D01*
G01X239710Y627653D01*
Y605057D01*
X239695Y605020D01*
G03Y603960I1298J-530D01*
G01X239710Y603923D01*
Y597387D01*
X239695Y597350D01*
G03Y596290I1298J-530D01*
G01X239710Y596253D01*
Y594787D01*
X239695Y594750D01*
G03Y593690I1298J-530D01*
G01X239710Y593653D01*
Y571057D01*
X239695Y571020D01*
G03Y569960I1298J-530D01*
G01X239710Y569923D01*
Y548404D01*
X237581Y546275D01*
X196521D01*
X194457Y548339D01*
Y603550D01*
X194582Y603600D01*
G03Y606202I-523J1301D01*
G01X194457Y606252D01*
Y621603D01*
G03X194164Y622310I-999J0D01*
G01X189445Y627029D01*
G03X188738Y627322I-707J-706D01*
G01X70414D01*
X60850Y636886D01*
G03X51927Y649349I-20142J-4995D01*
G01Y695475D01*
G03X51817Y695931I-1000J0D01*
G01X28972Y740516D01*
X26618Y745140D01*
G03X26612Y745151I-881J-473D01*
G01X26047Y746227D01*
Y765210D01*
X26054Y765236D01*
G03X26102Y765600I-1354J364D01*
G03X26054Y765964I-1402J0D01*
G01X26047Y765990D01*
Y1250887D01*
X28179Y1253019D01*
X51700D01*
G03X53940I1120J843D01*
G01X83686D01*
X83727Y1252999D01*
G03X84334Y1252861I607J1264D01*
G37*
G36*
G01X756791Y1422582D02*
X820169D01*
G02X820567Y1422147I0J-400D01*
G03X820488Y1420330I20673J-1809D01*
G03X841240Y1399578I20752J0D01*
G03X854383Y1404270I1J20752D01*
G01X854523Y1404385D01*
X856457Y1402451D01*
Y1260091D01*
X829124D01*
X829103Y1260096D01*
G03X828799Y1260129I-302J-1369D01*
G03X828495Y1260096I-2J-1402D01*
G01X828474Y1260091D01*
X799424D01*
X799403Y1260096D01*
G03X799099Y1260129I-302J-1369D01*
G03X798795Y1260096I-2J-1402D01*
G01X798774Y1260091D01*
X784203D01*
G03X782057I-1073J-718D01*
G01X769724D01*
X769703Y1260096D01*
G03X769399Y1260129I-302J-1369D01*
G03X769095Y1260096I-2J-1402D01*
G01X769074Y1260091D01*
X740024D01*
X740003Y1260096D01*
G03X739699Y1260129I-302J-1369D01*
G03X739395Y1260096I-2J-1402D01*
G01X739374Y1260091D01*
X715628D01*
X714337Y1261382D01*
G03X714273Y1261441I-709J-705D01*
G01Y1272684D01*
X714295Y1272727D01*
G03Y1274001I-1250J637D01*
G01X714273Y1274044D01*
Y1282246D01*
X714398Y1282296D01*
G03Y1285082I-562J1393D01*
G01X714273Y1285132D01*
Y1288951D01*
X717034Y1291712D01*
X730710D01*
G03X731417Y1292005I0J999D01*
G01X734307Y1294895D01*
G03X734600Y1295602I-706J707D01*
G01Y1341942D01*
G03X734307Y1342649I-999J0D01*
G01X729707Y1347249D01*
G03X729079Y1347539I-707J-706D01*
G03X728104Y1347898I-975J-1143D01*
G03X727185Y1347584I0J-1502D01*
G01X727131Y1347542D01*
X726577D01*
X726523Y1347584D01*
G03X725604Y1347898I-919J-1188D01*
G03X724633Y1347542I0J-1502D01*
G01X724025D01*
G03X722083I-971J-1146D01*
G01X709108D01*
G03X707166I-971J-1146D01*
G01X706558D01*
G03X705587Y1347898I-971J-1146D01*
G03X704668Y1347584I0J-1502D01*
G01X704614Y1347542D01*
X704060D01*
X704006Y1347584D01*
G03X703087Y1347898I-919J-1188D01*
G03X702116Y1347542I0J-1502D01*
G01X690576D01*
G03X689605Y1347898I-971J-1146D01*
G03X688686Y1347584I0J-1502D01*
G01X688632Y1347542D01*
X688078D01*
X688024Y1347584D01*
G03X687105Y1347898I-919J-1188D01*
G03X686134Y1347542I0J-1502D01*
G01X685526D01*
G03X683584I-971J-1146D01*
G01X671008D01*
G03X669066I-971J-1146D01*
G01X668458D01*
G03X667487Y1347898I-971J-1146D01*
G03X666568Y1347584I0J-1502D01*
G01X666514Y1347542D01*
X665960D01*
X665906Y1347584D01*
G03X664987Y1347898I-919J-1188D01*
G03X664016Y1347542I0J-1502D01*
G01X589910D01*
G03X589203Y1347249I0J-999D01*
G01X584430Y1342476D01*
G03X584137Y1341769I706J-707D01*
G01Y1308609D01*
X582293Y1306765D01*
X528573D01*
G03X527866Y1306472I0J-999D01*
G01X526166Y1304772D01*
G03X525873Y1304065I706J-707D01*
G01Y1295279D01*
X517059Y1286465D01*
X500973D01*
G03X500266Y1286172I0J-999D01*
G01X494266Y1280172D01*
G03X493973Y1279465I706J-707D01*
G01Y1274579D01*
X491959Y1272565D01*
X367587D01*
X366273Y1273879D01*
Y1280065D01*
G03X365980Y1280772I-999J0D01*
G01X360780Y1285972D01*
G03X360073Y1286265I-707J-706D01*
G01X338087D01*
X335073Y1289279D01*
Y1296419D01*
G03X334780Y1297126I-999J0D01*
G01X329814Y1302092D01*
G03X329107Y1302385I-707J-706D01*
G01X315271D01*
X300161Y1317495D01*
G03X299454Y1317788I-707J-706D01*
G01X267859D01*
X232684Y1352963D01*
G03X231977Y1353256I-707J-706D01*
G01X150494D01*
G03X149787Y1352963I0J-999D01*
G01X142208Y1345384D01*
G03X141915Y1344677I706J-707D01*
G01Y1273375D01*
X123559Y1255019D01*
X115537D01*
X115486Y1255142D01*
G03X112896I-1295J-539D01*
G01X112845Y1255019D01*
X85515D01*
G03X83153I-1181J-757D01*
G01X53612D01*
G03X52028I-792J-1158D01*
G01X29501D01*
G02X29101Y1255411I0J400D01*
G03X27699Y1256783I-1402J-30D01*
G03X26914Y1256543I-1J-1402D01*
G01X26778Y1256450D01*
X26047Y1257181D01*
Y1289975D01*
G03X26045Y1290032I-1000J-7D01*
G01Y1318459D01*
X35051Y1327465D01*
X87907D01*
G03X88614Y1327758I0J999D01*
G01X99404Y1338548D01*
G03X99697Y1339255I-706J707D01*
G01Y1369350D01*
X146012Y1415665D01*
X223341D01*
X223384Y1415642D01*
G03X224077Y1415473I692J1333D01*
G03X224770Y1415642I1J1502D01*
G01X224813Y1415665D01*
X337843D01*
X342837Y1410671D01*
Y1400345D01*
G03X343130Y1399638I999J0D01*
G01X346620Y1396148D01*
G03X347327Y1395855I707J706D01*
G01X400353D01*
G03X401060Y1396148I0J999D01*
G01X411663Y1406751D01*
X411701Y1406766D01*
G03X412485Y1407475I-551J1397D01*
G01X444741D01*
X444781Y1407328D01*
G03X447679I1449J393D01*
G01X447719Y1407475D01*
X502062D01*
X502088Y1407306D01*
G03X505056I1484J233D01*
G01X505082Y1407475D01*
X507803D01*
G03X508510Y1407768I0J999D01*
G01X509185Y1408443D01*
X509232Y1408458D01*
G03X510206Y1409432I-457J1431D01*
G01X510221Y1409479D01*
X523324Y1422582D01*
X575434D01*
G03X577006I786J1280D01*
G01X689811D01*
G03X692447I1318J722D01*
G01X692811D01*
G03X694129Y1421801I1318J722D01*
G03X694916Y1422024I0J1502D01*
G02X695474Y1421879I209J-341D01*
G03X696784Y1421112I1310J735D01*
G03X697969Y1421691I0J1502D01*
G02X698599I315J-246D01*
G03X699784Y1421112I1185J923D01*
G03X701272Y1422409I0J1502D01*
G01X701296Y1422582D01*
X754049D01*
X754093Y1422442D01*
G03X756747I1327J420D01*
G01X756791Y1422582D01*
G37*
G36*
G01X431220Y511231D02*
G03X431498Y511259I0J1392D01*
G01X431518Y511263D01*
X520166D01*
X520205Y511114D01*
G03X521561Y510067I1356J355D01*
G03X522563Y510488I0J1403D01*
G02X523155Y510466I286J-280D01*
G03X524220Y509970I1065J895D01*
G03X525170Y510345I0J1391D01*
G02X525740Y510322I274J-292D01*
G03X526852Y509829I1112J1008D01*
G03X528335Y511094I0J1502D01*
G01X528362Y511263D01*
X592906D01*
G03X595574I1334J690D01*
G01X611113D01*
G03X611870Y511058I757J1297D01*
G03X612627Y511263I0J1502D01*
G01X782041D01*
G03X784759I1359J639D01*
G01X796572D01*
G03X798268I848J1241D01*
G01X833315D01*
X877633Y466945D01*
G03X878340Y466652I707J706D01*
G01X945747D01*
G03X946454Y466945I0J999D01*
G01X1006111Y526602D01*
X1165827D01*
X1165874Y526467D01*
G03X1167190Y525530I1316J456D01*
G03X1168161Y525925I0J1391D01*
G02X1168719I279J-287D01*
G03X1169690Y525530I971J996D01*
G03X1171006Y526467I0J1393D01*
G01X1171053Y526602D01*
X1171902D01*
G03X1172720Y526360I818J1260D01*
G03X1173538Y526602I0J1502D01*
G01X1314186D01*
X1434253Y406535D01*
G03X1434960Y406242I707J706D01*
G01X1448433D01*
G03X1450159I863J1105D01*
G01X1461781D01*
X1461818Y406089D01*
G03X1464736I1459J357D01*
G01X1464773Y406242D01*
X1469458D01*
X1469495Y406089D01*
G03X1472413I1459J357D01*
G01X1472450Y406242D01*
X1489470D01*
G03X1491298I914J1050D01*
G01X1502926D01*
X1537910Y371258D01*
Y307682D01*
G03X1538203Y306975I999J0D01*
G01X1561073Y284105D01*
G03X1561780Y283812I707J706D01*
G01X1658640D01*
Y260110D01*
G03X1702014I21687J0D01*
G01Y283812D01*
X1755931D01*
X1755960Y283647D01*
G03X1757439Y282409I1479J264D01*
G03X1758587Y282943I0J1501D01*
G02X1759210Y282930I306J-258D01*
G03X1760398Y282346I1189J918D01*
G03X1761707Y283112I0J1501D01*
G02X1762408Y283105I349J-196D01*
G03X1763731Y282315I1323J713D01*
G03X1765222Y283636I0J1502D01*
G01X1765243Y283812D01*
X1775046D01*
X1780010Y278848D01*
Y179079D01*
X1779870Y179035D01*
G03Y176169I450J-1433D01*
G01X1780010Y176125D01*
Y162316D01*
X1763966Y146272D01*
X1693150D01*
X1693116Y146429D01*
G03X1686176I-3470J-760D01*
G01X1686142Y146272D01*
X1683150D01*
X1683116Y146429D01*
G03X1676176I-3470J-760D01*
G01X1676142Y146272D01*
X1527594D01*
X1527569Y146443D01*
G03X1524597I-1486J-218D01*
G01X1524572Y146272D01*
X1520420D01*
G03X1519713Y145979I0J-999D01*
G01X1468266Y94532D01*
X1394435D01*
G03X1392065I-1185J-730D01*
G01X1324269D01*
X1324222Y94667D01*
G03X1321590I-1316J-456D01*
G01X1321543Y94532D01*
X1315411D01*
G03X1312707I-1352J-656D01*
G01X1293129D01*
X1293112Y94535D01*
G03X1292880Y94554I-229J-1373D01*
G03X1292648Y94535I-3J-1392D01*
G01X1292631Y94532D01*
X1131814D01*
X1079740Y146606D01*
Y163694D01*
G03X1079807Y163755I-639J769D01*
G01X1081414Y165362D01*
X1270211D01*
X1270267Y165256D01*
G03X1272919I1326J706D01*
G01X1272975Y165362D01*
X1293379D01*
X1293407Y165354D01*
G03X1293802Y165297I396J1345D01*
G03X1294197Y165354I-1J1402D01*
G01X1294225Y165362D01*
X1299789D01*
X1299817Y165354D01*
G03X1300212Y165297I396J1345D01*
G03X1300607Y165354I-1J1402D01*
G01X1300635Y165362D01*
X1306199D01*
X1306227Y165354D01*
G03X1306622Y165297I396J1345D01*
G03X1307017Y165354I-1J1402D01*
G01X1307045Y165362D01*
X1312610D01*
X1312638Y165354D01*
G03X1313033Y165297I396J1345D01*
G03X1313428Y165354I-1J1402D01*
G01X1313456Y165362D01*
X1319029D01*
X1319057Y165354D01*
G03X1319452Y165297I396J1345D01*
G03X1319847Y165354I-1J1402D01*
G01X1319875Y165362D01*
X1331845D01*
X1331873Y165354D01*
G03X1332268Y165297I396J1345D01*
G03X1332707Y165368I-1J1402D01*
G03X1333307Y165655I-107J994D01*
G01X1334910Y167258D01*
X1335028Y167219D01*
G03X1335471Y167147I444J1330D01*
G01X1335472D01*
G03X1336874Y168549I0J1402D01*
G03X1335500Y169951I-1402J0D01*
G01Y170847D01*
G03Y173651I-28J1402D01*
G01Y175934D01*
X1335519Y175975D01*
G03Y177173I-1266J599D01*
G01X1335500Y177214D01*
Y194834D01*
X1335519Y194875D01*
G03Y196073I-1266J599D01*
G01X1335500Y196114D01*
Y221262D01*
G03X1335207Y221969I-999J0D01*
G01X1332307Y224869D01*
G03X1331600Y225162I-707J-706D01*
G01X1329914D01*
G03X1328208I-853J-1114D01*
G01X1323505D01*
G03X1321799I-853J-1114D01*
G01X1310681D01*
G03X1308975I-853J-1114D01*
G01X1304278D01*
G03X1302572I-853J-1114D01*
G01X1299514D01*
X1297300Y227376D01*
Y315062D01*
X1297310Y315093D01*
G03X1297389Y315571I-1423J481D01*
G03X1297310Y316049I-1502J-3D01*
G01X1297300Y316080D01*
Y323852D01*
G03X1297007Y324559I-999J0D01*
G01X1290267Y331299D01*
G03X1289560Y331592I-707J-706D01*
G01X1078880D01*
G03X1078173Y331299I0J-999D01*
G01X1071093Y324219D01*
G03X1070800Y323512I706J-707D01*
G01Y304376D01*
X1069786Y303362D01*
X1016942D01*
X1016889Y303480D01*
G03X1014151I-1369J-618D01*
G01X1014098Y303362D01*
X940023D01*
G02X939810Y304100I1J400D01*
G03X949492Y321653I-11070J17553D01*
G03X907986I-20753J0D01*
G03X917668Y304100I20752J0D01*
G02X917455Y303362I-214J-338D01*
G01X838940D01*
G03X838233Y303069I0J-999D01*
G01X829393Y294229D01*
X829340Y294215D01*
G03X828218Y292762I380J-1453D01*
G03X828237Y292521I1502J-3D01*
G01X828240Y292505D01*
Y280937D01*
G03X828118Y280345I1380J-593D01*
G03X828240Y279753I1502J1D01*
G01Y277819D01*
X828237Y277803D01*
G03X828218Y277562I1483J-238D01*
G03X828237Y277321I1502J-3D01*
G01X828240Y277305D01*
Y265007D01*
X828233Y264981D01*
G03X828178Y264580I1447J-403D01*
G03X828233Y264179I1502J2D01*
G01X828240Y264153D01*
Y242256D01*
X823746Y237762D01*
X675225D01*
X675200Y237934D01*
G03X672226I-1487J-209D01*
G01X672201Y237762D01*
X648600D01*
G03X647893Y237469I0J-999D01*
G01X635793Y225369D01*
G03X635500Y224662I706J-707D01*
G01Y128276D01*
X631786Y124562D01*
X599845D01*
X599794Y124685D01*
G03X597026I-1384J-582D01*
G01X596975Y124562D01*
X384724D01*
X384624Y124662D01*
X384610Y124714D01*
G03X383552Y125772I-1450J-392D01*
G01X383500Y125786D01*
X360997Y148289D01*
G03X360290Y148582I-707J-706D01*
G01X346282D01*
X346251Y148744D01*
G03X343301I-1475J-282D01*
G01X343270Y148582D01*
X128774D01*
X100240Y177116D01*
Y498698D01*
X119084Y517542D01*
X152530D01*
X158516Y511556D01*
G03X159223Y511263I707J706D01*
G01X161901D01*
G03X163599I849J1239D01*
G01X430922D01*
X430942Y511259D01*
G03X431220Y511231I278J1364D01*
G37*
G36*
G01X150908Y1351256D02*
X231563D01*
X266738Y1316081D01*
G03X267445Y1315788I707J706D01*
G01X283970D01*
X285277Y1314481D01*
Y1167285D01*
G03X285570Y1166578I999J0D01*
G01X314877Y1137271D01*
G03X315584Y1136978I707J706D01*
G01X344410D01*
X344466Y1136871D01*
G03X346756I1145J598D01*
G01X346812Y1136978D01*
X348105D01*
X348161Y1136870D01*
G03X349070Y1136194I1151J599D01*
G01X349160Y1136177D01*
X349967Y1134779D01*
X349936Y1134693D01*
G03X349864Y1134264I1225J-426D01*
G03X352458I1297J0D01*
G03X351403Y1135539I-1298J0D01*
G01X351313Y1135556D01*
X350838Y1136378D01*
G02X351185Y1136978I347J200D01*
G01X351810D01*
X351866Y1136871D01*
G03X354156I1145J598D01*
G01X354212Y1136978D01*
X355505D01*
X355561Y1136870D01*
G03X356470Y1136194I1151J599D01*
G01X356560Y1136177D01*
X357367Y1134779D01*
X357336Y1134693D01*
G03X357264Y1134264I1225J-426D01*
G03X359858I1297J0D01*
G03X358803Y1135539I-1298J0D01*
G01X358713Y1135556D01*
X358238Y1136378D01*
G02X358585Y1136978I347J200D01*
G01X359205D01*
X359261Y1136870D01*
G03X361563I1151J600D01*
G01X361619Y1136978D01*
X362905D01*
X362961Y1136870D01*
G03X363870Y1136194I1151J599D01*
G01X363960Y1136177D01*
X364768Y1134779D01*
X364737Y1134692D01*
G03X364664Y1134264I1225J-429D01*
G03X367260I1298J0D01*
G03X366204Y1135539I-1298J0D01*
G01X366114Y1135556D01*
X365639Y1136378D01*
G02X365985Y1136978I346J200D01*
G01X366605D01*
X366661Y1136870D01*
G03X368963I1151J600D01*
G01X369019Y1136978D01*
X370305D01*
X370361Y1136870D01*
G03X371270Y1136194I1151J599D01*
G01X371360Y1136177D01*
X372168Y1134779D01*
X372137Y1134692D01*
G03X372064Y1134264I1225J-429D01*
G03X374660I1298J0D01*
G03X373604Y1135539I-1298J0D01*
G01X373514Y1135556D01*
X373039Y1136378D01*
G02X373385Y1136978I346J200D01*
G01X374005D01*
X374061Y1136870D01*
G03X376363I1151J600D01*
G01X376419Y1136978D01*
X377705D01*
X377761Y1136870D01*
G03X378670Y1136194I1151J599D01*
G01X378760Y1136177D01*
X379568Y1134779D01*
X379537Y1134692D01*
G03X379464Y1134264I1225J-429D01*
G03X382060I1298J0D01*
G03X381004Y1135539I-1298J0D01*
G01X380914Y1135556D01*
X380439Y1136378D01*
G02X380785Y1136978I346J200D01*
G01X381405D01*
X381461Y1136870D01*
G03X383763I1151J600D01*
G01X383819Y1136978D01*
X385105D01*
X385161Y1136870D01*
G03X386070Y1136194I1151J599D01*
G01X386160Y1136177D01*
X386968Y1134779D01*
X386937Y1134692D01*
G03X386864Y1134264I1225J-429D01*
G03X389460I1298J0D01*
G03X388404Y1135539I-1298J0D01*
G01X388314Y1135556D01*
X387839Y1136378D01*
G02X388185Y1136978I346J200D01*
G01X388805D01*
X388861Y1136870D01*
G03X391163I1151J600D01*
G01X391219Y1136978D01*
X392505D01*
X392561Y1136870D01*
G03X393470Y1136194I1151J599D01*
G01X393560Y1136177D01*
X394368Y1134779D01*
X394337Y1134692D01*
G03X394264Y1134264I1225J-429D01*
G03X396860I1298J0D01*
G03X395804Y1135539I-1298J0D01*
G01X395714Y1135556D01*
X395239Y1136378D01*
G02X395585Y1136978I346J200D01*
G01X396205D01*
X396261Y1136870D01*
G03X398563I1151J600D01*
G01X398619Y1136978D01*
X399905D01*
X399961Y1136870D01*
G03X400870Y1136194I1151J599D01*
G01X400960Y1136177D01*
X401768Y1134779D01*
X401737Y1134692D01*
G03X401664Y1134264I1225J-429D01*
G03X404260I1298J0D01*
G03X403204Y1135539I-1298J0D01*
G01X403114Y1135556D01*
X402639Y1136378D01*
G02X402985Y1136978I346J200D01*
G01X403605D01*
X403661Y1136870D01*
G03X405963I1151J600D01*
G01X406019Y1136978D01*
X407021D01*
X409096Y1134903D01*
X409168Y1134779D01*
X409137Y1134692D01*
G03X409064Y1134264I1225J-429D01*
G03X409781Y1133104I1297J0D01*
G01X409891Y1133049D01*
Y1129066D01*
X409781Y1129010D01*
G03Y1126702I579J-1154D01*
G01X409891Y1126646D01*
Y1126037D01*
G02X409260Y1125710I-400J0D01*
G03X408511Y1125948I-749J-1060D01*
G03X407214Y1124651I0J-1297D01*
G03X408269Y1123376I1298J0D01*
G01X408359Y1123359D01*
X409167Y1121960D01*
X409137Y1121874D01*
G03X409064Y1121447I1225J-429D01*
G03X409781Y1120287I1297J0D01*
G01X409891Y1120232D01*
Y1117188D01*
G03X410184Y1116481I999J0D01*
G01X414626Y1112039D01*
X414618Y1111946D01*
G03X414614Y1111834I1293J-102D01*
G03X415911Y1110536I1298J0D01*
G03X416023Y1110541I-2J1298D01*
G01X416116Y1110549D01*
X416980Y1109685D01*
X416840Y1109543D01*
G03X416464Y1108630I922J-914D01*
G03X417762Y1107332I1298J0D01*
G03X418675Y1107708I-1J1298D01*
G01X418817Y1107848D01*
X419349Y1107316D01*
G02X419194Y1106655I-283J-282D01*
G03X418572Y1106204I417J-1229D01*
G01X416950D01*
G03X415911Y1106724I-1039J-778D01*
G03Y1104128I0J-1298D01*
G03X416950Y1104648I0J1298D01*
G01X418572D01*
G03X419611Y1104128I1039J778D01*
G03X420840Y1105009I0J1298D01*
G02X421501Y1105164I379J-128D01*
G01X423958Y1102707D01*
X423924Y1102593D01*
G03X423869Y1102221I1237J-373D01*
G03X424586Y1101064I1292J0D01*
G01X424697Y1101009D01*
Y1097031D01*
X424586Y1096976D01*
G03X423864Y1095813I576J-1163D01*
G03X423937Y1095385I1298J1D01*
G01X423968Y1095298D01*
X423161Y1093900D01*
X423070Y1093883D01*
G03X422014Y1092608I242J-1275D01*
G03X423311Y1091310I1298J0D01*
G03X424065Y1091552I-1J1298D01*
G02X424697Y1091226I232J-326D01*
G01Y1090616D01*
X424586Y1090561D01*
G03Y1088247I577J-1157D01*
G01X424697Y1088192D01*
Y1087582D01*
G02X424065Y1087256I-400J0D01*
G03X423311Y1087498I-755J-1056D01*
G03X422272Y1086978I0J-1298D01*
G01X420650D01*
G03X419611Y1087498I-1039J-778D01*
G03Y1084902I0J-1298D01*
G03X420650Y1085422I0J1298D01*
G01X422272D01*
G03X423311Y1084902I1039J778D01*
G03X424065Y1085144I-1J1298D01*
G02X424697Y1084818I232J-326D01*
G01Y1084213D01*
X424586Y1084158D01*
G03X423864Y1082995I576J-1163D01*
G03X424586Y1081832I1298J0D01*
G01X424697Y1081777D01*
Y1077799D01*
X424586Y1077744D01*
G03Y1075430I577J-1157D01*
G01X424697Y1075375D01*
Y1071390D01*
X424586Y1071335D01*
G03Y1069021I577J-1157D01*
G01X424697Y1068966D01*
Y1064982D01*
X424586Y1064927D01*
G03Y1062613I577J-1157D01*
G01X424697Y1062558D01*
Y1058573D01*
X424586Y1058518D01*
G03Y1056204I577J-1157D01*
G01X424697Y1056149D01*
Y1052164D01*
X424586Y1052109D01*
G03Y1049795I577J-1157D01*
G01X424697Y1049740D01*
Y1045756D01*
X424586Y1045701D01*
G03Y1043387I577J-1157D01*
G01X424697Y1043332D01*
Y1043000D01*
X424084Y1042387D01*
X423952Y1042463D01*
G03X423312Y1042632I-639J-1123D01*
G03X422020Y1041340I0J-1292D01*
G03X422189Y1040700I1292J-1D01*
G01X422265Y1040568D01*
X420218Y1038521D01*
G03X419925Y1037814I706J-707D01*
G01Y1031961D01*
G03X420218Y1031254I999J0D01*
G01X421534Y1029938D01*
G03X422241Y1029645I707J706D01*
G01X423040D01*
X423795Y1028890D01*
Y1028300D01*
X423323Y1027828D01*
X415636D01*
G03X414929Y1027535I0J-999D01*
G01X414559Y1027165D01*
X414175D01*
Y1027166D01*
X411984D01*
X410742Y1028409D01*
Y1029685D01*
X411074Y1030018D01*
Y1030019D01*
X411427Y1030371D01*
G03X411572Y1030699I-354J353D01*
G03X412073Y1031565I-498J866D01*
G01Y1048565D01*
G03X411780Y1049272I-999J0D01*
G01X405080Y1055972D01*
G03X404373Y1056265I-707J-706D01*
G01X380473D01*
G03X379766Y1055972I0J-999D01*
G01X379212Y1055418D01*
X379111Y1055433D01*
G03X378911Y1055449I-203J-1276D01*
G03X377619Y1054157I0J-1292D01*
G03X377635Y1053957I1292J3D01*
G01X377650Y1053856D01*
X369632Y1045838D01*
X369558Y1045832D01*
G03X368374Y1044648I104J-1288D01*
G01X368368Y1044574D01*
X363000Y1039206D01*
X362870Y1039276D01*
G03X361122Y1037528I-608J-1140D01*
G01X361192Y1037398D01*
X359921Y1036127D01*
X359887Y1036112D01*
G03X359230Y1035455I524J-1181D01*
G01X359215Y1035421D01*
X353513Y1029719D01*
X353398Y1029756D01*
G03X353011Y1029815I-386J-1233D01*
G03X351719Y1028523I0J-1292D01*
G03X351819Y1028025I1292J0D01*
G01X351766Y1027972D01*
G03X351473Y1027265I706J-707D01*
G01Y983428D01*
X351448Y983382D01*
G03X351286Y982756I1130J-626D01*
G03X351448Y982130I1292J0D01*
G01X351473Y982084D01*
Y977017D01*
X351448Y976972D01*
G03X351287Y976347I1131J-625D01*
G03X351448Y975722I1292J0D01*
G01X351473Y975677D01*
Y970611D01*
X351448Y970565D01*
G03X351286Y969939I1130J-626D01*
G03X351448Y969313I1292J0D01*
G01X351473Y969267D01*
Y964202D01*
X351448Y964156D01*
G03X351286Y963530I1130J-626D01*
G03X351448Y962904I1292J0D01*
G01X351473Y962858D01*
Y957794D01*
X351448Y957748D01*
G03X351286Y957122I1130J-626D01*
G03X351448Y956496I1292J0D01*
G01X351473Y956450D01*
Y951385D01*
X351448Y951339D01*
G03X351286Y950713I1130J-626D01*
G03X351448Y950087I1292J0D01*
G01X351473Y950041D01*
Y944976D01*
X351448Y944930D01*
G03X351286Y944304I1130J-626D01*
G03X351448Y943678I1292J0D01*
G01X351473Y943632D01*
Y938568D01*
X351448Y938522D01*
G03X351286Y937896I1130J-626D01*
G03X351448Y937270I1292J0D01*
G01X351473Y937224D01*
Y932160D01*
X351448Y932114D01*
G03X351286Y931488I1130J-626D01*
G03X351448Y930862I1292J0D01*
G01X351473Y930816D01*
Y925751D01*
X351448Y925705D01*
G03X351286Y925079I1130J-626D01*
G03X351448Y924453I1292J0D01*
G01X351473Y924407D01*
Y919943D01*
G03X351581Y919491I1000J0D01*
G03X351286Y918670I997J-822D01*
G03X352578Y917378I1292J0D01*
G03X353233Y917557I-1J1292D01*
G01X353367Y917635D01*
X358685Y912317D01*
X358686Y912237D01*
G03X359953Y910970I1292J25D01*
G01X360033Y910969D01*
X367986Y903016D01*
X367964Y902911D01*
G03X367937Y902649I1265J-263D01*
G03X369229Y901357I1292J0D01*
G03X369491Y901384I-1J1292D01*
G01X369596Y901406D01*
X377341Y893661D01*
X377288Y893538D01*
G03X377187Y893036I1191J-501D01*
G03X378479Y891744I1292J0D01*
G03X378981Y891845I1J1292D01*
G01X379104Y891898D01*
X381317Y889685D01*
Y887598D01*
G03X380880Y886627I860J-971D01*
G03X380953Y886199I1298J1D01*
G01X380984Y886112D01*
X380177Y884715D01*
X380087Y884698D01*
G03X379032Y883423I243J-1275D01*
G03X380329Y882126I1297J0D01*
G03X380778Y882206I1J1297D01*
G02X381317Y881831I139J-375D01*
G01Y881181D01*
G03Y879257I861J-962D01*
G01Y874781D01*
G03X380880Y873810I860J-971D01*
G03X380953Y873382I1298J1D01*
G01X380984Y873295D01*
X380177Y871898D01*
X380087Y871881D01*
G03X379032Y870606I243J-1275D01*
G03X379035Y870506I1297J-11D01*
G01X379042Y870414D01*
X378520Y869892D01*
G02X377890Y869975I-283J282D01*
G01X377823Y870091D01*
X377854Y870177D01*
G03X377926Y870606I-1225J426D01*
G03X375332I-1297J0D01*
G03X376387Y869331I1298J0D01*
G01X376477Y869314D01*
X377013Y868385D01*
X373970Y865342D01*
G03X373677Y864635I706J-707D01*
G01Y861682D01*
X373651Y861636D01*
G03X373480Y860993I1127J-644D01*
G03X373553Y860565I1298J1D01*
G01X373584Y860478D01*
X372777Y859081D01*
X372687Y859064D01*
G03X372000Y858695I242J-1275D01*
G01X370158D01*
G03X369229Y859086I-928J-906D01*
G03X368300Y858695I-1J-1297D01*
G01X367642D01*
G02X367295Y859295I0J400D01*
G01X367530Y859701D01*
X367620Y859718D01*
G03X368676Y860993I-242J1275D01*
G03X366080I-1298J0D01*
G03X366153Y860565I1298J1D01*
G01X366184Y860478D01*
X365377Y859081D01*
X365287Y859064D01*
G03X364600Y858695I242J-1275D01*
G01X362758D01*
G03X361829Y859086I-928J-906D01*
G03X360900Y858695I-1J-1297D01*
G01X360242D01*
G02X359895Y859295I0J400D01*
G01X360130Y859701D01*
X360220Y859718D01*
G03X361276Y860993I-242J1275D01*
G03X358680I-1298J0D01*
G03X358753Y860565I1298J1D01*
G01X358784Y860478D01*
X357977Y859081D01*
X357887Y859064D01*
G03X357200Y858695I242J-1275D01*
G01X355358D01*
G03X354429Y859086I-928J-906D01*
G03X353500Y858695I-1J-1297D01*
G01X353031D01*
X352472Y859254D01*
X352730Y859701D01*
X352820Y859718D01*
G03X353876Y860993I-242J1275D01*
G03X351280I-1298J0D01*
G03X351282Y860924I1298J3D01*
G02X350861Y860504I-399J-21D01*
G03X350807Y860505I-46J-999D01*
G01X293247D01*
X293223Y860511D01*
G03X292973Y860543I-251J-968D01*
G01X202343D01*
X202316Y860710D01*
G03X199766I-1275J-211D01*
G01X199739Y860543D01*
X186201D01*
X186174Y860710D01*
G03X183624I-1275J-211D01*
G01X183597Y860543D01*
X142943D01*
X142916Y860710D01*
G03X140366I-1275J-211D01*
G01X140339Y860543D01*
X127073D01*
X126734Y860882D01*
X126719Y860925D01*
G03X125925Y861719I-1220J-426D01*
G01X125882Y861734D01*
X124973Y862643D01*
Y1253605D01*
X132227Y1260859D01*
X132354Y1260801D01*
G03X132941Y1260672I587J1273D01*
G03X134343Y1262074I0J1402D01*
G03X134214Y1262661I-1402J0D01*
G01X134156Y1262788D01*
X143622Y1272254D01*
G03X143915Y1272961I-706J707D01*
G01Y1344263D01*
X150908Y1351256D01*
G37*
G36*
G01X471868Y1065765D02*
X472907D01*
G03X473773Y1065265I866J500D01*
G01X519459D01*
X520262Y1064462D01*
X520200Y1064334D01*
G03X520070Y1063770I1162J-565D01*
G03X521362Y1062478I1292J0D01*
G03X521926Y1062608I-1J1292D01*
G01X522054Y1062670D01*
X527473Y1057251D01*
X527482Y1057184D01*
G03X528585Y1056081I1280J177D01*
G01X528652Y1056072D01*
X529668Y1055056D01*
X529567Y1054918D01*
G03X529319Y1054157I1044J-761D01*
G03X530611Y1052865I1292J0D01*
G03X531502Y1053222I-1J1292D01*
G01X533836Y1050888D01*
G03X534543Y1050595I707J706D01*
G01X534912D01*
X534962Y1050470D01*
G03X537360I1199J482D01*
G01X537410Y1050595D01*
X552753D01*
X556627Y1046721D01*
Y910419D01*
X553970Y907762D01*
X534970D01*
G03X534263Y907469I0J-999D01*
G01X533940Y907146D01*
X533859Y907145D01*
G03X532587Y905873I20J-1292D01*
G01X532586Y905792D01*
X527265Y900471D01*
G03X526479Y900737I-785J-1026D01*
G03X525187Y899445I0J-1292D01*
G03X525453Y898659I1292J-1D01*
G01X524278Y897484D01*
X524233Y897470D01*
G03X523399Y896636I396J-1230D01*
G01X523385Y896591D01*
X521659Y894865D01*
X508773D01*
G03X508066Y894572I0J-999D01*
G01X507813Y894319D01*
X507751Y894308D01*
G03X506706Y893263I227J-1272D01*
G01X506695Y893201D01*
X501766Y888272D01*
G03X501581Y888016I707J-706D01*
G02X501072Y887827I-357J181D01*
G03X500578Y887924I-492J-1200D01*
G03X499280Y886627I0J-1298D01*
G03X499353Y886199I1298J1D01*
G01X499384Y886112D01*
X498577Y884715D01*
X498487Y884698D01*
G03X497432Y883423I243J-1275D01*
G03X500026I1297J0D01*
G03X499954Y883851I-1297J2D01*
G01X499923Y883938D01*
X500730Y885335D01*
X500820Y885352D01*
G03X500956Y885386I-246J1274D01*
G02X501473Y885003I117J-383D01*
G01Y884300D01*
G03Y882546I957J-877D01*
G01Y877883D01*
G03Y876145I956J-869D01*
G01Y875434D01*
G02X500956Y875051I-400J0D01*
G03X500578Y875108I-380J-1241D01*
G03X499280Y873810I0J-1298D01*
G03X500336Y872535I1298J0D01*
G01X500426Y872518D01*
X501234Y871119D01*
X501203Y871032D01*
G03X501132Y870606I1226J-423D01*
G03X501473Y869729I1298J0D01*
G01Y865066D01*
G03Y863328I956J-869D01*
G01Y862617D01*
G02X500956Y862234I-400J0D01*
G03X500578Y862290I-377J-1241D01*
G03X499280Y860993I0J-1298D01*
G03X500336Y859718I1298J0D01*
G01X500426Y859701D01*
X501234Y858302D01*
X501203Y858215D01*
G03X501132Y857789I1226J-423D01*
G03X501473Y856912I1298J0D01*
G01Y852249D01*
G03Y850511I956J-869D01*
G01Y849800D01*
G02X500956Y849417I-400J0D01*
G03X500578Y849474I-380J-1241D01*
G03X499280Y848176I0J-1298D01*
G03X500336Y846901I1298J0D01*
G01X500426Y846884D01*
X501233Y845486D01*
X501202Y845400D01*
G03X501130Y844971I1225J-426D01*
G03X502427Y843674I1297J0D01*
G03X503624Y844471I0J1297D01*
G02X504102Y844702I369J-154D01*
G03X504373Y844665I269J963D01*
G01X504858D01*
X504906Y844533D01*
G03X504941Y844444I1224J430D01*
G01X504980Y844356D01*
X504139Y842761D01*
X504044Y842743D01*
G03X502982Y841467I236J-1276D01*
G03X505576I1297J0D01*
G03X505465Y841994I-1297J2D01*
G01X505426Y842082D01*
X506267Y843677D01*
X506362Y843695D01*
G03X507348Y844533I-235J1276D01*
G01X507396Y844665D01*
X508558D01*
X508606Y844533D01*
G03X511048I1221J438D01*
G01X511096Y844665D01*
X512258D01*
X512306Y844533D01*
G03X512341Y844444I1224J430D01*
G01X512380Y844356D01*
X511539Y842761D01*
X511444Y842743D01*
G03X510382Y841467I236J-1276D01*
G03X512976I1297J0D01*
G03X512865Y841994I-1297J2D01*
G01X512826Y842082D01*
X513667Y843677D01*
X513762Y843695D01*
G03X514748Y844533I-235J1276D01*
G01X514796Y844665D01*
X515958D01*
X516006Y844533D01*
G03X518448I1221J438D01*
G01X518496Y844665D01*
X519658D01*
X519706Y844533D01*
G03X519741Y844444I1224J430D01*
G01X519780Y844356D01*
X518939Y842761D01*
X518844Y842743D01*
G03X517782Y841467I236J-1276D01*
G03X520376I1297J0D01*
G03X520265Y841994I-1297J2D01*
G01X520226Y842082D01*
X521067Y843677D01*
X521162Y843695D01*
G03X522148Y844533I-235J1276D01*
G01X522196Y844665D01*
X523358D01*
X523406Y844533D01*
G03X525848I1221J438D01*
G01X525896Y844665D01*
X527025D01*
X527049Y844493D01*
G03X529609I1280J178D01*
G01X529633Y844665D01*
X530719D01*
X530743Y844493D01*
G03X533313I1285J178D01*
G01X533337Y844665D01*
X534425D01*
X534449Y844493D01*
G03X537009I1280J178D01*
G01X537033Y844665D01*
X594257D01*
X594275Y844662D01*
G03X594457Y844645I184J983D01*
G01X595457D01*
G03X595639Y844662I-2J1000D01*
G01X595657Y844665D01*
X596257D01*
X596275Y844662D01*
G03X596457Y844645I184J983D01*
G01X605283D01*
X606867Y843061D01*
Y773043D01*
X600393Y766569D01*
G03X600100Y765862I706J-707D01*
G01Y760376D01*
X385999Y546275D01*
X254704D01*
G03X254634Y546352I-774J-633D01*
G01X254588Y546398D01*
G03X253881Y546691I-707J-706D01*
G03X253069Y546275I0J-1000D01*
G01X243811D01*
X241710Y548376D01*
Y569170D01*
G03Y571810I-717J1320D01*
G01Y592900D01*
G03X242495Y594220I-717J1320D01*
G03X242089Y595247I-1502J0D01*
G02Y595793I292J273D01*
G03X242495Y596820I-1096J1027D01*
G03X241710Y598140I-1502J0D01*
G01Y603170D01*
G03Y605810I-717J1320D01*
G01Y626900D01*
G03X242495Y628220I-717J1320D01*
G03X242089Y629247I-1502J0D01*
G02Y629793I292J273D01*
G03X242495Y630820I-1096J1027D01*
G03X241977Y631955I-1502J0D01*
G02X241956Y632540I262J302D01*
G01X244118Y634702D01*
X278086D01*
X282633Y630155D01*
G03X283340Y629862I707J706D01*
G01X285376D01*
G03X287788I1206J895D01*
G01X295181D01*
G03X297629I1224J869D01*
G01X314975D01*
G03X315682Y630155I0J999D01*
G01X454880Y769353D01*
G03X455173Y770060I-706J707D01*
G01Y843987D01*
G03X455624Y844971I-846J983D01*
G03X455173Y845955I-1297J1D01*
G01Y846590D01*
G02X455716Y846964I400J0D01*
G03X455936Y846901I466J1211D01*
G01X456026Y846884D01*
X456833Y845486D01*
X456802Y845400D01*
G03X456730Y844971I1225J-426D01*
G03X459324I1297J0D01*
G03X458269Y846246I-1298J0D01*
G01X458179Y846263D01*
X457372Y847661D01*
X457403Y847747D01*
G03X457476Y848176I-1224J429D01*
G03X456178Y849474I-1298J0D01*
G03X455716Y849388I3J-1298D01*
G02X455173Y849762I-143J374D01*
G01Y850403D01*
G03Y852357I-844J977D01*
G01Y856804D01*
G03Y858774I-844J985D01*
G01Y859407D01*
G02X455716Y859781I400J0D01*
G03X455936Y859718I466J1211D01*
G01X456026Y859701D01*
X456834Y858302D01*
X456803Y858215D01*
G03X456732Y857789I1226J-423D01*
G03X459326I1297J0D01*
G03X458268Y859064I-1297J0D01*
G01X458178Y859081D01*
X457372Y860478D01*
X457403Y860564D01*
G03X457476Y860993I-1224J429D01*
G03X456178Y862290I-1297J0D01*
G03X455716Y862205I0J-1298D01*
G02X455173Y862579I-143J374D01*
G01Y863219D01*
G03Y865175I-844J978D01*
G01Y869621D01*
G03Y871591I-844J985D01*
G01Y872224D01*
G02X455716Y872598I400J0D01*
G03X455936Y872535I466J1211D01*
G01X456026Y872518D01*
X456834Y871119D01*
X456803Y871032D01*
G03X456732Y870606I1226J-423D01*
G03X459326I1297J0D01*
G03X458268Y871881I-1297J0D01*
G01X458178Y871898D01*
X457372Y873295D01*
X457403Y873381D01*
G03X457476Y873810I-1224J429D01*
G03X456178Y875108I-1298J0D01*
G03X455716Y875022I3J-1298D01*
G02X455173Y875396I-143J374D01*
G01Y876036D01*
G03Y877992I-844J978D01*
G01Y882438D01*
G03X455626Y883423I-844J985D01*
G03X455554Y883851I-1297J2D01*
G01X455523Y883938D01*
X456330Y885335D01*
X456420Y885352D01*
G03X457476Y886627I-242J1275D01*
G03X456178Y887924I-1297J0D01*
G03X455716Y887839I0J-1298D01*
G02X455173Y888213I-143J374D01*
G01Y888854D01*
G03Y890810I-844J978D01*
G01Y895262D01*
G03X455621Y896240I-844J978D01*
G03X455602Y896460I-1292J-1D01*
G01X455584Y896562D01*
X463581Y904559D01*
X463656Y904563D01*
G03X464868Y905775I-78J1290D01*
G01X464872Y905850D01*
X470225Y911203D01*
X470357Y911130D01*
G03X470980Y910970I623J1133D01*
G03X472272Y912262I0J1292D01*
G03X472112Y912885I-1293J0D01*
G01X472039Y913017D01*
X473275Y914253D01*
X473313Y914268D01*
G03X474026Y914981I-485J1198D01*
G01X474041Y915019D01*
X479708Y920686D01*
X479825Y920648D01*
G03X480229Y920583I405J1227D01*
G03X481521Y921875I0J1292D01*
G03X481456Y922279I-1292J-1D01*
G01X481418Y922396D01*
X489237Y930215D01*
X489333Y930204D01*
G03X489478Y930196I144J1284D01*
G03X490770Y931488I0J1292D01*
G03X490762Y931633I-1292J1D01*
G01X490751Y931729D01*
X495985Y936963D01*
G03X496879Y936604I894J934D01*
G03X498171Y937896I0J1292D01*
G03X497921Y938660I-1292J0D01*
G01X497820Y938798D01*
X498832Y939810D01*
X498899Y939819D01*
G03X500010Y940930I-170J1281D01*
G01X500019Y940997D01*
X501664Y942642D01*
G03X501957Y943349I-706J707D01*
G01Y1002008D01*
G03Y1003768I-946J880D01*
G01Y1008417D01*
G03Y1010177I-946J880D01*
G01Y1014824D01*
G03Y1016586I-945J881D01*
G01Y1021234D01*
G03Y1022994I-946J880D01*
G01Y1027643D01*
G03X502303Y1028523I-946J880D01*
G03X501011Y1029815I-1292J0D01*
G03X500461Y1029692I0J-1291D01*
G01X500334Y1029632D01*
X497594Y1032372D01*
G03X496887Y1032665I-707J-706D01*
G01X496349D01*
G03X494573I-888J-937D01*
G01X492650D01*
G03X490874I-888J-937D01*
G01X488950D01*
G03X487174I-888J-937D01*
G01X485249D01*
G03X483473I-888J-937D01*
G01X481550D01*
G03X480662Y1033019I-888J-937D01*
G03X479446Y1032164I0J-1292D01*
G03X479119Y1032019I26J-500D01*
G01X478766Y1031666D01*
X478765D01*
X477772Y1030673D01*
Y1029852D01*
G03Y1027194I1039J-1329D01*
G01Y1025672D01*
X477126Y1025027D01*
X475780Y1026372D01*
G03X475073Y1026665I-707J-706D01*
G01X468374D01*
X467673Y1027366D01*
Y1035610D01*
X467806Y1035657D01*
G03Y1038091I-434J1217D01*
G01X467673Y1038138D01*
Y1063058D01*
X470380Y1065765D01*
X470954D01*
X470986Y1065754D01*
G03X471411Y1065682I425J1220D01*
G03X471836Y1065754I0J1292D01*
G01X471868Y1065765D01*
G37*
G36*
G01X478773Y1030258D02*
X479258Y1030743D01*
G02X479806Y1030760I283J-283D01*
G03X480662Y1030435I857J967D01*
G03X481398Y1030665I0J1293D01*
G01X483625D01*
G03X485097I736J1063D01*
G01X487326D01*
G03X488798I736J1063D01*
G01X491026D01*
G03X492498I736J1063D01*
G01X494725D01*
G03X495461Y1030435I736J1063D01*
G03X496150Y1030634I0J1292D01*
G01X496199Y1030665D01*
X496473D01*
X499957Y1027181D01*
Y1022861D01*
G03Y1021367I1053J-747D01*
G01Y1016451D01*
G03Y1014959I1056J-746D01*
G01Y1010044D01*
G03Y1008550I1053J-747D01*
G01Y1003635D01*
G03Y1002141I1053J-747D01*
G01Y983889D01*
G03Y981623I621J-1133D01*
G01Y977480D01*
G03Y975214I621J-1133D01*
G01Y971072D01*
G03Y968806I621J-1133D01*
G01Y964662D01*
G03Y962398I621J-1132D01*
G01Y958255D01*
G03Y955989I621J-1133D01*
G01Y951846D01*
G03Y949580I621J-1133D01*
G01Y945437D01*
G03X499286Y944304I621J-1133D01*
G03X499625Y943431I1292J-1D01*
G01X498579Y942385D01*
X498516Y942374D01*
G03X497455Y941313I213J-1274D01*
G01X497444Y941250D01*
X491999Y935805D01*
X491872Y935863D01*
G03X491329Y935983I-544J-1172D01*
G03X490037Y934691I0J-1292D01*
G03X490157Y934148I1292J1D01*
G01X490215Y934021D01*
X488748Y932554D01*
X488734Y932545D01*
G03X488412Y932218I745J-1056D01*
G01X482500Y926306D01*
X482390Y926333D01*
G03X482078Y926371I-311J-1254D01*
G03X480786Y925079I0J-1292D01*
G03X480824Y924767I1292J-1D01*
G01X480851Y924657D01*
X472949Y916755D01*
X472863Y916758D01*
X472828D01*
G03X471536Y915466I0J-1292D01*
G01Y915431D01*
X471539Y915345D01*
X466256Y910062D01*
X466121Y910148D01*
G03X465429Y910349I-692J-1091D01*
G03X464137Y909057I0J-1292D01*
G03X464338Y908365I1292J0D01*
G01X464424Y908230D01*
X463313Y907119D01*
X463259Y907105D01*
G03X462326Y906172I319J-1252D01*
G01X462312Y906118D01*
X456786Y900592D01*
X456664Y900642D01*
G03X456178Y900737I-486J-1196D01*
G03X454886Y899445I0J-1292D01*
G03X454981Y898959I1291J0D01*
G01X455031Y898837D01*
X453466Y897272D01*
G03X453251Y896952I707J-707D01*
G03X453037Y896240I1077J-712D01*
G03X453155Y895701I1292J0D01*
G01X453173Y895661D01*
Y890411D01*
X453155Y890371D01*
G03X453037Y889832I1174J-539D01*
G03X453155Y889293I1292J0D01*
G01X453173Y889253D01*
Y884014D01*
X453154Y883974D01*
G03Y882872I1183J-551D01*
G01X453173Y882832D01*
Y881433D01*
X452939D01*
X452907Y881444D01*
G03X452719Y881494I-427J-1225D01*
G01X452629Y881511D01*
X451823Y882908D01*
X451854Y882994D01*
G03X451926Y883423I-1225J426D01*
G03X449332I-1297J0D01*
G03X450387Y882148I1298J0D01*
G01X450477Y882131D01*
X451284Y880733D01*
X451254Y880646D01*
G03X451182Y880219I1225J-426D01*
G03X452479Y878922I1297J0D01*
G03X452704Y878941I4J1297D01*
G02X453173Y878547I69J-394D01*
G01Y877593D01*
X453155Y877553D01*
G03X453037Y877014I1174J-539D01*
G03X453155Y876475I1292J0D01*
G01X453173Y876435D01*
Y871197D01*
X453154Y871157D01*
G03X453032Y870606I1183J-551D01*
G03X453104Y870178I1297J-2D01*
G01X453135Y870091D01*
X452328Y868693D01*
X452238Y868676D01*
G03X451180Y867401I239J-1275D01*
G03X452478Y866104I1297J0D01*
G03X452704Y866123I5J1297D01*
G02X453173Y865729I69J-394D01*
G01Y864776D01*
X453155Y864736D01*
G03X453037Y864197I1174J-539D01*
G03X453155Y863658I1292J0D01*
G01X453173Y863618D01*
Y858380D01*
X453154Y858340D01*
G03X453032Y857789I1183J-551D01*
G03X453104Y857361I1297J-2D01*
G01X453135Y857274D01*
X452328Y855876D01*
X452238Y855859D01*
G03X451180Y854584I239J-1275D01*
G03X452478Y853286I1298J0D01*
G03X452704Y853306I-1J1298D01*
G02X453173Y852912I69J-394D01*
G01Y851961D01*
X453155Y851921D01*
G03X453036Y851380I1173J-542D01*
G03X453155Y850839I1292J1D01*
G01X453173Y850799D01*
Y845566D01*
X453154Y845525D01*
G03X453030Y844971I1173J-553D01*
G03X453141Y844444I1297J-2D01*
G01X453180Y844356D01*
X452339Y842761D01*
X452244Y842743D01*
G03X451182Y841467I236J-1276D01*
G03X452479Y840170I1297J0D01*
G03X452704Y840189I4J1297D01*
G02X453173Y839795I69J-394D01*
G01Y770474D01*
X314561Y631862D01*
X297394D01*
G03X295416I-989J-1129D01*
G01X287599D01*
G03X285565I-1017J-1104D01*
G01X283754D01*
X279207Y636409D01*
G03X278500Y636702I-707J-706D01*
G01X243870D01*
X242452Y638120D01*
X242471Y638223D01*
G03X242495Y638490I-1478J267D01*
G03X241710Y639810I-1502J0D01*
G01Y659248D01*
X241716Y659272D01*
G03X241747Y659519I-969J247D01*
G03X241716Y659766I-1000J0D01*
G01X241710Y659790D01*
Y664573D01*
X241711Y664585D01*
G03X241718Y664700I-993J118D01*
G01Y664812D01*
G03X241711Y664927I-1000J-3D01*
G01X241710Y664939D01*
Y668658D01*
X243514Y670462D01*
X258600D01*
G03X259307Y670755I0J999D01*
G01X268414Y679862D01*
X295197D01*
G03X295904Y680155I0J999D01*
G01X304130Y688381D01*
G03X304336Y688680I-707J707D01*
G01X339262Y766940D01*
G03X339315Y767089I-913J409D01*
G01X341987Y777045D01*
X342076Y777083D01*
G03X342919Y778362I-549J1279D01*
G03X342643Y779194I-1392J0D01*
G01X342585Y779272D01*
X348809Y802461D01*
X348983Y802439D01*
G03X350098Y802368I1113J8683D01*
G03X358852Y811122I0J8754D01*
G03X358134Y814595I-8754J1D01*
G01X358065Y814756D01*
X397737Y838669D01*
G03X398221Y839525I-515J856D01*
G01Y841110D01*
X398228Y841135D01*
G03X398271Y841467I-1249J331D01*
G03X398228Y841799I-1292J1D01*
G01X398221Y841824D01*
Y843286D01*
G02X398670Y843683I400J0D01*
G03X398827Y843674I153J1288D01*
G03X400124Y844971I0J1297D01*
G03X399069Y846246I-1298J0D01*
G01X398979Y846263D01*
X398221Y847577D01*
Y847803D01*
X398228Y847829D01*
G03X398276Y848176I-1250J350D01*
G03X398228Y848523I-1298J-3D01*
G01X398221Y848549D01*
Y854227D01*
X398228Y854252D01*
G03X398271Y854584I-1249J331D01*
G03X398228Y854916I-1292J1D01*
G01X398221Y854941D01*
Y856548D01*
X398449D01*
X398475Y856541D01*
G03X398587Y856514I360J1247D01*
G01X398677Y856497D01*
X399484Y855099D01*
X399453Y855013D01*
G03X399380Y854584I1224J-429D01*
G03X401976I1298J0D01*
G03X400920Y855859I-1298J0D01*
G01X400830Y855876D01*
X400023Y857274D01*
X400054Y857360D01*
G03X400126Y857789I-1225J426D01*
G03X398829Y859086I-1297J0D01*
G03X398670Y859077I-6J-1297D01*
G02X398221Y859474I-49J397D01*
G01Y860620D01*
X398228Y860646D01*
G03X398276Y860993I-1250J350D01*
G03X398228Y861340I-1298J-3D01*
G01X398221Y861366D01*
Y862518D01*
G02X398670Y862915I400J0D01*
G03X398829Y862905I160J1282D01*
G03X400121Y864197I0J1292D01*
G03X400056Y864600I-1292J-2D01*
G01X400018Y864717D01*
X404974Y869673D01*
G03X405003Y869703I-704J710D01*
G02X405294Y869706I147J-135D01*
G03X405987Y869331I935J900D01*
G01X406077Y869314D01*
X406884Y867916D01*
X406853Y867830D01*
G03X406780Y867401I1224J-429D01*
G03X409376I1298J0D01*
G03X408320Y868676I-1298J0D01*
G01X408230Y868693D01*
X407423Y870091D01*
X407454Y870177D01*
G03X407526Y870606I-1225J426D01*
G03X406229Y871904I-1298J0D01*
G03X405799Y871830I2J-1298D01*
G02X405267Y872208I-132J378D01*
G01Y872865D01*
G03X405676Y873810I-889J946D01*
G03X405267Y874755I-1298J-1D01*
G01Y879281D01*
G03Y881157I-887J938D01*
G01Y881821D01*
G02X405799Y882199I400J0D01*
G03X405987Y882148I433J1223D01*
G01X406077Y882131D01*
X406883Y880734D01*
X406853Y880647D01*
G03X406780Y880219I1225J-429D01*
G03X409376I1298J0D01*
G03X408319Y881494I-1297J0D01*
G01X408229Y881511D01*
X407423Y882908D01*
X407454Y882994D01*
G03X407526Y883423I-1225J426D01*
G03X406229Y884720I-1297J0D01*
G03X405799Y884647I-1J-1297D01*
G02X405267Y885025I-132J378D01*
G01Y885682D01*
G03X405676Y886627I-889J946D01*
G03X405267Y887572I-1298J-1D01*
G01Y892098D01*
G03Y893974I-890J938D01*
G01Y898507D01*
G03Y900383I-890J938D01*
G01Y901525D01*
G03X404974Y902232I-999J0D01*
G01X401869Y905337D01*
X401907Y905454D01*
G03X401970Y905853I-1229J399D01*
G03X400678Y907145I-1292J0D01*
G03X400279Y907082I0J-1292D01*
G01X400162Y907044D01*
X394487Y912719D01*
X394472Y912756D01*
G03X393772Y913456I-1194J-494D01*
G01X393735Y913471D01*
X392491Y914715D01*
X392563Y914846D01*
G03X392721Y915466I-1134J619D01*
G03X391429Y916758I-1292J0D01*
G03X390809Y916600I-1J-1292D01*
G01X390678Y916528D01*
X385323Y921883D01*
X385318Y921958D01*
G03X384112Y923164I-1289J-83D01*
G01X384037Y923169D01*
X381837Y925369D01*
Y998967D01*
G03Y1000401I-1076J717D01*
G01Y1005376D01*
G03Y1006810I-1076J717D01*
G01Y1011784D01*
G03Y1013218I-1076J717D01*
G01Y1018193D01*
G03Y1019627I-1076J717D01*
G01Y1024604D01*
G03X382052Y1025318I-1078J714D01*
G03X382050Y1025390I-1292J0D01*
G01X382045Y1025479D01*
X383431Y1026865D01*
X403259D01*
X403808Y1026316D01*
X403823Y1026283D01*
G03X404460Y1025646I1175J538D01*
G01X404493Y1025631D01*
X404873Y1025251D01*
Y1023724D01*
X404715Y1023690D01*
G03Y1021164I271J-1263D01*
G01X404873Y1021130D01*
Y1017969D01*
X404013Y1017109D01*
G03X403720Y1016402I706J-707D01*
G01Y1013495D01*
G03X404013Y1012788I999J0D01*
G01X404873Y1011928D01*
Y1008406D01*
X404747Y1008356D01*
G03X403935Y1007156I481J-1200D01*
G03X404284Y1006273I1292J0D01*
G02X404285Y1005728I-292J-273D01*
G03X403939Y1004848I946J-880D01*
G03X404748Y1003650I1292J0D01*
G01X404873Y1003599D01*
Y996551D01*
X404730Y996509D01*
G03X403809Y995271I372J-1238D01*
G03X404153Y994393I1292J0D01*
G02Y993849I-293J-272D01*
G03X403809Y992971I948J-878D01*
G03X404730Y991733I1293J0D01*
G01X404873Y991691D01*
Y978365D01*
G03X405166Y977658I999J0D01*
G01X407066Y975758D01*
G03X407773Y975465I707J706D01*
G01X410959D01*
X412873Y973551D01*
Y969679D01*
X412159Y968965D01*
X407773D01*
G03X407066Y968672I0J-999D01*
G01X405523Y967129D01*
X405415Y967154D01*
G03X405122Y967188I-294J-1258D01*
G03X403830Y965896I0J-1292D01*
G03X404174Y965018I1292J0D01*
G02Y964474I-293J-272D01*
G03X403830Y963596I948J-878D01*
G03X404560Y962433I1291J0D01*
G01X404673Y962378D01*
Y949748D01*
X404563Y949693D01*
G03X403853Y948539I583J-1154D01*
G03X404197Y947661I1292J0D01*
G02Y947117I-293J-272D01*
G03X403853Y946239I948J-878D01*
G03X404563Y945085I1293J0D01*
G01X404673Y945030D01*
Y943300D01*
G03X403997Y942164I617J-1136D01*
G03X405289Y940872I1292J0D01*
G03X405781Y940969I1J1292D01*
G01X405904Y941020D01*
X410266Y936658D01*
G03X410973Y936365I707J706D01*
G01X426577D01*
X426610Y936206D01*
G03X429140I1265J264D01*
G01X429173Y936365D01*
X454073D01*
G03X454780Y936658I0J999D01*
G01X456780Y938658D01*
G03X457073Y939365I-706J707D01*
G01Y944551D01*
X463987Y951465D01*
X474273D01*
G03X474980Y951758I0J999D01*
G01X477180Y953958D01*
G03X477473Y954665I-706J707D01*
G01Y957965D01*
G03X477180Y958672I-999J0D01*
G01X476080Y959772D01*
G03X475373Y960065I-707J-706D01*
G01X473187D01*
X468000Y965252D01*
Y971378D01*
X476087Y979465D01*
X476184Y979454D01*
G03X476335Y979445I152J1283D01*
G03X477627Y980737I0J1292D01*
G03X477599Y981002I-1292J-3D01*
G03X477773Y981565I-825J563D01*
G01Y1023966D01*
G03X477760Y1024127I-1000J0D01*
G01X477743Y1024228D01*
X478627Y1025111D01*
G03X478773Y1025463I-354J353D01*
G01Y1030258D01*
G37*
G36*
G01X380887Y1054265D02*
X403510D01*
X403521Y1054077D01*
G03X404811Y1052865I1290J81D01*
G03X405165Y1052914I2J1292D01*
G01X405278Y1052946D01*
X410073Y1048151D01*
Y1045811D01*
X409939Y1045765D01*
G03Y1043323I423J-1221D01*
G01X410073Y1043277D01*
Y1031565D01*
G03X410306Y1030924I1000J1D01*
G01X410423Y1030783D01*
X409886Y1030246D01*
G03X409740Y1029894I354J-353D01*
G01Y1028200D01*
G03X409886Y1027848I500J1D01*
G01X411423Y1026311D01*
G03X411775Y1026165I353J354D01*
G01X412987D01*
G02X413383Y1025708I0J-400D01*
G03X413373Y1025565I990J-141D01*
G01Y1012179D01*
X411959Y1010765D01*
X408158D01*
G03X408131Y1010793I-733J-680D01*
G01X406873Y1012051D01*
Y1012342D01*
G03X406580Y1013049I-999J0D01*
G01X405720Y1013909D01*
Y1015988D01*
X406580Y1016848D01*
G03X406873Y1017555I-706J707D01*
G01Y1025665D01*
G03X406580Y1026372I-999J0D01*
G01X406284Y1026668D01*
X406288Y1026757D01*
G03X406290Y1026821I-1290J72D01*
G03X404998Y1028113I-1292J0D01*
G03X404934Y1028111I8J-1292D01*
G01X404845Y1028107D01*
X404380Y1028572D01*
G03X403673Y1028865I-707J-706D01*
G01X402364D01*
X402315Y1028992D01*
G03X399907I-1204J-469D01*
G01X399858Y1028865D01*
X398664D01*
X398615Y1028992D01*
G03X396207I-1204J-469D01*
G01X396158Y1028865D01*
X394964D01*
X394915Y1028992D01*
G03X392507I-1204J-469D01*
G01X392458Y1028865D01*
X391264D01*
X391215Y1028992D01*
G03X388807I-1204J-469D01*
G01X388758Y1028865D01*
X387564D01*
X387515Y1028992D01*
G03X385107I-1204J-469D01*
G01X385058Y1028865D01*
X383864D01*
X383815Y1028992D01*
G03X382611Y1029815I-1204J-469D01*
G03X381319Y1028523I0J-1292D01*
G03X381465Y1027925I1292J-1D01*
G01X381533Y1027795D01*
X380239Y1026501D01*
X380207Y1026486D01*
G03X379468Y1025318I554J-1168D01*
G03X379837Y1024414I1292J0D01*
G01Y1019812D01*
G03Y1018008I925J-902D01*
G01Y1013403D01*
G03Y1011599I925J-902D01*
G01Y1006995D01*
G03Y1005191I925J-902D01*
G01Y1000586D01*
G03Y998782I925J-902D01*
G01Y980753D01*
X379730Y980697D01*
G03Y978407I599J-1145D01*
G01X379837Y978351D01*
Y974344D01*
X379730Y974288D01*
G03Y971998I598J-1145D01*
G01X379837Y971942D01*
Y967936D01*
X379730Y967880D01*
G03Y965590I599J-1145D01*
G01X379837Y965534D01*
Y961527D01*
X379730Y961471D01*
G03Y959181I599J-1145D01*
G01X379837Y959125D01*
Y955118D01*
X379730Y955062D01*
G03Y952772I599J-1145D01*
G01X379837Y952716D01*
Y948710D01*
X379730Y948654D01*
G03Y946364I599J-1145D01*
G01X379837Y946308D01*
Y942301D01*
X379730Y942245D01*
G03Y939955I599J-1145D01*
G01X379837Y939899D01*
Y935892D01*
X379730Y935836D01*
G03Y933546I599J-1145D01*
G01X379837Y933490D01*
Y929484D01*
X379730Y929428D01*
G03Y927138I599J-1145D01*
G01X379837Y927082D01*
Y924955D01*
G03X380130Y924248I999J0D01*
G01X382762Y921616D01*
X382775Y921562D01*
G03X383716Y920621I1254J313D01*
G01X383770Y920608D01*
X384877Y919501D01*
X384790Y919366D01*
G03X384587Y918670I1089J-695D01*
G03X385879Y917378I1292J0D01*
G03X386575Y917581I1J1292D01*
G01X386710Y917668D01*
X391989Y912389D01*
X391987Y912302D01*
G03X391986Y912262I1291J-52D01*
G03X393278Y910970I1292J0D01*
G03X393318Y910971I-12J1292D01*
G01X393405Y910973D01*
X401304Y903074D01*
X401276Y902964D01*
G03X401237Y902649I1253J-315D01*
G03X402529Y901357I1292J0D01*
G03X402844Y901396I0J1292D01*
G01X402954Y901424D01*
X403267Y901111D01*
Y900106D01*
X403243Y900062D01*
G03Y898828I1134J-617D01*
G01X403267Y898784D01*
Y893697D01*
X403243Y893653D01*
G03Y892419I1134J-617D01*
G01X403267Y892375D01*
Y887299D01*
X403242Y887254D01*
G03X403080Y886627I1136J-628D01*
G03X403153Y886199I1298J1D01*
G01X403184Y886112D01*
X402377Y884715D01*
X402287Y884698D01*
G03X401232Y883423I243J-1275D01*
G03X402529Y882126I1297J0D01*
G03X402787Y882151I4J1297D01*
G02X403267Y881760I80J-392D01*
G01Y880879D01*
X403243Y880834D01*
G03X403087Y880219I1136J-615D01*
G03X403243Y879604I1292J0D01*
G01X403267Y879559D01*
Y874482D01*
X403242Y874437D01*
G03X403080Y873810I1136J-628D01*
G03X403153Y873382I1298J1D01*
G01X403184Y873295D01*
X402377Y871898D01*
X402287Y871881D01*
G03X401232Y870606I243J-1275D01*
G03X401606Y869695I1297J0D01*
G02X401604Y869131I-285J-281D01*
G01X401105Y868632D01*
X400995Y868659D01*
G03X400920Y868676I-324J-1256D01*
G01X400830Y868693D01*
X400023Y870091D01*
X400054Y870177D01*
G03X400126Y870606I-1225J426D01*
G03X397532I-1297J0D01*
G03X398587Y869331I1298J0D01*
G01X398677Y869314D01*
X399484Y867916D01*
X399453Y867830D01*
G03X399380Y867401I1224J-429D01*
G03X399420Y867084I1298J3D01*
G01X399447Y866974D01*
X396514Y864041D01*
G03X396221Y863334I706J-707D01*
G01Y862047D01*
G03X395680Y860993I756J-1054D01*
G03X395753Y860565I1298J1D01*
G01X395784Y860478D01*
X394977Y859081D01*
X394887Y859064D01*
G03X393832Y857789I243J-1275D01*
G03X395129Y856492I1297J0D01*
G03X395658Y856604I0J1305D01*
G02X396221Y856239I163J-365D01*
G01Y855630D01*
G03Y853538I757J-1046D01*
G01Y849230D01*
G03Y847122I756J-1054D01*
G01Y846520D01*
G02X395657Y846155I-400J0D01*
G03X395127Y846268I-530J-1184D01*
G03X393830Y844971I0J-1297D01*
G03X393941Y844444I1297J-2D01*
G01X393980Y844356D01*
X393139Y842761D01*
X393044Y842743D01*
G03X391982Y841467I236J-1276D01*
G03X394576I1297J0D01*
G03X394465Y841994I-1297J2D01*
G01X394426Y842082D01*
X395267Y843677D01*
X395362Y843695D01*
G03X395657Y843787I-236J1276D01*
G02X396221Y843422I164J-365D01*
G01Y842513D01*
G03X395687Y841467I757J-1046D01*
G03X396149Y840477I1292J0D01*
G01X396221Y840417D01*
Y840090D01*
X357033Y816468D01*
X356924Y816604D01*
G03X350098Y819876I-6825J-5482D01*
G03X341344Y811122I0J-8754D01*
G03X346717Y803047I8754J0D01*
G01X346878Y802979D01*
X340532Y779337D01*
X340499Y779301D01*
G03X340135Y778362I1029J-939D01*
G03X340167Y778064I1392J-1D01*
G01X340178Y778016D01*
X337404Y767683D01*
X302585Y689664D01*
X294783Y681862D01*
X268000D01*
G03X267293Y681569I0J-999D01*
G01X258186Y672462D01*
X243614D01*
X241710Y674366D01*
Y856636D01*
X243617Y858543D01*
X292737D01*
X292761Y858537D01*
G03X293011Y858505I251J968D01*
G01X349061D01*
G02X349454Y858031I0J-400D01*
G03X349432Y857789I1275J-238D01*
G03X350729Y856492I1297J0D01*
G03X351690Y856917I1J1297D01*
G02X351968Y856935I148J-134D01*
G03X352617Y856695I650J759D01*
G01X353731D01*
G03X354187Y856514I698J1094D01*
G01X354277Y856497D01*
X355084Y855099D01*
X355053Y855013D01*
G03X354980Y854584I1224J-429D01*
G03X357576I1298J0D01*
G03X356520Y855859I-1298J0D01*
G01X356430Y855876D01*
X356303Y856095D01*
G02X356650Y856695I347J200D01*
G01X357431D01*
G03X358129Y856492I697J1094D01*
G03X358827Y856695I1J1297D01*
G01X361131D01*
G03X361587Y856514I698J1094D01*
G01X361677Y856497D01*
X362484Y855099D01*
X362453Y855013D01*
G03X362380Y854584I1224J-429D01*
G03X364976I1298J0D01*
G03X363920Y855859I-1298J0D01*
G01X363830Y855876D01*
X363703Y856095D01*
G02X364050Y856695I347J200D01*
G01X364831D01*
G03X365529Y856492I697J1094D01*
G03X366227Y856695I1J1297D01*
G01X368531D01*
G03X368987Y856514I698J1094D01*
G01X369077Y856497D01*
X369884Y855099D01*
X369853Y855013D01*
G03X369780Y854584I1224J-429D01*
G03X372376I1298J0D01*
G03X371320Y855859I-1298J0D01*
G01X371230Y855876D01*
X371103Y856095D01*
G02X371450Y856695I347J200D01*
G01X372231D01*
G03X372929Y856492I697J1094D01*
G03X373852Y856877I0J1299D01*
G03X373984Y856988I-575J818D01*
G01X374691Y857695D01*
G02X375364Y857501I283J-283D01*
G03X376387Y856514I1265J288D01*
G01X376477Y856497D01*
X377284Y855099D01*
X377253Y855013D01*
G03X377180Y854584I1224J-429D01*
G03X379776I1298J0D01*
G03X378720Y855859I-1298J0D01*
G01X378630Y855876D01*
X377823Y857274D01*
X377854Y857360D01*
G03X377926Y857789I-1225J426D01*
G03X376629Y859086I-1297J0D01*
G03X376020Y858935I-2J-1297D01*
G02X375727Y859117I-93J177D01*
G01Y860108D01*
G03X376076Y860993I-948J885D01*
G03X375677Y861929I-1297J0D01*
G01Y864221D01*
X377764Y866308D01*
X377893Y866243D01*
G03X378478Y866104I584J1158D01*
G03X379776Y867401I0J1298D01*
G03X379636Y867986I-1298J-1D01*
G01X379571Y868115D01*
X380893Y869437D01*
X380921Y869451D01*
G03X381484Y870014I-592J1155D01*
G01X381498Y870042D01*
X382071Y870615D01*
G02X382748Y870397I282J-283D01*
G03X383787Y869331I1281J209D01*
G01X383877Y869314D01*
X384684Y867916D01*
X384653Y867830D01*
G03X384580Y867401I1224J-429D01*
G03X387176I1298J0D01*
G03X386120Y868676I-1298J0D01*
G01X386030Y868693D01*
X385223Y870091D01*
X385254Y870177D01*
G03X385326Y870606I-1225J426D01*
G03X384029Y871904I-1298J0D01*
G03X383790Y871881I4J-1298D01*
G02X383317Y872275I-73J393D01*
G01Y873187D01*
X383338Y873229D01*
G03X383476Y873810I-1160J582D01*
G03X383338Y874391I-1298J-1D01*
G01X383317Y874433D01*
Y879605D01*
X383338Y879647D01*
G03X383471Y880219I-1159J571D01*
G03X383338Y880791I-1292J1D01*
G01X383317Y880833D01*
Y882216D01*
X383552D01*
X383585Y882204D01*
G03X383787Y882148I447J1218D01*
G01X383877Y882131D01*
X384683Y880734D01*
X384653Y880647D01*
G03X384580Y880219I1225J-429D01*
G03X387176I1298J0D01*
G03X386119Y881494I-1297J0D01*
G01X386029Y881511D01*
X385223Y882908D01*
X385254Y882994D01*
G03X385326Y883423I-1225J426D01*
G03X384029Y884720I-1297J0D01*
G03X383790Y884698I-1J-1297D01*
G02X383317Y885092I-73J393D01*
G01Y886004D01*
X383338Y886046D01*
G03X383476Y886627I-1160J582D01*
G03X383338Y887208I-1298J-1D01*
G01X383317Y887250D01*
Y890099D01*
G03X383024Y890806I-999J0D01*
G01X377890Y895940D01*
X377906Y896041D01*
G03X377921Y896240I-1277J196D01*
G03X376629Y897532I-1292J0D01*
G03X376430Y897517I-3J-1292D01*
G01X376329Y897501D01*
X368545Y905285D01*
X368590Y905405D01*
G03X368670Y905853I-1212J448D01*
G03X367378Y907145I-1292J0D01*
G03X366930Y907065I0J-1292D01*
G01X366810Y907020D01*
X361224Y912606D01*
X361210Y912652D01*
G03X360368Y913494I-1232J-390D01*
G01X360322Y913508D01*
X359159Y914671D01*
X359239Y914805D01*
G03X359421Y915466I-1109J661D01*
G03X358129Y916758I-1292J0D01*
G03X357468Y916576I0J-1291D01*
G01X357334Y916496D01*
X353473Y920357D01*
Y924147D01*
G03Y926011I-895J932D01*
G01Y930556D01*
G03Y932420I-895J932D01*
G01Y936964D01*
G03Y938828I-895J932D01*
G01Y943372D01*
G03Y945236I-895J932D01*
G01Y949781D01*
G03Y951645I-895J932D01*
G01Y956190D01*
G03Y958054I-895J932D01*
G01Y962598D01*
G03Y964462I-895J932D01*
G01Y969007D01*
G03Y970871I-895J932D01*
G01Y975414D01*
G03Y977280I-895J933D01*
G01Y981824D01*
G03Y983688I-895J932D01*
G01Y1001675D01*
X353584Y1001730D01*
G03Y1004046I-573J1158D01*
G01X353473Y1004101D01*
Y1008084D01*
X353584Y1008139D01*
G03Y1010455I-573J1158D01*
G01X353473Y1010510D01*
Y1014492D01*
X353584Y1014547D01*
G03Y1016863I-573J1158D01*
G01X353473Y1016918D01*
Y1020901D01*
X353584Y1020956D01*
G03Y1023272I-573J1158D01*
G01X353473Y1023327D01*
Y1026851D01*
X360266Y1033644D01*
X360354Y1033640D01*
G03X360411Y1033639I51J1291D01*
G03X361703Y1034931I0J1292D01*
G03X361702Y1034988I-1292J6D01*
G01X361698Y1035076D01*
X366969Y1040347D01*
X367105Y1040258D01*
G03X367811Y1040048I706J1082D01*
G03X369103Y1041340I0J1292D01*
G03X368893Y1042046I-1292J0D01*
G01X368804Y1042182D01*
X369894Y1043272D01*
X369950Y1043284D01*
G03X370922Y1044256I-288J1260D01*
G01X370934Y1044312D01*
X376436Y1049814D01*
X376560Y1049762D01*
G03X377062Y1049660I503J1190D01*
G03X378354Y1050952I0J1292D01*
G03X378252Y1051454I-1292J-1D01*
G01X378200Y1051578D01*
X380887Y1054265D01*
G37*
G36*
G01X288564Y1315788D02*
X299040D01*
X314150Y1300678D01*
G03X314857Y1300385I707J706D01*
G01X328693D01*
X333073Y1296005D01*
Y1288865D01*
G03X333366Y1288158I999J0D01*
G01X336966Y1284558D01*
G03X337673Y1284265I707J706D01*
G01X359659D01*
X364273Y1279651D01*
Y1273465D01*
G03X364566Y1272758I999J0D01*
G01X366466Y1270858D01*
G03X367173Y1270565I707J706D01*
G01X492373D01*
G03X493080Y1270858I0J999D01*
G01X495680Y1273458D01*
G03X495973Y1274165I-706J707D01*
G01Y1279051D01*
X501387Y1284465D01*
X517473D01*
G03X518180Y1284758I0J999D01*
G01X527580Y1294158D01*
G03X527873Y1294865I-706J707D01*
G01Y1303651D01*
X528987Y1304765D01*
X567926D01*
G03X568015Y1304663I796J605D01*
G01X569397Y1303281D01*
Y1167749D01*
X540722Y1139074D01*
X526887D01*
X526208Y1140359D01*
X526247Y1140448D01*
G03X526358Y1140973I-1186J525D01*
G03X523764I-1297J0D01*
G03X524826Y1139697I1298J0D01*
G01X524921Y1139679D01*
X525086Y1139367D01*
G02X524909Y1139074I-177J-93D01*
G01X519487D01*
X518808Y1140359D01*
X518847Y1140448D01*
G03X518958Y1140973I-1186J525D01*
G03X516364I-1297J0D01*
G03X517426Y1139697I1298J0D01*
G01X517521Y1139679D01*
X517686Y1139367D01*
G02X517509Y1139074I-177J-93D01*
G01X512087D01*
X511408Y1140359D01*
X511447Y1140448D01*
G03X511558Y1140973I-1186J525D01*
G03X508964I-1297J0D01*
G03X510026Y1139697I1298J0D01*
G01X510121Y1139679D01*
X510286Y1139367D01*
G02X510109Y1139074I-177J-93D01*
G01X504687D01*
X504008Y1140359D01*
X504047Y1140448D01*
G03X504158Y1140973I-1186J525D01*
G03X501564I-1297J0D01*
G03X502626Y1139697I1298J0D01*
G01X502721Y1139679D01*
X502886Y1139367D01*
G02X502709Y1139074I-177J-93D01*
G01X497287D01*
X496608Y1140359D01*
X496647Y1140448D01*
G03X496758Y1140973I-1186J525D01*
G03X494164I-1297J0D01*
G03X495226Y1139697I1298J0D01*
G01X495321Y1139679D01*
X495486Y1139367D01*
G02X495309Y1139074I-177J-93D01*
G01X489887D01*
X489208Y1140359D01*
X489247Y1140448D01*
G03X489358Y1140973I-1186J525D01*
G03X486764I-1297J0D01*
G03X487826Y1139697I1298J0D01*
G01X487921Y1139679D01*
X488086Y1139367D01*
G02X487909Y1139074I-177J-93D01*
G01X482487D01*
X481808Y1140359D01*
X481847Y1140448D01*
G03X481958Y1140973I-1186J525D01*
G03X479364I-1297J0D01*
G03X480426Y1139697I1298J0D01*
G01X480521Y1139679D01*
X480686Y1139367D01*
G02X480509Y1139074I-177J-93D01*
G01X479380D01*
G03X478673Y1138781I0J-999D01*
G01X478648Y1138756D01*
G03X477514Y1137469I163J-1287D01*
G03X477558Y1137137I1298J3D01*
G01X477579Y1137058D01*
X476708Y1135539D01*
X476627Y1135518D01*
G03X475664Y1134264I335J-1254D01*
G03X475711Y1133920I1298J2D01*
G01X475733Y1133839D01*
X474869Y1132332D01*
X474787Y1132311D01*
G03X473819Y1131060I324J-1251D01*
G03X473868Y1130708I1292J0D01*
G01X473891Y1130627D01*
X473037Y1129137D01*
X472953Y1129116D01*
G03X471964Y1127856I308J-1260D01*
G03X472018Y1127486I1298J0D01*
G01X472043Y1127404D01*
X471200Y1125934D01*
X471116Y1125914D01*
G03X470114Y1124651I295J-1263D01*
G03X470171Y1124268I1297J-3D01*
G01X470197Y1124185D01*
X469364Y1122732D01*
X469278Y1122713D01*
G03X468264Y1121447I283J-1266D01*
G03X468326Y1121052I1298J1D01*
G01X468353Y1120968D01*
X467525Y1119525D01*
X467438Y1119506D01*
G03X466419Y1118243I273J-1263D01*
G03X466483Y1117841I1292J0D01*
G01X466511Y1117756D01*
X465689Y1116323D01*
X465601Y1116304D01*
G03X464570Y1115039I261J-1265D01*
G03X464638Y1114626I1292J1D01*
G01X464667Y1114540D01*
X463852Y1113119D01*
X463763Y1113102D01*
G03X462720Y1111834I249J-1268D01*
G03X462792Y1111409I1292J0D01*
G01X462822Y1111323D01*
X462016Y1109917D01*
X461925Y1109900D01*
G03X460870Y1108630I237J-1270D01*
G03X460946Y1108193I1292J0D01*
G01X460977Y1108106D01*
X460179Y1106715D01*
X460087Y1106698D01*
G03X459020Y1105426I225J-1272D01*
G03X459100Y1104977I1292J-1D01*
G01X459133Y1104890D01*
X458342Y1103511D01*
X458249Y1103495D01*
G03X457170Y1102221I213J-1274D01*
G03X457255Y1101761I1292J1D01*
G01X457288Y1101673D01*
X456506Y1100308D01*
X456411Y1100293D01*
G03X455319Y1099017I200J-1276D01*
G03X455773Y1098034I1291J0D01*
G01Y1093590D01*
G03Y1091624I840J-983D01*
G01Y1087183D01*
G03Y1085217I837J-983D01*
G01Y1080774D01*
G03Y1078808I840J-983D01*
G01Y1074366D01*
G03Y1072400I837J-983D01*
G01Y1067957D01*
G03Y1065991I837J-983D01*
G01Y1061548D01*
G03Y1059582I837J-983D01*
G01Y1055140D01*
G03Y1053174I837J-983D01*
G01Y1048732D01*
G03Y1046766I837J-983D01*
G01Y1042323D01*
G03Y1040357I837J-983D01*
G01Y1028265D01*
G03X456066Y1027558I999J0D01*
G01X458666Y1024958D01*
G03X459373Y1024665I707J706D01*
G01X474659D01*
X475288Y1024036D01*
G02X475305Y1023489I-283J-283D01*
G03X474983Y1022636I969J-853D01*
G03X475667Y1021496I1292J0D01*
G01X475773Y1021439D01*
Y1018718D01*
X475668Y1018661D01*
G03Y1016391I617J-1135D01*
G01X475773Y1016334D01*
Y1014118D01*
X475668Y1014061D01*
G03X474993Y1012926I617J-1135D01*
G03X475388Y1011996I1292J0D01*
G02X475390Y1011423I-278J-287D01*
G03X475003Y1010500I905J-922D01*
G03X475670Y1009369I1292J0D01*
G01X475773Y1009312D01*
Y1007218D01*
X475668Y1007161D01*
G03X474993Y1006026I617J-1135D01*
G03X475337Y1005148I1292J0D01*
G02Y1004604I-293J-272D01*
G03X474993Y1003726I948J-878D01*
G03X475668Y1002591I1292J0D01*
G01X475773Y1002534D01*
Y998018D01*
X475668Y997961D01*
G03X474993Y996826I617J-1135D01*
G03X475337Y995948I1292J0D01*
G02Y995404I-293J-272D01*
G03X474993Y994526I948J-878D01*
G03X475668Y993391I1292J0D01*
G01X475773Y993334D01*
Y991118D01*
X475668Y991061D01*
G03X474993Y989926I617J-1135D01*
G03X475337Y989048I1292J0D01*
G02Y988504I-293J-272D01*
G03X474993Y987626I948J-878D01*
G03X475668Y986491I1292J0D01*
G01X475773Y986434D01*
Y981979D01*
X475578Y981784D01*
X475566Y981776D01*
G03X475296Y981506I769J-1039D01*
G01X475288Y981494D01*
X466293Y972499D01*
G03X466199Y972390I708J-705D01*
G03X464980Y971100I73J-1290D01*
G03X465863Y969874I1293J0D01*
G01X466000Y969829D01*
Y964838D01*
G03X466293Y964131I999J0D01*
G01X472066Y958358D01*
G03X472773Y958065I707J706D01*
G01X474959D01*
X475473Y957551D01*
Y955079D01*
X473859Y953465D01*
X463573D01*
G03X462866Y953172I0J-999D01*
G01X455366Y945672D01*
G03X455073Y944965I706J-707D01*
G01Y939779D01*
X453659Y938365D01*
X449990D01*
X449934Y938475D01*
G03X447624I-1155J-577D01*
G01X447568Y938365D01*
X446290D01*
X446234Y938475D01*
G03X443924I-1155J-577D01*
G01X443868Y938365D01*
X442590D01*
X442534Y938475D01*
G03X440224I-1155J-577D01*
G01X440168Y938365D01*
X438890D01*
X438834Y938475D01*
G03X436524I-1155J-577D01*
G01X436468Y938365D01*
X435190D01*
X435134Y938475D01*
G03X432824I-1155J-577D01*
G01X432768Y938365D01*
X431490D01*
X431434Y938475D01*
G03X429124I-1155J-577D01*
G01X429068Y938365D01*
X411387D01*
X406673Y943079D01*
Y965451D01*
X408187Y966965D01*
X412573D01*
G03X413280Y967258I0J999D01*
G01X414580Y968558D01*
G03X414873Y969265I-706J707D01*
G01Y969946D01*
X414978Y970003D01*
G03Y972277I-612J1137D01*
G01X414873Y972334D01*
Y973965D01*
G03X414580Y974672I-999J0D01*
G01X412080Y977172D01*
G03X411373Y977465I-707J-706D01*
G01X408187D01*
X406873Y978779D01*
Y1007514D01*
X408124Y1008765D01*
X412373D01*
G03X413080Y1009058I0J999D01*
G01X415080Y1011058D01*
G03X415373Y1011765I-706J707D01*
G01Y1013253D01*
X415521Y1013292D01*
G03Y1015788I-337J1248D01*
G01X415373Y1015827D01*
Y1025151D01*
X416050Y1025828D01*
X423737D01*
G03X424444Y1026121I0J999D01*
G01X425502Y1027179D01*
G03X425795Y1027886I-706J707D01*
G01Y1029304D01*
G03X425502Y1030011I-999J0D01*
G01X424161Y1031352D01*
G03X423454Y1031645I-707J-706D01*
G01X422655D01*
X421925Y1032375D01*
Y1037400D01*
X426404Y1041879D01*
G03X426697Y1042586I-706J707D01*
G01Y1084100D01*
X427164Y1084908D01*
X427254Y1084925D01*
G03X428310Y1086200I-242J1275D01*
G03X427077Y1087496I-1298J0D01*
G02X426697Y1087895I20J399D01*
G01Y1090913D01*
G02X427077Y1091312I400J0D01*
G03X428050Y1091830I-66J1296D01*
G01X429672D01*
G03X430711Y1091310I1039J778D01*
G03Y1093906I0J1298D01*
G03X429672Y1093386I0J-1298D01*
G01X428050D01*
G03X427077Y1093904I-1039J-778D01*
G02X426697Y1094303I20J399D01*
G01Y1102382D01*
G03X426404Y1103089I-999J0D01*
G01X424525Y1104968D01*
X424556Y1105081D01*
G03X424603Y1105426I-1245J345D01*
G03X423311Y1106718I-1292J0D01*
G03X422966Y1106671I0J-1292D01*
G01X422853Y1106640D01*
X419466Y1110027D01*
X419763Y1110542D01*
X419853Y1110559D01*
G03X420908Y1111834I-243J1275D01*
G03X419611Y1113132I-1298J0D01*
G03X418332Y1112053I0J-1298D01*
G02X417655Y1111838I-394J68D01*
G01X417065Y1112428D01*
X417051Y1112454D01*
G03X416531Y1112974I-1140J-620D01*
G01X416505Y1112988D01*
X415649Y1113844D01*
X415256Y1114524D01*
X415287Y1114611D01*
G03X415360Y1115039I-1225J429D01*
G03X414062Y1116336I-1297J0D01*
G03X413485Y1116201I-1J-1297D01*
G01X413356Y1116137D01*
X411891Y1117602D01*
Y1134522D01*
G03X411598Y1135229I-999J0D01*
G01X409753Y1137074D01*
X409777Y1137182D01*
G03X409810Y1137469I-1265J291D01*
G03X408512Y1138766I-1297J0D01*
G03X408120Y1138706I-2J-1297D01*
G03X407435Y1138978I-685J-727D01*
G01X407094D01*
G02X406740Y1139565I0J400D01*
G01X406801Y1139679D01*
X406896Y1139697D01*
G03X407958Y1140973I-236J1276D01*
G03X405364I-1297J0D01*
G03X405475Y1140447I1297J-1D01*
G01X405514Y1140358D01*
X404786Y1138978D01*
X399694D01*
G02X399340Y1139565I0J400D01*
G01X399401Y1139679D01*
X399496Y1139697D01*
G03X400558Y1140973I-236J1276D01*
G03X397964I-1297J0D01*
G03X398075Y1140447I1297J-1D01*
G01X398114Y1140358D01*
X397386Y1138978D01*
X392294D01*
G02X391940Y1139565I0J400D01*
G01X392001Y1139679D01*
X392096Y1139697D01*
G03X393158Y1140973I-236J1276D01*
G03X390564I-1297J0D01*
G03X390675Y1140447I1297J-1D01*
G01X390714Y1140358D01*
X389986Y1138978D01*
X384894D01*
G02X384540Y1139565I0J400D01*
G01X384601Y1139679D01*
X384696Y1139697D01*
G03X385758Y1140973I-236J1276D01*
G03X383164I-1297J0D01*
G03X383275Y1140447I1297J-1D01*
G01X383314Y1140358D01*
X382586Y1138978D01*
X377494D01*
G02X377140Y1139565I0J400D01*
G01X377201Y1139679D01*
X377296Y1139697D01*
G03X378358Y1140973I-236J1276D01*
G03X375764I-1297J0D01*
G03X375875Y1140447I1297J-1D01*
G01X375914Y1140358D01*
X375186Y1138978D01*
X370094D01*
G02X369740Y1139565I0J400D01*
G01X369801Y1139679D01*
X369896Y1139697D01*
G03X370958Y1140973I-236J1276D01*
G03X368364I-1297J0D01*
G03X368475Y1140447I1297J-1D01*
G01X368514Y1140358D01*
X367786Y1138978D01*
X362694D01*
G02X362340Y1139565I0J400D01*
G01X362401Y1139679D01*
X362496Y1139697D01*
G03X363558Y1140973I-236J1276D01*
G03X360964I-1297J0D01*
G03X361075Y1140447I1297J-1D01*
G01X361114Y1140358D01*
X360386Y1138978D01*
X315998D01*
X287277Y1167699D01*
Y1314501D01*
X288564Y1315788D01*
G37*
G36*
G01X726720Y1345542D02*
X726988D01*
X727048Y1345474D01*
G03X728104Y1344994I1056J922D01*
G03X728767Y1345160I1J1402D01*
G01X728897Y1345231D01*
X732600Y1341528D01*
Y1296016D01*
X730296Y1293712D01*
X716620D01*
G03X715913Y1293419I0J-999D01*
G01X712566Y1290072D01*
G03X712273Y1289365I706J-707D01*
G01Y1274534D01*
G03Y1272194I774J-1170D01*
G01Y848380D01*
X710538Y846645D01*
X601057D01*
X601039Y846648D01*
G03X600857Y846665I-184J-983D01*
G01X535161D01*
G02X534859Y847327I0J400D01*
G03X535176Y848176I-981J850D01*
G03X532580I-1298J0D01*
G03X532670Y847702I1298J1D01*
G01X532704Y847616D01*
X532202Y846665D01*
X531461D01*
G02X531159Y847327I0J400D01*
G03X531476Y848176I-981J850D01*
G03X530178Y849474I-1298J0D01*
G03X529139Y848954I0J-1298D01*
G01X527517D01*
G03X526478Y849474I-1039J-778D01*
G03X525180Y848176I0J-1298D01*
G03X525497Y847327I1298J1D01*
G02X525195Y846665I-302J-262D01*
G01X524547D01*
X523972Y847661D01*
X524003Y847747D01*
G03X524076Y848176I-1224J429D01*
G03X521480I-1298J0D01*
G03X521797Y847327I1298J1D01*
G02X521495Y846665I-302J-262D01*
G01X517147D01*
X516572Y847661D01*
X516603Y847747D01*
G03X516676Y848176I-1224J429D01*
G03X514080I-1298J0D01*
G03X514397Y847327I1298J1D01*
G02X514095Y846665I-302J-262D01*
G01X509747D01*
X509172Y847661D01*
X509203Y847747D01*
G03X509276Y848176I-1224J429D01*
G03X506680I-1298J0D01*
G03X506997Y847327I1298J1D01*
G02X506695Y846665I-302J-262D01*
G01X504787D01*
X503473Y847979D01*
Y850619D01*
G03Y852141I-1044J761D01*
G01Y852936D01*
G02X503968Y853324I400J0D01*
G03X504278Y853286I312J1260D01*
G03X505576Y854584I0J1298D01*
G03X505503Y855011I-1298J-2D01*
G01X505473Y855098D01*
X506281Y856497D01*
X506371Y856514D01*
G03X507426Y857789I-243J1275D01*
G03X504832I-1297J0D01*
G03X504904Y857361I1297J-2D01*
G01X504935Y857274D01*
X504128Y855876D01*
X504038Y855859D01*
G03X503968Y855844I237J-1276D01*
G02X503473Y856232I-95J388D01*
G01Y857019D01*
G03Y858559I-1045J770D01*
G01Y863436D01*
G03Y864958I-1044J761D01*
G01Y865753D01*
G02X503968Y866141I400J0D01*
G03X504278Y866104I308J1260D01*
G03X505576Y867401I0J1298D01*
G03X505503Y867828I-1298J-2D01*
G01X505473Y867915D01*
X506281Y869314D01*
X506371Y869331D01*
G03X507426Y870606I-243J1275D01*
G03X504832I-1297J0D01*
G03X504904Y870178I1297J-2D01*
G01X504935Y870091D01*
X504128Y868693D01*
X504038Y868676D01*
G03X503968Y868661I237J-1276D01*
G02X503473Y869049I-95J388D01*
G01Y869836D01*
G03Y871376I-1045J770D01*
G01Y876253D01*
G03Y877775I-1044J761D01*
G01Y878571D01*
G02X503968Y878959I400J0D01*
G03X504278Y878922I308J1260D01*
G03X505576Y880219I0J1298D01*
G03X504519Y881494I-1297J0D01*
G01X504429Y881511D01*
X503623Y882908D01*
X503654Y882994D01*
G03X503726Y883423I-1225J426D01*
G03X503473Y884193I-1298J0D01*
G01Y887151D01*
X505220Y888898D01*
X505358Y888795D01*
G03X506129Y888540I771J1038D01*
G03X507421Y889832I0J1292D01*
G03X507166Y890603I-1293J0D01*
G01X507063Y890741D01*
X508067Y891745D01*
X508136Y891754D01*
G03X509229Y892715I-158J1282D01*
G01X509268Y892865D01*
X510388D01*
X510427Y892715D01*
G03X512929I1251J320D01*
G01X512968Y892865D01*
X514089D01*
X514128Y892715D01*
G03X516630I1251J320D01*
G01X516669Y892865D01*
X517788D01*
X517827Y892715D01*
G03X520329I1251J320D01*
G01X520368Y892865D01*
X522073D01*
G03X522780Y893158I0J999D01*
G01X524569Y894947D01*
X524650Y894948D01*
G03X525921Y896219I-21J1292D01*
G01X525922Y896300D01*
X531238Y901616D01*
X531371Y901537D01*
G03X532029Y901357I658J1113D01*
G03X533321Y902649I0J1292D01*
G03X533141Y903307I-1293J0D01*
G01X533062Y903440D01*
X534231Y904609D01*
X534277Y904624D01*
G03X535108Y905455I-398J1229D01*
G01X535123Y905501D01*
X535384Y905762D01*
X536280D01*
X536312Y905601D01*
G03X538846I1267J252D01*
G01X538878Y905762D01*
X547380D01*
X547412Y905601D01*
G03X549946I1267J252D01*
G01X549978Y905762D01*
X554384D01*
G03X555091Y906055I0J999D01*
G01X558334Y909298D01*
G03X558627Y910005I-706J707D01*
G01Y1047135D01*
G03X558334Y1047842I-999J0D01*
G01X553874Y1052302D01*
G03X553167Y1052595I-707J-706D01*
G01X534957D01*
X530048Y1057504D01*
X530037Y1057568D01*
G03X528969Y1058636I-1275J-207D01*
G01X528905Y1058647D01*
X527870Y1059682D01*
X527967Y1059820D01*
G03X528203Y1060565I-1056J744D01*
G03X526911Y1061857I-1292J0D01*
G03X526166Y1061621I-1J-1292D01*
G01X526028Y1061524D01*
X520789Y1066763D01*
X520798Y1066856D01*
G03X520803Y1066974I-1287J114D01*
G03X519511Y1068266I-1292J0D01*
G03X518291Y1067399I0J-1292D01*
G01X518244Y1067265D01*
X517078D01*
X517031Y1067399D01*
G03X514591I-1220J-425D01*
G01X514544Y1067265D01*
X513378D01*
X513331Y1067399D01*
G03X510891I-1220J-425D01*
G01X510844Y1067265D01*
X509678D01*
X509631Y1067399D01*
G03X507191I-1220J-425D01*
G01X507144Y1067265D01*
X505978D01*
X505931Y1067399D01*
G03X503491I-1220J-425D01*
G01X503444Y1067265D01*
X502278D01*
X502231Y1067399D01*
G03X499791I-1220J-425D01*
G01X499744Y1067265D01*
X498578D01*
X498531Y1067399D01*
G03X496091I-1220J-425D01*
G01X496044Y1067265D01*
X494878D01*
X494831Y1067399D01*
G03X492391I-1220J-425D01*
G01X492344Y1067265D01*
X491178D01*
X491131Y1067399D01*
G03X488691I-1220J-425D01*
G01X488644Y1067265D01*
X487478D01*
X487431Y1067399D01*
G03X484991I-1220J-425D01*
G01X484944Y1067265D01*
X483779D01*
X483732Y1067399D01*
G03X481292I-1220J-425D01*
G01X481245Y1067265D01*
X480078D01*
X480031Y1067399D01*
G03X477591I-1220J-425D01*
G01X477544Y1067265D01*
X476378D01*
X476331Y1067399D01*
G03X475111Y1068266I-1220J-425D01*
G03X473851Y1067262I0J-1293D01*
G03X472908Y1066766I-78J-997D01*
G01X469965D01*
X466672Y1063473D01*
Y1061893D01*
G03Y1059237I1039J-1328D01*
G01Y1055485D01*
G03Y1052829I1039J-1328D01*
G01Y1048517D01*
G03X466419Y1047750I1039J-768D01*
G03X466672Y1046983I1292J1D01*
G01Y1042107D01*
G03X466419Y1041340I1039J-768D01*
G03X466672Y1040573I1292J1D01*
G01Y1037960D01*
G03Y1035788I700J-1086D01*
G01Y1027171D01*
X466166Y1026665D01*
X459787D01*
X457773Y1028679D01*
Y1040774D01*
X457790Y1040813D01*
G03X457903Y1041340I-1179J528D01*
G03X457790Y1041867I-1292J-1D01*
G01X457773Y1041906D01*
Y1047183D01*
X457790Y1047222D01*
G03X457903Y1047749I-1179J528D01*
G03X457790Y1048276I-1292J-1D01*
G01X457773Y1048315D01*
Y1053591D01*
X457790Y1053630D01*
G03X457903Y1054157I-1179J528D01*
G03X457790Y1054684I-1292J-1D01*
G01X457773Y1054723D01*
Y1059999D01*
X457790Y1060038D01*
G03X457903Y1060565I-1179J528D01*
G03X457790Y1061092I-1292J-1D01*
G01X457773Y1061131D01*
Y1066408D01*
X457790Y1066447D01*
G03X457903Y1066974I-1179J528D01*
G03X457790Y1067501I-1292J-1D01*
G01X457773Y1067540D01*
Y1072817D01*
X457790Y1072856D01*
G03X457903Y1073383I-1179J528D01*
G03X457790Y1073910I-1292J-1D01*
G01X457773Y1073949D01*
Y1079223D01*
X457791Y1079262D01*
G03X457904Y1079791I-1179J528D01*
G03X457791Y1080320I-1292J1D01*
G01X457773Y1080359D01*
Y1085634D01*
X457790Y1085673D01*
G03X457903Y1086200I-1179J528D01*
G03X457790Y1086727I-1292J-1D01*
G01X457773Y1086766D01*
Y1092039D01*
X457791Y1092078D01*
G03X457904Y1092607I-1179J528D01*
G03X457791Y1093136I-1292J1D01*
G01X457773Y1093175D01*
Y1098451D01*
X457790Y1098490D01*
G03X457832Y1098595I-1177J532D01*
G01X457838Y1098613D01*
X459394Y1101326D01*
X459410Y1101343D01*
G03X459699Y1101847I-948J878D01*
G01X459705Y1101869D01*
X461215Y1104502D01*
X461233Y1104520D01*
G03X461559Y1105088I-921J906D01*
G01X461566Y1105113D01*
X463037Y1107679D01*
X463058Y1107699D01*
G03X463418Y1108327I-896J931D01*
G01X463425Y1108355D01*
X464861Y1110859D01*
X464884Y1110881D01*
G03X465275Y1111563I-872J953D01*
G01X465282Y1111594D01*
X466687Y1114044D01*
X466712Y1114066D01*
G03X467131Y1114797I-850J973D01*
G01X467137Y1114829D01*
X468514Y1117230D01*
X468541Y1117253D01*
G03X468985Y1118026I-830J991D01*
G01X468991Y1118061D01*
X470333Y1120403D01*
X470364Y1120427D01*
G03X470847Y1121270I-802J1020D01*
G01X470853Y1121309D01*
X472162Y1123592D01*
X472195Y1123617D01*
G03X472699Y1124497I-784J1034D01*
G01X472704Y1124537D01*
X473143Y1125304D01*
G02X473837I347J-199D01*
G01X473917Y1125166D01*
X473886Y1125080D01*
G03X473814Y1124651I1225J-426D01*
G03X476408I1297J0D01*
G03X475353Y1125926I-1298J0D01*
G01X475263Y1125943D01*
X474456Y1127341D01*
X474487Y1127427D01*
G03X474553Y1127727I-1225J427D01*
G01X474557Y1127769D01*
X475827Y1129984D01*
X475863Y1130009D01*
G03X476398Y1130942I-752J1051D01*
G01X476402Y1130985D01*
X477650Y1133163D01*
X477689Y1133189D01*
G03X478257Y1134180I-727J1075D01*
G01X478260Y1134226D01*
X479482Y1136357D01*
X479522Y1136383D01*
G03X480003Y1136953I-709J1087D01*
G01X480055Y1137074D01*
X481269D01*
X481321Y1136953D01*
G03X482512Y1136172I1190J516D01*
G03X483703Y1136953I1J1297D01*
G01X483755Y1137074D01*
X484394D01*
G02X484741Y1136474I0J-400D01*
G01X484211Y1135556D01*
X484121Y1135539D01*
G03X483064Y1134264I240J-1275D01*
G03X485660I1298J0D01*
G03X485587Y1134692I-1298J-1D01*
G01X485557Y1134779D01*
X486364Y1136177D01*
X486454Y1136194D01*
G03X487403Y1136953I-242J1275D01*
G01X487455Y1137074D01*
X488669D01*
X488721Y1136953D01*
G03X489912Y1136172I1190J516D01*
G03X491103Y1136953I1J1297D01*
G01X491155Y1137074D01*
X491794D01*
G02X492141Y1136474I0J-400D01*
G01X491611Y1135556D01*
X491521Y1135539D01*
G03X490464Y1134264I240J-1275D01*
G03X493060I1298J0D01*
G03X492987Y1134692I-1298J-1D01*
G01X492957Y1134779D01*
X493764Y1136177D01*
X493854Y1136194D01*
G03X494803Y1136953I-242J1275D01*
G01X494855Y1137074D01*
X496069D01*
X496121Y1136953D01*
G03X497312Y1136172I1190J516D01*
G03X498503Y1136953I1J1297D01*
G01X498555Y1137074D01*
X499194D01*
G02X499541Y1136474I0J-400D01*
G01X499011Y1135556D01*
X498921Y1135539D01*
G03X497864Y1134264I240J-1275D01*
G03X500460I1298J0D01*
G03X500387Y1134692I-1298J-1D01*
G01X500357Y1134779D01*
X501164Y1136177D01*
X501254Y1136194D01*
G03X502203Y1136953I-242J1275D01*
G01X502255Y1137074D01*
X503469D01*
X503521Y1136953D01*
G03X504712Y1136172I1190J516D01*
G03X505903Y1136953I1J1297D01*
G01X505955Y1137074D01*
X506594D01*
G02X506941Y1136474I0J-400D01*
G01X506411Y1135556D01*
X506321Y1135539D01*
G03X505264Y1134264I240J-1275D01*
G03X507860I1298J0D01*
G03X507787Y1134692I-1298J-1D01*
G01X507757Y1134779D01*
X508564Y1136177D01*
X508654Y1136194D01*
G03X509603Y1136953I-242J1275D01*
G01X509655Y1137074D01*
X510869D01*
X510921Y1136953D01*
G03X512112Y1136172I1190J516D01*
G03X513303Y1136953I1J1297D01*
G01X513355Y1137074D01*
X513994D01*
G02X514341Y1136474I0J-400D01*
G01X513811Y1135556D01*
X513721Y1135539D01*
G03X512664Y1134264I240J-1275D01*
G03X515260I1298J0D01*
G03X515187Y1134692I-1298J-1D01*
G01X515157Y1134779D01*
X515964Y1136177D01*
X516054Y1136194D01*
G03X517003Y1136953I-242J1275D01*
G01X517055Y1137074D01*
X518269D01*
X518321Y1136953D01*
G03X519512Y1136172I1190J516D01*
G03X520703Y1136953I1J1297D01*
G01X520755Y1137074D01*
X521394D01*
G02X521741Y1136474I0J-400D01*
G01X521211Y1135556D01*
X521121Y1135539D01*
G03X520064Y1134264I240J-1275D01*
G03X522660I1298J0D01*
G03X522587Y1134692I-1298J-1D01*
G01X522557Y1134779D01*
X523364Y1136177D01*
X523454Y1136194D01*
G03X524403Y1136953I-242J1275D01*
G01X524455Y1137074D01*
X525669D01*
X525721Y1136953D01*
G03X526912Y1136172I1190J516D01*
G03X528103Y1136953I1J1297D01*
G01X528155Y1137074D01*
X529375D01*
X529427Y1136954D01*
G03X531797I1185J515D01*
G01X531849Y1137074D01*
X532494D01*
G02X532840Y1136474I0J-400D01*
G01X532310Y1135556D01*
X532220Y1135539D01*
G03X531164Y1134264I242J-1275D01*
G03X533760I1298J0D01*
G03X533687Y1134692I-1298J-1D01*
G01X533656Y1134779D01*
X534464Y1136177D01*
X534554Y1136194D01*
G03X535503Y1136953I-242J1275D01*
G01X535555Y1137074D01*
X541136D01*
G03X541843Y1137367I0J999D01*
G01X571104Y1166628D01*
G03X571397Y1167335I-706J707D01*
G01Y1303321D01*
X572841Y1304765D01*
X582707D01*
G03X583414Y1305058I0J999D01*
G01X585844Y1307488D01*
G03X586137Y1308195I-706J707D01*
G01Y1341355D01*
X590324Y1345542D01*
X663875D01*
G03X664987Y1344994I1112J854D01*
G03X666043Y1345474I0J1402D01*
G01X666103Y1345542D01*
X666371D01*
X666431Y1345474D01*
G03X668543I1056J922D01*
G01X668603Y1345542D01*
X668921D01*
X668981Y1345474D01*
G03X670037Y1344994I1056J922D01*
G03X671149Y1345542I0J1402D01*
G01X683443D01*
G03X684555Y1344994I1112J854D01*
G03X685611Y1345474I0J1402D01*
G01X685671Y1345542D01*
X685989D01*
X686049Y1345474D01*
G03X688161I1056J922D01*
G01X688221Y1345542D01*
X688489D01*
X688549Y1345474D01*
G03X689605Y1344994I1056J922D01*
G03X690717Y1345542I0J1402D01*
G01X701975D01*
G03X703087Y1344994I1112J854D01*
G03X704143Y1345474I0J1402D01*
G01X704203Y1345542D01*
X704471D01*
X704531Y1345474D01*
G03X706643I1056J922D01*
G01X706703Y1345542D01*
X707021D01*
X707081Y1345474D01*
G03X708137Y1344994I1056J922D01*
G03X709249Y1345542I0J1402D01*
G01X721942D01*
G03X723054Y1344994I1112J854D01*
G03X724110Y1345474I0J1402D01*
G01X724170Y1345542D01*
X724488D01*
X724548Y1345474D01*
G03X726660I1056J922D01*
G01X726720Y1345542D01*
G37*
G36*
G01X846066Y1258091D02*
X855167D01*
G03X855175Y1258083I711J703D01*
G01X856270Y1256988D01*
G03X856457Y1256841I707J707D01*
G01Y765869D01*
X851223Y760635D01*
X671104D01*
G03X668452I-1326J-706D01*
G01X603782D01*
G02X603392Y761126I0J400D01*
G03X603429Y761445I-1365J320D01*
G03X602266Y762826I-1401J0D01*
G01X602100Y762855D01*
Y765448D01*
X608574Y771922D01*
G03X608867Y772629I-706J707D01*
G01Y843061D01*
X610451Y844645D01*
X710952D01*
G03X711659Y844938I0J999D01*
G01X713980Y847259D01*
G03X714273Y847966I-706J707D01*
G01Y1256853D01*
G03X714337Y1256912I-645J764D01*
G01X715516Y1258091D01*
X722575D01*
G03X724825I1125J637D01*
G01X738450D01*
G03X740948I1249J635D01*
G01X768150D01*
G03X770648I1249J635D01*
G01X782961D01*
X782973Y1258090D01*
G03X783130Y1258080I160J1282D01*
G03X783287Y1258090I-3J1292D01*
G01X783299Y1258091D01*
X797850D01*
G03X800348I1249J635D01*
G01X811315D01*
G03X813565I1125J637D01*
G01X827550D01*
G03X830048I1249J635D01*
G01X843816D01*
G03X846066I1125J637D01*
G37*
G36*
G01X1102415Y1256125D02*
X1119023D01*
X1119400Y1255748D01*
Y861362D01*
G03X1119693Y860655I999J0D01*
G01X1122058Y858290D01*
G03X1122765Y857997I707J706D01*
G01X1250061D01*
X1252220Y855838D01*
Y767022D01*
X1250503Y765305D01*
X1002681D01*
X1000207Y767779D01*
Y1255073D01*
G03X1000287Y1255145I-628J778D01*
G01X1001086Y1255944D01*
G03X1002070Y1255540I985J998D01*
G03X1003209Y1256125I0J1401D01*
G01X1011806D01*
G03X1012543Y1255896I737J1073D01*
G03X1013280Y1256125I0J1302D01*
G01X1071355D01*
X1071398Y1256103D01*
G03X1072584I593J1158D01*
G01X1072627Y1256125D01*
X1100693D01*
G03X1102415I861J978D01*
G37*
G36*
G01X1676377Y1426535D02*
X1734813D01*
X1752487Y1408861D01*
Y1322085D01*
G03X1752780Y1321378I999J0D01*
G01X1755130Y1319028D01*
G03X1755837Y1318735I707J706D01*
G01X1785448D01*
X1787247Y1316936D01*
Y1295949D01*
X1783560Y1292262D01*
G03X1783267Y1291555I706J-707D01*
G01Y1290695D01*
G03Y1284633I1944J-3031D01*
G01Y1268869D01*
X1782543Y1268145D01*
X1691714D01*
X1690478Y1269381D01*
G03X1690414Y1269440I-709J-705D01*
G01Y1272662D01*
X1690436Y1272705D01*
G03Y1273983I-1249J639D01*
G01X1690414Y1274026D01*
Y1294850D01*
X1692914Y1297350D01*
G03X1693207Y1298057I-706J707D01*
G01Y1382985D01*
G03X1692914Y1383692I-999J0D01*
G01X1691074Y1385532D01*
G03X1690367Y1385825I-707J-706D01*
G01X1607424D01*
G03X1606717Y1385532I0J-999D01*
G01X1560571Y1339386D01*
G03X1560278Y1338679I706J-707D01*
G01Y1302860D01*
X1559233Y1301815D01*
X1507617D01*
G03X1506910Y1301522I0J-999D01*
G01X1491852Y1286464D01*
X1477114D01*
G03X1476407Y1286171I0J-999D01*
G01X1470407Y1280171D01*
G03X1470114Y1279464I706J-707D01*
G01Y1274578D01*
X1468100Y1272564D01*
X1346762D01*
X1336164Y1283162D01*
G03X1335457Y1283455I-707J-706D01*
G01X1325611D01*
X1299311Y1309755D01*
G03X1298604Y1310048I-707J-706D01*
G01X1255724D01*
X1254531Y1311241D01*
Y1333482D01*
G03Y1335816I-944J1167D01*
G01Y1380553D01*
G03X1254238Y1381260I-999J0D01*
G01X1248975Y1386523D01*
G03X1248268Y1386816I-707J-706D01*
G01X1121944D01*
G03X1121237Y1386523I0J-999D01*
G01X1117993Y1383279D01*
G03X1117700Y1382572I706J-707D01*
G01Y1258512D01*
G03X1117712Y1258356I999J-2D01*
G01X1117715Y1258341D01*
Y1258125D01*
X1102513D01*
G03X1100595I-959J-1024D01*
G01X1073096D01*
G03X1070886I-1105J-863D01*
G01X1043580D01*
G03X1041082I-1249J-637D01*
G01X1013595D01*
G03X1011491I-1052J-927D01*
G01X1002822D01*
G03X1002070Y1258344I-752J-1182D01*
G03X1001362Y1258152I0J-1401D01*
G01X1001316Y1258125D01*
X1001091D01*
X1000207Y1259009D01*
Y1395505D01*
X1006635Y1401933D01*
X1006765Y1401867D01*
G03X1016240Y1399578I9474J18463D01*
G03X1036992Y1420330I0J20752D01*
G03X1036351Y1425450I-20752J2D01*
G02X1036739Y1425949I388J99D01*
G01X1114397D01*
X1114445Y1425819D01*
G03X1117261I1408J523D01*
G01X1117309Y1425949D01*
X1133255D01*
G03X1134429Y1425362I1174J881D01*
G03X1135546Y1425879I-1J1467D01*
G01X1135606Y1425949D01*
X1135852D01*
X1135912Y1425879D01*
G03X1137029Y1425362I1118J950D01*
G03X1138203Y1425949I0J1468D01*
G01X1144393D01*
G03X1146691I1149J912D01*
G01X1171398D01*
G03X1172572Y1425362I1174J881D01*
G03X1173689Y1425879I-1J1467D01*
G01X1173749Y1425949D01*
X1173995D01*
X1174055Y1425879D01*
G03X1175172Y1425362I1118J950D01*
G03X1176346Y1425949I0J1468D01*
G01X1182536D01*
G03X1184834I1149J912D01*
G01X1303629D01*
X1329530Y1400048D01*
G03X1330237Y1399755I707J706D01*
G01X1368298D01*
G03X1369005Y1400048I0J999D01*
G01X1394088Y1425131D01*
X1394130Y1425146D01*
G03X1395046Y1426062I-500J1416D01*
G01X1395061Y1426104D01*
X1395492Y1426535D01*
X1413320D01*
X1413366Y1426400D01*
G03X1416206I1420J490D01*
G01X1416252Y1426535D01*
X1430691D01*
G03X1432743I1026J1097D01*
G01X1511359D01*
G03X1512177Y1426293I818J1260D01*
G03X1512995Y1426535I0J1502D01*
G01X1631698D01*
G03X1633334I818J1219D01*
G01X1634168D01*
G03X1635804I818J1219D01*
G01X1636598D01*
G03X1638234I818J1219D01*
G01X1669841D01*
G03X1671477I818J1219D01*
G01X1672311D01*
G03X1673947I818J1219D01*
G01X1674741D01*
G03X1676377I818J1219D01*
G37*
G36*
G01X1079294Y329592D02*
X1289146D01*
X1295300Y323438D01*
Y316959D01*
X1295192Y316903D01*
G03Y314239I696J-1332D01*
G01X1295300Y314183D01*
Y301552D01*
G02X1294816Y301161I-400J0D01*
G03X1294500Y301194I-313J-1469D01*
G01X1291100D01*
G03Y298190I0J-1502D01*
G01X1294500D01*
G03X1294816Y298223I3J1502D01*
G02X1295300Y297832I84J-391D01*
G01Y226962D01*
G03X1295593Y226255I999J0D01*
G01X1298393Y223455D01*
G03X1299100Y223162I707J706D01*
G01X1302339D01*
G03X1304511I1086J888D01*
G01X1308742D01*
G03X1310914I1086J888D01*
G01X1321566D01*
G03X1323738I1086J888D01*
G01X1327975D01*
G03X1330147I1086J888D01*
G01X1330555D01*
G02X1330935Y222637I0J-400D01*
G03X1330865Y222199I1332J-437D01*
G03X1332267Y220797I1402J0D01*
G03X1333067Y221048I0J1402D01*
G01X1333205Y221143D01*
X1333500Y220848D01*
Y196657D01*
G03Y194291I752J-1183D01*
G01Y177757D01*
G03Y175391I752J-1183D01*
G01Y168676D01*
X1332818Y167994D01*
X1332702Y168032D01*
G03X1332268Y168101I-434J-1333D01*
G03X1331033Y167362I0J-1401D01*
G01X1320687D01*
G03X1318217I-1235J-662D01*
G01X1314268D01*
G03X1311798I-1235J-662D01*
G01X1307857D01*
G03X1305387I-1235J-662D01*
G01X1301447D01*
G03X1298977I-1235J-662D01*
G01X1295037D01*
G03X1292567I-1235J-662D01*
G01X1272138D01*
X1272105Y167374D01*
G03X1271081I-512J-1411D01*
G01X1271048Y167362D01*
X1080814D01*
X1079740Y168436D01*
Y220112D01*
G03X1079447Y220819I-999J0D01*
G01X1072800Y227466D01*
Y323098D01*
X1079294Y329592D01*
G37*
G36*
G01X1189634Y1384816D02*
X1247854D01*
X1252531Y1380139D01*
Y1335718D01*
G03Y1333580I1055J-1069D01*
G01Y1310827D01*
G03X1252824Y1310120I999J0D01*
G01X1254603Y1308341D01*
G03X1255310Y1308048I707J706D01*
G01X1267250D01*
X1268587Y1306711D01*
Y1168775D01*
G03X1268880Y1168068I999J0D01*
G01X1299678Y1137270D01*
G03X1300385Y1136977I707J706D01*
G01X1320551D01*
X1320607Y1136870D01*
G03X1322897I1145J599D01*
G01X1322953Y1136977D01*
X1324247D01*
X1324303Y1136869D01*
G03X1325212Y1136194I1151J600D01*
G01X1325302Y1136177D01*
X1326109Y1134779D01*
X1326078Y1134693D01*
G03X1326006Y1134264I1225J-426D01*
G03X1328600I1297J0D01*
G03X1327545Y1135539I-1298J0D01*
G01X1327455Y1135556D01*
X1326981Y1136377D01*
G02X1327327Y1136977I346J200D01*
G01X1327951D01*
X1328007Y1136870D01*
G03X1330297I1145J599D01*
G01X1330353Y1136977D01*
X1331647D01*
X1331703Y1136869D01*
G03X1332612Y1136194I1151J600D01*
G01X1332702Y1136177D01*
X1333509Y1134779D01*
X1333478Y1134693D01*
G03X1333406Y1134264I1225J-426D01*
G03X1336000I1297J0D01*
G03X1334945Y1135539I-1298J0D01*
G01X1334855Y1135556D01*
X1334381Y1136377D01*
G02X1334727Y1136977I346J200D01*
G01X1335347D01*
X1335403Y1136869D01*
G03X1336554Y1136172I1150J600D01*
G03X1337705Y1136869I1J1297D01*
G01X1337761Y1136977D01*
X1339047D01*
X1339103Y1136869D01*
G03X1340012Y1136194I1151J600D01*
G01X1340102Y1136177D01*
X1340910Y1134779D01*
X1340879Y1134692D01*
G03X1340806Y1134264I1225J-429D01*
G03X1343402I1298J0D01*
G03X1342346Y1135539I-1298J0D01*
G01X1342256Y1135556D01*
X1341782Y1136377D01*
G02X1342128Y1136977I346J200D01*
G01X1342747D01*
X1342803Y1136869D01*
G03X1343954Y1136172I1150J600D01*
G03X1345105Y1136869I1J1297D01*
G01X1345161Y1136977D01*
X1346447D01*
X1346503Y1136869D01*
G03X1347412Y1136194I1151J600D01*
G01X1347502Y1136177D01*
X1348310Y1134779D01*
X1348279Y1134692D01*
G03X1348206Y1134264I1225J-429D01*
G03X1350802I1298J0D01*
G03X1349746Y1135539I-1298J0D01*
G01X1349656Y1135556D01*
X1349182Y1136377D01*
G02X1349528Y1136977I346J200D01*
G01X1350147D01*
X1350203Y1136869D01*
G03X1351354Y1136172I1150J600D01*
G03X1352505Y1136869I1J1297D01*
G01X1352561Y1136977D01*
X1353847D01*
X1353903Y1136869D01*
G03X1354812Y1136194I1151J600D01*
G01X1354902Y1136177D01*
X1355710Y1134779D01*
X1355679Y1134692D01*
G03X1355606Y1134264I1225J-429D01*
G03X1358202I1298J0D01*
G03X1357146Y1135539I-1298J0D01*
G01X1357056Y1135556D01*
X1356582Y1136377D01*
G02X1356928Y1136977I346J200D01*
G01X1357547D01*
X1357603Y1136869D01*
G03X1358754Y1136172I1150J600D01*
G03X1359905Y1136869I1J1297D01*
G01X1359961Y1136977D01*
X1361247D01*
X1361303Y1136869D01*
G03X1362212Y1136194I1151J600D01*
G01X1362302Y1136177D01*
X1363110Y1134779D01*
X1363079Y1134692D01*
G03X1363006Y1134264I1225J-429D01*
G03X1365602I1298J0D01*
G03X1364546Y1135539I-1298J0D01*
G01X1364456Y1135556D01*
X1363982Y1136377D01*
G02X1364328Y1136977I346J200D01*
G01X1364947D01*
X1365003Y1136869D01*
G03X1366154Y1136172I1150J600D01*
G03X1367305Y1136869I1J1297D01*
G01X1367361Y1136977D01*
X1368647D01*
X1368703Y1136869D01*
G03X1369612Y1136194I1151J600D01*
G01X1369702Y1136177D01*
X1370510Y1134779D01*
X1370479Y1134692D01*
G03X1370406Y1134264I1225J-429D01*
G03X1373002I1298J0D01*
G03X1371946Y1135539I-1298J0D01*
G01X1371856Y1135556D01*
X1371382Y1136377D01*
G02X1371728Y1136977I346J200D01*
G01X1372347D01*
X1372403Y1136869D01*
G03X1373554Y1136172I1150J600D01*
G03X1374705Y1136869I1J1297D01*
G01X1374761Y1136977D01*
X1376047D01*
X1376103Y1136869D01*
G03X1377012Y1136194I1151J600D01*
G01X1377102Y1136177D01*
X1377910Y1134779D01*
X1377879Y1134692D01*
G03X1377806Y1134264I1225J-429D01*
G03X1380402I1298J0D01*
G03X1379346Y1135539I-1298J0D01*
G01X1379256Y1135556D01*
X1378782Y1136377D01*
G02X1379128Y1136977I346J200D01*
G01X1379747D01*
X1379803Y1136869D01*
G03X1380954Y1136172I1150J600D01*
G03X1382105Y1136869I1J1297D01*
G01X1382161Y1136977D01*
X1383162D01*
X1385240Y1134899D01*
X1385310Y1134779D01*
X1385279Y1134692D01*
G03X1385206Y1134264I1225J-429D01*
G03X1385922Y1133104I1298J0D01*
G01X1386032Y1133049D01*
Y1129065D01*
X1385922Y1129010D01*
G03Y1126702I581J-1154D01*
G01X1386032Y1126647D01*
Y1126038D01*
G02X1385401Y1125711I-400J0D01*
G03X1384653Y1125948I-747J-1060D01*
G03X1383356Y1124651I0J-1297D01*
G03X1384411Y1123376I1298J0D01*
G01X1384501Y1123359D01*
X1385309Y1121960D01*
X1385279Y1121874D01*
G03X1385206Y1121447I1225J-429D01*
G03X1385922Y1120287I1298J0D01*
G01X1386032Y1120232D01*
Y1117187D01*
G03X1386325Y1116480I999J0D01*
G01X1390768Y1112037D01*
X1390760Y1111944D01*
G03X1390756Y1111834I1293J-102D01*
G03X1392053Y1110536I1298J0D01*
G03X1392163Y1110541I-4J1298D01*
G01X1392256Y1110549D01*
X1392981Y1109824D01*
G02Y1109542I-142J-141D01*
G03X1392606Y1108630I923J-913D01*
G03X1393904Y1107332I1298J0D01*
G03X1394816Y1107707I-1J1298D01*
G02X1395098I141J-142D01*
G01X1395489Y1107316D01*
G02X1395335Y1106654I-283J-283D01*
G03X1394714Y1106204I417J-1229D01*
G01X1393092D01*
G03X1392053Y1106724I-1039J-778D01*
G03Y1104128I0J-1298D01*
G03X1393092Y1104648I0J1298D01*
G01X1394714D01*
G03X1395753Y1104128I1039J778D01*
G03X1396981Y1105008I0J1297D01*
G02X1397643Y1105162I379J-129D01*
G01X1400099Y1102706D01*
X1400065Y1102591D01*
G03X1400011Y1102221I1238J-370D01*
G03X1400727Y1101064I1293J0D01*
G01X1400838Y1101009D01*
Y1097030D01*
X1400727Y1096975D01*
G03X1400006Y1095813I576J-1162D01*
G03X1400079Y1095385I1298J1D01*
G01X1400110Y1095298D01*
X1399303Y1093900D01*
X1399212Y1093883D01*
G03X1398156Y1092608I242J-1275D01*
G03X1399453Y1091310I1298J0D01*
G03X1400206Y1091551I0J1297D01*
G02X1400838Y1091226I232J-326D01*
G01Y1090615D01*
X1400727Y1090560D01*
G03Y1088248I577J-1156D01*
G01X1400838Y1088193D01*
Y1087582D01*
G02X1400206Y1087257I-400J1D01*
G03X1399453Y1087498I-753J-1056D01*
G03X1398414Y1086978I0J-1298D01*
G01X1396792D01*
G03X1395753Y1087498I-1039J-778D01*
G03Y1084902I0J-1298D01*
G03X1396792Y1085422I0J1298D01*
G01X1398414D01*
G03X1399453Y1084902I1039J778D01*
G03X1400206Y1085143I0J1297D01*
G02X1400838Y1084818I232J-326D01*
G01Y1084212D01*
X1400727Y1084157D01*
G03Y1081833I576J-1162D01*
G01X1400838Y1081778D01*
Y1077798D01*
X1400727Y1077743D01*
G03Y1075431I577J-1156D01*
G01X1400838Y1075376D01*
Y1071389D01*
X1400727Y1071334D01*
G03Y1069022I577J-1156D01*
G01X1400838Y1068967D01*
Y1064981D01*
X1400727Y1064926D01*
G03Y1062614I577J-1156D01*
G01X1400838Y1062559D01*
Y1058572D01*
X1400727Y1058517D01*
G03Y1056205I577J-1156D01*
G01X1400838Y1056150D01*
Y1052163D01*
X1400727Y1052108D01*
G03Y1049796I577J-1156D01*
G01X1400838Y1049741D01*
Y1045755D01*
X1400727Y1045700D01*
G03Y1043388I577J-1156D01*
G01X1400838Y1043333D01*
Y1042999D01*
X1400226Y1042387D01*
X1400094Y1042463D01*
G03X1399454Y1042632I-639J-1123D01*
G03X1398162Y1041340I0J-1292D01*
G03X1398331Y1040700I1292J-1D01*
G01X1398407Y1040568D01*
X1396359Y1038520D01*
G03X1396066Y1037813I706J-707D01*
G01Y1031960D01*
G03X1396359Y1031253I999J0D01*
G01X1397675Y1029937D01*
G03X1398382Y1029644I707J706D01*
G01X1399181D01*
X1399936Y1028889D01*
Y1028299D01*
X1399464Y1027827D01*
X1391777D01*
G03X1391070Y1027534I0J-999D01*
G01X1390700Y1027164D01*
X1389525D01*
X1389401Y1027289D01*
G03X1389374Y1027314I-353J-354D01*
G01X1389367Y1027319D01*
X1387716Y1028971D01*
Y1030699D01*
G03X1388214Y1031564I-502J865D01*
G01Y1048564D01*
G03X1387921Y1049271I-999J0D01*
G01X1381221Y1055971D01*
G03X1380514Y1056264I-707J-706D01*
G01X1356614D01*
G03X1355907Y1055971I0J-999D01*
G01X1355354Y1055418D01*
X1355253Y1055433D01*
G03X1355053Y1055449I-203J-1276D01*
G03X1353761Y1054157I0J-1292D01*
G03X1353777Y1053957I1292J3D01*
G01X1353792Y1053856D01*
X1345774Y1045838D01*
X1345700Y1045832D01*
G03X1344516Y1044648I104J-1288D01*
G01X1344510Y1044574D01*
X1339142Y1039206D01*
X1339012Y1039276D01*
G03X1337264Y1037528I-608J-1140D01*
G01X1337334Y1037398D01*
X1336063Y1036127D01*
X1336029Y1036112D01*
G03X1335372Y1035455I524J-1181D01*
G01X1335357Y1035421D01*
X1329655Y1029719D01*
X1329540Y1029756D01*
G03X1329153Y1029815I-386J-1233D01*
G03X1327861Y1028523I0J-1292D01*
G03X1327961Y1028025I1292J0D01*
G01X1327907Y1027971D01*
G03X1327614Y1027264I706J-707D01*
G01Y983426D01*
X1327589Y983381D01*
G03X1327428Y982756I1131J-625D01*
G03X1327589Y982131I1292J0D01*
G01X1327614Y982086D01*
Y977015D01*
X1327589Y976970D01*
G03Y975724I1133J-623D01*
G01X1327614Y975679D01*
Y970609D01*
X1327589Y970564D01*
G03X1327428Y969939I1131J-625D01*
G03X1327589Y969314I1292J0D01*
G01X1327614Y969269D01*
Y964200D01*
X1327589Y964155D01*
G03X1327428Y963530I1131J-625D01*
G03X1327589Y962905I1292J0D01*
G01X1327614Y962860D01*
Y957792D01*
X1327589Y957747D01*
G03X1327428Y957122I1131J-625D01*
G03X1327589Y956497I1292J0D01*
G01X1327614Y956452D01*
Y951383D01*
X1327589Y951338D01*
G03X1327428Y950713I1131J-625D01*
G03X1327589Y950088I1292J0D01*
G01X1327614Y950043D01*
Y944974D01*
X1327589Y944929D01*
G03X1327428Y944304I1131J-625D01*
G03X1327589Y943679I1292J0D01*
G01X1327614Y943634D01*
Y938566D01*
X1327589Y938521D01*
G03X1327428Y937896I1131J-625D01*
G03X1327589Y937271I1292J0D01*
G01X1327614Y937226D01*
Y932158D01*
X1327589Y932113D01*
G03X1327428Y931488I1131J-625D01*
G03X1327589Y930863I1292J0D01*
G01X1327614Y930818D01*
Y925749D01*
X1327589Y925704D01*
G03X1327428Y925079I1131J-625D01*
G03X1327589Y924454I1292J0D01*
G01X1327614Y924409D01*
Y919340D01*
X1327589Y919295D01*
G03X1327428Y918670I1131J-625D01*
G03X1327589Y918045I1292J0D01*
G01X1327614Y918000D01*
Y915664D01*
G03X1327907Y914957I999J0D01*
G01X1331420Y911444D01*
G03X1331595Y911267I1002J816D01*
G01X1331603Y911261D01*
X1333149Y909715D01*
X1333092Y909589D01*
G03X1332978Y909057I1178J-531D01*
G03X1334270Y907765I1292J0D01*
G03X1334802Y907879I1J1292D01*
G01X1334928Y907936D01*
X1340389Y902475D01*
X1340401Y902414D01*
G03X1341436Y901379I1270J235D01*
G01X1341497Y901367D01*
X1342550Y900314D01*
X1342455Y900177D01*
G03X1342228Y899445I1065J-732D01*
G03X1343520Y898153I1292J0D01*
G03X1344252Y898380I0J1292D01*
G01X1344389Y898475D01*
X1349639Y893225D01*
X1349632Y893134D01*
G03X1349628Y893036I1288J-102D01*
G03X1350920Y891744I1292J0D01*
G03X1351018Y891748I-4J1292D01*
G01X1351109Y891755D01*
X1356714Y886150D01*
Y885399D01*
X1356319Y884715D01*
X1356229Y884698D01*
G03X1355174Y883423I243J-1275D01*
G03X1356351Y882131I1298J0D01*
G02X1356714Y881733I-37J-398D01*
G01Y872582D01*
X1356319Y871898D01*
X1356229Y871881D01*
G03X1355174Y870606I243J-1275D01*
G03X1356351Y869314I1298J0D01*
G02X1356714Y868916I-37J-398D01*
G01Y868494D01*
X1356301Y868081D01*
G02X1355689Y868137I-283J283D01*
G03X1354862Y868676I-1069J-736D01*
G01X1354772Y868693D01*
X1353965Y870091D01*
X1353996Y870177D01*
G03X1354068Y870606I-1225J426D01*
G03X1351474I-1297J0D01*
G03X1352529Y869331I1298J0D01*
G01X1352619Y869314D01*
X1353426Y867916D01*
X1353395Y867830D01*
G03X1353322Y867401I1224J-429D01*
G03X1353884Y866332I1298J0D01*
G02X1353940Y865720I-227J-329D01*
G01X1353496Y865276D01*
X1353366Y865344D01*
G03X1352771Y865489I-595J-1148D01*
G03X1351479Y864197I0J-1292D01*
G03X1351624Y863602I1293J0D01*
G01X1351692Y863472D01*
X1350404Y862184D01*
X1350372Y862169D01*
G03X1349744Y861541I548J-1176D01*
G01X1349729Y861509D01*
X1348217Y859997D01*
X1345109D01*
G02X1344735Y860537I1J400D01*
G03X1344818Y860993I-1215J457D01*
G03X1342222I-1298J0D01*
G03X1342295Y860565I1298J1D01*
G01X1342326Y860478D01*
X1342048Y859997D01*
X1337709D01*
G02X1337335Y860537I1J400D01*
G03X1337418Y860993I-1215J457D01*
G03X1334822I-1298J0D01*
G03X1334895Y860565I1298J1D01*
G01X1334926Y860478D01*
X1334648Y859997D01*
X1330309D01*
G02X1329935Y860537I1J400D01*
G03X1330018Y860993I-1215J457D01*
G03X1327422I-1298J0D01*
G03X1327495Y860565I1298J1D01*
G01X1327526Y860478D01*
X1327248Y859997D01*
X1123179D01*
X1121400Y861776D01*
Y1256162D01*
G03X1121107Y1256869I-999J0D01*
G01X1120144Y1257832D01*
G03X1119797Y1258058I-707J-707D01*
G02X1119675Y1258289I73J186D01*
G03X1119700Y1258512I-975J222D01*
G01Y1382158D01*
X1122234Y1384692D01*
X1123366D01*
X1123421Y1384580D01*
G03X1124679Y1383798I1258J621D01*
G03X1125652Y1384190I1J1402D01*
G02X1126206I277J-288D01*
G03X1127179Y1383798I972J1010D01*
G03X1128171Y1384209I0J1403D01*
G02X1128737I283J-282D01*
G03X1129729Y1383798I992J992D01*
G03X1130987Y1384580I0J1403D01*
G01X1131042Y1384692D01*
X1142934D01*
X1142989Y1384580D01*
G03X1144247Y1383798I1258J621D01*
G03X1145239Y1384209I0J1403D01*
G02X1145805I283J-282D01*
G03X1146797Y1383798I992J992D01*
G03X1147770Y1384190I1J1402D01*
G02X1148324I277J-288D01*
G03X1149297Y1383798I972J1010D01*
G03X1150555Y1384580I0J1403D01*
G01X1150610Y1384692D01*
X1161466D01*
X1161521Y1384580D01*
G03X1162779Y1383798I1258J621D01*
G03X1163752Y1384190I1J1402D01*
G02X1164306I277J-288D01*
G03X1165279Y1383798I972J1010D01*
G03X1166271Y1384209I0J1403D01*
G02X1166837I283J-282D01*
G03X1167829Y1383798I992J992D01*
G03X1169087Y1384580I0J1403D01*
G01X1169142Y1384692D01*
X1181434D01*
X1181489Y1384580D01*
G03X1182747Y1383798I1258J621D01*
G03X1183739Y1384209I0J1403D01*
G02X1184305I283J-282D01*
G03X1185297Y1383798I992J992D01*
G03X1186270Y1384190I1J1402D01*
G02X1186824I277J-288D01*
G03X1187797Y1383798I972J1010D01*
G03X1189104Y1384693I0J1402D01*
G03X1189592Y1384795I46J998D01*
G01X1189634Y1384816D01*
G37*
G36*
G01X1357028Y1054264D02*
X1379652D01*
X1379664Y1054076D01*
G03X1380953Y1052865I1289J81D01*
G03X1381305Y1052914I0J1292D01*
G01X1381418Y1052946D01*
X1386214Y1048150D01*
Y1045811D01*
X1386080Y1045764D01*
G03Y1043324I423J-1220D01*
G01X1386214Y1043277D01*
Y1031564D01*
G03X1386714Y1030698I1000J0D01*
G01Y1029813D01*
G03X1386415Y1028854I1388J-959D01*
G03X1388027Y1027169I1687J0D01*
G01X1388105Y1027165D01*
X1388960Y1026310D01*
G03X1388993Y1026281I346J361D01*
G01X1389001Y1026274D01*
X1389526Y1025748D01*
X1389518Y1025655D01*
G03X1389514Y1025564I996J-89D01*
G01Y1012178D01*
X1388100Y1010764D01*
X1384299D01*
G03X1384272Y1010792I-733J-680D01*
G01X1383014Y1012050D01*
Y1025664D01*
G03X1382721Y1026371I-999J0D01*
G01X1382426Y1026666D01*
X1382430Y1026755D01*
G03X1382432Y1026821I-1290J72D01*
G03X1381140Y1028113I-1292J0D01*
G03X1381074Y1028111I6J-1292D01*
G01X1380985Y1028107D01*
X1380521Y1028571D01*
G03X1379814Y1028864I-707J-706D01*
G01X1378507D01*
X1378457Y1028991D01*
G03X1376049I-1204J-468D01*
G01X1375999Y1028864D01*
X1374807D01*
X1374757Y1028991D01*
G03X1372349I-1204J-468D01*
G01X1372299Y1028864D01*
X1371107D01*
X1371057Y1028991D01*
G03X1368649I-1204J-468D01*
G01X1368599Y1028864D01*
X1367407D01*
X1367357Y1028991D01*
G03X1364949I-1204J-468D01*
G01X1364899Y1028864D01*
X1363707D01*
X1363657Y1028991D01*
G03X1361249I-1204J-468D01*
G01X1361199Y1028864D01*
X1360007D01*
X1359957Y1028991D01*
G03X1358753Y1029815I-1204J-468D01*
G03X1357461Y1028523I0J-1292D01*
G03X1357607Y1027925I1292J-1D01*
G01X1357675Y1027795D01*
X1356381Y1026501D01*
X1356349Y1026486D01*
G03X1355610Y1025318I554J-1168D01*
G03X1355978Y1024415I1292J0D01*
G01Y1019811D01*
G03Y1018009I926J-901D01*
G01Y1013402D01*
G03Y1011600I926J-901D01*
G01Y1006994D01*
G03Y1005192I926J-901D01*
G01Y1000585D01*
G03Y998783I926J-901D01*
G01Y980752D01*
X1355871Y980696D01*
G03Y978408I600J-1144D01*
G01X1355978Y978352D01*
Y974344D01*
X1355871Y974288D01*
G03Y971998I599J-1145D01*
G01X1355978Y971942D01*
Y967935D01*
X1355871Y967879D01*
G03Y965591I600J-1144D01*
G01X1355978Y965535D01*
Y961526D01*
X1355871Y961470D01*
G03Y959182I600J-1144D01*
G01X1355978Y959126D01*
Y955117D01*
X1355871Y955061D01*
G03Y952773I600J-1144D01*
G01X1355978Y952717D01*
Y948709D01*
X1355871Y948653D01*
G03Y946365I600J-1144D01*
G01X1355978Y946309D01*
Y942300D01*
X1355871Y942244D01*
G03Y939956I600J-1144D01*
G01X1355978Y939900D01*
Y935891D01*
X1355871Y935835D01*
G03Y933547I600J-1144D01*
G01X1355978Y933491D01*
Y929483D01*
X1355871Y929427D01*
G03Y927139I600J-1144D01*
G01X1355978Y927083D01*
Y924954D01*
G03X1356271Y924247I999J0D01*
G01X1358905Y921613D01*
X1358918Y921560D01*
G03X1359856Y920622I1253J315D01*
G01X1359909Y920609D01*
X1361018Y919500D01*
X1360932Y919365D01*
G03X1360729Y918670I1088J-695D01*
G03X1362021Y917378I1292J0D01*
G03X1362716Y917581I0J1291D01*
G01X1362851Y917667D01*
X1368131Y912387D01*
X1368129Y912301D01*
G03X1368128Y912262I1291J-53D01*
G03X1369420Y910970I1292J0D01*
G03X1369459Y910971I-14J1292D01*
G01X1369545Y910973D01*
X1377445Y903073D01*
X1377418Y902963D01*
G03X1377379Y902649I1253J-315D01*
G03X1378671Y901357I1292J0D01*
G03X1378985Y901396I-1J1292D01*
G01X1379095Y901423D01*
X1384971Y895547D01*
Y890512D01*
X1384945Y890466D01*
G03X1384779Y889832I1126J-634D01*
G03X1384945Y889198I1292J0D01*
G01X1384971Y889152D01*
Y884113D01*
X1384945Y884067D01*
G03Y882779I1127J-644D01*
G01X1384971Y882733D01*
Y881880D01*
G02X1384488Y881488I-400J-1D01*
G03X1384461Y881494I-295J-1263D01*
G01X1384371Y881511D01*
X1383565Y882908D01*
X1383596Y882994D01*
G03X1383668Y883423I-1225J426D01*
G03X1381074I-1297J0D01*
G03X1382129Y882148I1298J0D01*
G01X1382219Y882131D01*
X1383025Y880734D01*
X1382995Y880647D01*
G03X1382922Y880219I1225J-429D01*
G03X1384220Y878922I1297J0D01*
G03X1384488Y878950I0J1297D01*
G02X1384971Y878558I83J-391D01*
G01Y877694D01*
X1384945Y877648D01*
G03X1384779Y877014I1126J-634D01*
G03X1384945Y876380I1292J0D01*
G01X1384971Y876334D01*
Y874363D01*
X1382507Y871899D01*
X1382420Y871903D01*
G03X1382371Y871904I-51J-1297D01*
G03X1381074Y870606I0J-1297D01*
G01Y870557D01*
X1381078Y870470D01*
X1378574Y867966D01*
G02X1377944Y868049I-283J282D01*
G03X1377062Y868676I-1124J-648D01*
G01X1376972Y868693D01*
X1376165Y870091D01*
X1376196Y870177D01*
G03X1376268Y870606I-1225J426D01*
G03X1373674I-1297J0D01*
G03X1374729Y869331I1298J0D01*
G01X1374819Y869314D01*
X1375626Y867916D01*
X1375595Y867830D01*
G03X1375522Y867401I1224J-429D01*
G03X1376172Y866277I1297J0D01*
G02X1376255Y865647I-199J-347D01*
G01X1375805Y865197D01*
X1375669Y865284D01*
G03X1374971Y865489I-698J-1086D01*
G03X1373679Y864197I0J-1292D01*
G03X1373884Y863499I1291J0D01*
G01X1373971Y863363D01*
X1373835Y863227D01*
G03X1373542Y862520I706J-707D01*
G01Y862274D01*
X1373327D01*
X1373312Y862276D01*
G03X1373120Y862290I-190J-1283D01*
G03X1371822Y860993I0J-1298D01*
G03X1371895Y860565I1298J1D01*
G01X1371926Y860478D01*
X1371119Y859081D01*
X1371029Y859064D01*
G03X1369974Y857789I243J-1275D01*
G03X1372568I1297J0D01*
G03X1372496Y858217I-1297J2D01*
G01X1372465Y858304D01*
X1372796Y858876D01*
G02X1373542Y858676I346J-200D01*
G01Y849873D01*
G02X1373137Y849473I-400J0D01*
G03X1373120Y849474I-85J-1293D01*
G03X1371822Y848176I0J-1298D01*
G03X1372878Y846901I1298J0D01*
G01X1372968Y846884D01*
X1373542Y845889D01*
Y745470D01*
G03X1373835Y744763I999J0D01*
G01X1376073Y742525D01*
G03X1376780Y742232I707J706D01*
G01X1398006D01*
X1399940Y740298D01*
Y687042D01*
G03X1400233Y686335I999J0D01*
G01X1468076Y618492D01*
G03X1468783Y618199I707J706D01*
G01X1612228D01*
X1614042Y616385D01*
Y587013D01*
X1612335Y585306D01*
G03X1612176Y585099I707J-707D01*
G01X1608020D01*
G03X1606380I-820J-1136D01*
G01X1562761D01*
G03X1560227I-1267J-807D01*
G01X1401697D01*
X1254220Y732576D01*
Y763305D01*
X1255187D01*
G03Y765305I0J1000D01*
G01X1254220D01*
Y766298D01*
X1254233Y766332D01*
G03X1254297Y766685I-937J352D01*
G03X1254233Y767038I-1001J1D01*
G01X1254220Y767072D01*
Y856004D01*
X1256213Y857997D01*
X1325574D01*
Y857796D01*
Y857789D01*
G03X1328168I1297J0D01*
G01Y857796D01*
Y857997D01*
X1329274D01*
Y857796D01*
Y857789D01*
G03X1330329Y856514I1298J0D01*
G01X1330419Y856497D01*
X1331226Y855099D01*
X1331195Y855013D01*
G03X1331122Y854584I1224J-429D01*
G03X1333718I1298J0D01*
G03X1332662Y855859I-1298J0D01*
G01X1332572Y855876D01*
X1331765Y857274D01*
X1331796Y857360D01*
G03X1331868Y857789I-1225J426D01*
G01Y857796D01*
Y857997D01*
X1332974D01*
Y857796D01*
Y857789D01*
G03X1335568I1297J0D01*
G01Y857796D01*
Y857997D01*
X1336674D01*
Y857796D01*
Y857789D01*
G03X1337729Y856514I1298J0D01*
G01X1337819Y856497D01*
X1338626Y855099D01*
X1338595Y855013D01*
G03X1338522Y854584I1224J-429D01*
G03X1341118I1298J0D01*
G03X1340062Y855859I-1298J0D01*
G01X1339972Y855876D01*
X1339165Y857274D01*
X1339196Y857360D01*
G03X1339268Y857789I-1225J426D01*
G01Y857796D01*
Y857997D01*
X1340374D01*
Y857796D01*
Y857789D01*
G03X1342968I1297J0D01*
G01Y857796D01*
Y857997D01*
X1344074D01*
Y857796D01*
Y857789D01*
G03X1345129Y856514I1298J0D01*
G01X1345219Y856497D01*
X1346026Y855099D01*
X1345995Y855013D01*
G03X1345922Y854584I1224J-429D01*
G03X1348518I1298J0D01*
G03X1347462Y855859I-1298J0D01*
G01X1347372Y855876D01*
X1346565Y857274D01*
X1346596Y857360D01*
G03X1346668Y857789I-1225J426D01*
G01Y857796D01*
Y857997D01*
X1347774D01*
Y857796D01*
Y857789D01*
G03X1350368I1297J0D01*
G03X1350296Y858217I-1297J2D01*
G01X1350265Y858304D01*
X1351072Y859701D01*
X1351162Y859718D01*
G03X1352218Y860993I-242J1275D01*
G03X1352215Y861072I-1298J-10D01*
G01X1352210Y861162D01*
X1357466Y866418D01*
X1357603Y866327D01*
G03X1358321Y866109I718J1073D01*
G03X1359613Y867401I0J1292D01*
G03X1358835Y868587I-1293J0D01*
G01X1358714Y868639D01*
Y869278D01*
G02X1359363Y869591I400J0D01*
G03X1359929Y869331I809J1015D01*
G01X1360019Y869314D01*
X1360826Y867916D01*
X1360795Y867830D01*
G03X1360722Y867401I1224J-429D01*
G03X1363318I1298J0D01*
G03X1362262Y868676I-1298J0D01*
G01X1362172Y868693D01*
X1361365Y870091D01*
X1361396Y870177D01*
G03X1361468Y870606I-1225J426D01*
G03X1360171Y871904I-1298J0D01*
G03X1359363Y871621I1J-1298D01*
G02X1358714Y871934I-249J313D01*
G01Y872567D01*
X1358835Y872619D01*
G03Y875001I-514J1191D01*
G01X1358714Y875053D01*
Y878981D01*
X1358835Y879033D01*
G03Y881405I-515J1186D01*
G01X1358714Y881457D01*
Y882095D01*
G02X1359363Y882408I400J0D01*
G03X1359929Y882148I809J1015D01*
G01X1360019Y882131D01*
X1360825Y880734D01*
X1360795Y880647D01*
G03X1360722Y880219I1225J-429D01*
G03X1363318I1298J0D01*
G03X1362261Y881494I-1297J0D01*
G01X1362171Y881511D01*
X1361365Y882908D01*
X1361396Y882994D01*
G03X1361468Y883423I-1225J426D01*
G03X1360171Y884720I-1297J0D01*
G03X1359363Y884438I0J-1297D01*
G02X1358714Y884751I-249J313D01*
G01Y885384D01*
X1358835Y885436D01*
G03X1359618Y886627I-514J1191D01*
G03X1358320Y887924I-1297J0D01*
G03X1357963Y887874I0J-1297D01*
G01X1357850Y887842D01*
X1352074Y893618D01*
X1352060Y893644D01*
G03X1351528Y894176I-1140J-608D01*
G01X1351502Y894190D01*
X1350161Y895531D01*
X1350226Y895660D01*
G03X1350363Y896240I-1155J579D01*
G03X1349071Y897532I-1292J0D01*
G03X1348491Y897395I-1J-1292D01*
G01X1348362Y897330D01*
X1342962Y902730D01*
X1342954Y902799D01*
G03X1341821Y903932I-1283J-150D01*
G01X1341752Y903940D01*
X1340751Y904941D01*
X1340855Y905079D01*
G03X1341112Y905853I-1035J773D01*
G03X1339820Y907145I-1292J0D01*
G03X1339046Y906888I-1J-1292D01*
G01X1338908Y906784D01*
X1333689Y912003D01*
X1333702Y912100D01*
G03X1333712Y912262I-1282J160D01*
G03X1332420Y913554I-1292J0D01*
G03X1332258Y913544I-2J-1292D01*
G01X1332161Y913531D01*
X1329614Y916078D01*
Y917737D01*
G03Y919603I-895J933D01*
G01Y924146D01*
G03Y926012I-895J933D01*
G01Y930555D01*
G03Y932421I-895J933D01*
G01Y936963D01*
G03Y938829I-895J933D01*
G01Y943371D01*
G03Y945237I-895J933D01*
G01Y949780D01*
G03Y951646I-895J933D01*
G01Y956189D01*
G03Y958055I-895J933D01*
G01Y962597D01*
G03Y964463I-895J933D01*
G01Y969006D01*
G03Y970872I-895J933D01*
G01Y975413D01*
G03Y977281I-894J934D01*
G01Y981823D01*
G03Y983689I-895J933D01*
G01Y1001675D01*
X1329725Y1001730D01*
G03Y1004046I-571J1158D01*
G01X1329614Y1004101D01*
Y1008084D01*
X1329725Y1008139D01*
G03Y1010455I-571J1158D01*
G01X1329614Y1010510D01*
Y1014492D01*
X1329725Y1014547D01*
G03Y1016863I-571J1158D01*
G01X1329614Y1016918D01*
Y1020901D01*
X1329725Y1020956D01*
G03Y1023272I-571J1158D01*
G01X1329614Y1023327D01*
Y1026850D01*
X1336408Y1033644D01*
X1336496Y1033640D01*
G03X1336553Y1033639I51J1291D01*
G03X1337845Y1034931I0J1292D01*
G03X1337844Y1034988I-1292J6D01*
G01X1337840Y1035076D01*
X1343111Y1040347D01*
X1343247Y1040258D01*
G03X1343953Y1040048I706J1082D01*
G03X1345245Y1041340I0J1292D01*
G03X1345035Y1042046I-1292J0D01*
G01X1344946Y1042182D01*
X1346036Y1043272D01*
X1346092Y1043284D01*
G03X1347064Y1044256I-288J1260D01*
G01X1347076Y1044312D01*
X1352578Y1049814D01*
X1352702Y1049762D01*
G03X1353204Y1049660I503J1190D01*
G03X1354496Y1050952I0J1292D01*
G03X1354394Y1051454I-1292J-1D01*
G01X1354342Y1051578D01*
X1357028Y1054264D01*
G37*
G36*
G01X1272064Y1308048D02*
X1298190D01*
X1324490Y1281748D01*
G03X1325197Y1281455I707J706D01*
G01X1335043D01*
X1345641Y1270857D01*
G03X1346348Y1270564I707J706D01*
G01X1468514D01*
G03X1469221Y1270857I0J999D01*
G01X1471821Y1273457D01*
G03X1472114Y1274164I-706J707D01*
G01Y1279050D01*
X1477528Y1284464D01*
X1492266D01*
G03X1492973Y1284757I0J999D01*
G01X1508031Y1299815D01*
X1544393D01*
X1545707Y1298501D01*
Y1166619D01*
X1518161Y1139073D01*
X1503030D01*
X1502350Y1140359D01*
X1502389Y1140448D01*
G03X1502500Y1140973I-1186J525D01*
G03X1499906I-1297J0D01*
G03X1500968Y1139697I1298J0D01*
G01X1501063Y1139679D01*
X1501229Y1139366D01*
G02X1501052Y1139073I-177J-93D01*
G01X1495630D01*
X1494950Y1140359D01*
X1494989Y1140448D01*
G03X1495100Y1140973I-1186J525D01*
G03X1492506I-1297J0D01*
G03X1493568Y1139697I1298J0D01*
G01X1493663Y1139679D01*
X1493829Y1139366D01*
G02X1493652Y1139073I-177J-93D01*
G01X1488230D01*
X1487550Y1140359D01*
X1487589Y1140448D01*
G03X1487700Y1140973I-1186J525D01*
G03X1485106I-1297J0D01*
G03X1486168Y1139697I1298J0D01*
G01X1486263Y1139679D01*
X1486429Y1139366D01*
G02X1486252Y1139073I-177J-93D01*
G01X1480830D01*
X1480150Y1140359D01*
X1480189Y1140448D01*
G03X1480300Y1140973I-1186J525D01*
G03X1477706I-1297J0D01*
G03X1478768Y1139697I1298J0D01*
G01X1478863Y1139679D01*
X1479029Y1139366D01*
G02X1478852Y1139073I-177J-93D01*
G01X1473430D01*
X1472750Y1140359D01*
X1472789Y1140448D01*
G03X1472900Y1140973I-1186J525D01*
G03X1470306I-1297J0D01*
G03X1471368Y1139697I1298J0D01*
G01X1471463Y1139679D01*
X1471629Y1139366D01*
G02X1471452Y1139073I-177J-93D01*
G01X1466030D01*
X1465350Y1140359D01*
X1465389Y1140448D01*
G03X1465500Y1140973I-1186J525D01*
G03X1462906I-1297J0D01*
G03X1463968Y1139697I1298J0D01*
G01X1464063Y1139679D01*
X1464229Y1139366D01*
G02X1464052Y1139073I-177J-93D01*
G01X1458630D01*
X1457950Y1140359D01*
X1457989Y1140448D01*
G03X1458100Y1140973I-1186J525D01*
G03X1455506I-1297J0D01*
G03X1456568Y1139697I1298J0D01*
G01X1456663Y1139679D01*
X1456829Y1139366D01*
G02X1456652Y1139073I-177J-93D01*
G01X1455521D01*
G03X1454814Y1138780I0J-999D01*
G01X1454790Y1138756D01*
G03X1453656Y1137469I163J-1287D01*
G03X1453700Y1137138I1297J4D01*
G01X1453721Y1137058D01*
X1452849Y1135539D01*
X1452769Y1135518D01*
G03X1451806Y1134264I335J-1254D01*
G03X1451853Y1133920I1298J2D01*
G01X1451875Y1133840D01*
X1451010Y1132332D01*
X1450929Y1132311D01*
G03X1449961Y1131060I324J-1251D01*
G03X1450010Y1130708I1292J0D01*
G01X1450033Y1130627D01*
X1449178Y1129137D01*
X1449095Y1129116D01*
G03X1448106Y1127856I308J-1260D01*
G03X1448160Y1127486I1298J0D01*
G01X1448185Y1127404D01*
X1447342Y1125934D01*
X1447257Y1125914D01*
G03X1446256Y1124651I296J-1263D01*
G03X1446313Y1124268I1297J-3D01*
G01X1446339Y1124185D01*
X1445506Y1122732D01*
X1445420Y1122713D01*
G03X1444406Y1121447I283J-1266D01*
G03X1444468Y1121053I1298J2D01*
G01X1444495Y1120969D01*
X1443666Y1119525D01*
X1443580Y1119506D01*
G03X1442561Y1118243I273J-1263D01*
G03X1442625Y1117841I1292J0D01*
G01X1442653Y1117757D01*
X1441830Y1116322D01*
X1441742Y1116304D01*
G03X1440712Y1115039I262J-1265D01*
G03X1440780Y1114626I1292J1D01*
G01X1440809Y1114541D01*
X1439994Y1113119D01*
X1439904Y1113102D01*
G03X1438862Y1111834I251J-1268D01*
G03X1438934Y1111409I1292J0D01*
G01X1438964Y1111323D01*
X1438157Y1109917D01*
X1438067Y1109900D01*
G03X1437012Y1108630I237J-1270D01*
G03X1437088Y1108193I1292J0D01*
G01X1437119Y1108107D01*
X1436321Y1106715D01*
X1436229Y1106698D01*
G03X1435162Y1105426I225J-1272D01*
G03X1435242Y1104978I1292J0D01*
G01X1435275Y1104890D01*
X1434484Y1103511D01*
X1434391Y1103495D01*
G03X1433312Y1102221I213J-1274D01*
G03X1433396Y1101762I1292J-1D01*
G01X1433430Y1101673D01*
X1432648Y1100308D01*
X1432553Y1100293D01*
G03X1431461Y1099017I200J-1276D01*
G03X1431914Y1098034I1293J0D01*
G01Y1093589D01*
G03Y1091625I841J-982D01*
G01Y1087183D01*
G03Y1085217I840J-983D01*
G01Y1080773D01*
G03Y1078809I841J-982D01*
G01Y1074366D01*
G03Y1072400I840J-983D01*
G01Y1067957D01*
G03Y1065991I840J-983D01*
G01Y1061548D01*
G03Y1059582I840J-983D01*
G01Y1055140D01*
G03Y1053174I840J-983D01*
G01Y1048732D01*
G03Y1046766I840J-983D01*
G01Y1042323D01*
G03Y1040357I840J-983D01*
G01Y1028264D01*
G03X1432207Y1027557I999J0D01*
G01X1434807Y1024957D01*
G03X1435514Y1024664I707J706D01*
G01X1450800D01*
X1451429Y1024035D01*
G02X1451446Y1023488I-283J-283D01*
G03X1451124Y1022635I969J-853D01*
G03X1451808Y1021495I1292J0D01*
G01X1451914Y1021438D01*
Y1018717D01*
X1451809Y1018660D01*
G03Y1016390I617J-1135D01*
G01X1451914Y1016333D01*
Y1014117D01*
X1451809Y1014060D01*
G03X1451134Y1012925I617J-1135D01*
G03X1451529Y1011995I1292J0D01*
G02X1451531Y1011422I-278J-287D01*
G03X1451144Y1010499I905J-922D01*
G03X1451811Y1009368I1292J0D01*
G01X1451914Y1009311D01*
Y1007217D01*
X1451809Y1007160D01*
G03X1451134Y1006025I617J-1135D01*
G03X1451478Y1005147I1292J0D01*
G02Y1004603I-293J-272D01*
G03X1451134Y1003725I948J-878D01*
G03X1451809Y1002590I1292J0D01*
G01X1451914Y1002533D01*
Y998017D01*
X1451809Y997960D01*
G03X1451134Y996825I617J-1135D01*
G03X1451478Y995947I1292J0D01*
G02Y995403I-293J-272D01*
G03X1451134Y994525I948J-878D01*
G03X1451809Y993390I1292J0D01*
G01X1451914Y993333D01*
Y991117D01*
X1451809Y991060D01*
G03X1451134Y989925I617J-1135D01*
G03X1451478Y989047I1292J0D01*
G02Y988503I-293J-272D01*
G03X1451134Y987625I948J-878D01*
G03X1451809Y986490I1292J0D01*
G01X1451914Y986433D01*
Y981899D01*
G03X1451187Y980821I562J-1163D01*
G01X1451182Y980746D01*
X1443107Y972671D01*
G03X1442814Y971964I706J-707D01*
G01Y964164D01*
G03X1443107Y963457I999J0D01*
G01X1448207Y958357D01*
G03X1448914Y958064I707J706D01*
G01X1451100D01*
X1451614Y957550D01*
Y955078D01*
X1450000Y953464D01*
X1439714D01*
G03X1439007Y953171I0J-999D01*
G01X1431507Y945671D01*
G03X1431214Y944964I706J-707D01*
G01Y939778D01*
X1429800Y938364D01*
X1426131D01*
X1426075Y938474D01*
G03X1423765I-1155J-577D01*
G01X1423709Y938364D01*
X1422431D01*
X1422375Y938474D01*
G03X1420065I-1155J-577D01*
G01X1420009Y938364D01*
X1418731D01*
X1418675Y938474D01*
G03X1416365I-1155J-577D01*
G01X1416309Y938364D01*
X1415031D01*
X1414975Y938474D01*
G03X1412665I-1155J-577D01*
G01X1412609Y938364D01*
X1411331D01*
X1411275Y938474D01*
G03X1408965I-1155J-577D01*
G01X1408909Y938364D01*
X1407631D01*
X1407575Y938474D01*
G03X1405265I-1155J-577D01*
G01X1405209Y938364D01*
X1387528D01*
X1382814Y943078D01*
Y965450D01*
X1384328Y966964D01*
X1388714D01*
G03X1389421Y967257I0J999D01*
G01X1390721Y968557D01*
G03X1391014Y969264I-706J707D01*
G01Y969945D01*
X1391119Y970002D01*
G03Y972276I-612J1137D01*
G01X1391014Y972333D01*
Y973964D01*
G03X1390721Y974671I-999J0D01*
G01X1388221Y977171D01*
G03X1387514Y977464I-707J-706D01*
G01X1384328D01*
X1383014Y978778D01*
Y1007513D01*
X1384265Y1008764D01*
X1388514D01*
G03X1389221Y1009057I0J999D01*
G01X1391221Y1011057D01*
G03X1391514Y1011764I-706J707D01*
G01Y1013252D01*
X1391662Y1013291D01*
G03Y1015787I-337J1248D01*
G01X1391514Y1015826D01*
Y1025150D01*
X1392191Y1025827D01*
X1399878D01*
G03X1400585Y1026120I0J999D01*
G01X1401643Y1027178D01*
G03X1401936Y1027885I-706J707D01*
G01Y1029303D01*
G03X1401643Y1030010I-999J0D01*
G01X1400302Y1031351D01*
G03X1399595Y1031644I-707J-706D01*
G01X1398796D01*
X1398066Y1032374D01*
Y1037399D01*
X1402545Y1041878D01*
G03X1402838Y1042585I-706J707D01*
G01Y1084098D01*
X1403306Y1084908D01*
X1403396Y1084925D01*
G03X1404452Y1086200I-242J1275D01*
G03X1403218Y1087496I-1298J0D01*
G02X1402838Y1087895I20J399D01*
G01Y1090913D01*
G02X1403218Y1091312I400J0D01*
G03X1404192Y1091830I-65J1296D01*
G01X1405814D01*
G03X1406853Y1091310I1039J778D01*
G03Y1093906I0J1298D01*
G03X1405814Y1093386I0J-1298D01*
G01X1404192D01*
G03X1403218Y1093904I-1039J-778D01*
G02X1402838Y1094303I20J399D01*
G01Y1102381D01*
G03X1402545Y1103088I-999J0D01*
G01X1400666Y1104967D01*
X1400698Y1105079D01*
G03X1400745Y1105426I-1245J345D01*
G03X1399453Y1106718I-1292J0D01*
G03X1399106Y1106671I-2J-1292D01*
G01X1398994Y1106639D01*
X1395607Y1110026D01*
X1395905Y1110542D01*
X1395995Y1110559D01*
G03X1397050Y1111834I-243J1275D01*
G03X1395753Y1113132I-1298J0D01*
G03X1394474Y1112052I0J-1297D01*
G02X1393797Y1111836I-394J67D01*
G01X1393209Y1112424D01*
X1393195Y1112450D01*
G03X1392669Y1112976I-1142J-616D01*
G01X1392643Y1112990D01*
X1391794Y1113839D01*
X1391398Y1114524D01*
X1391429Y1114611D01*
G03X1391502Y1115039I-1225J429D01*
G03X1390204Y1116336I-1297J0D01*
G03X1389626Y1116200I0J-1296D01*
G01X1389497Y1116136D01*
X1388032Y1117601D01*
Y1134521D01*
G03X1387739Y1135228I-999J0D01*
G01X1385894Y1137073D01*
X1385919Y1137180D01*
G03X1385952Y1137469I-1265J291D01*
G03X1384654Y1138766I-1297J0D01*
G03X1384261Y1138706I-3J-1297D01*
G03X1383576Y1138977I-684J-729D01*
G01X1383235D01*
G02X1382881Y1139564I0J400D01*
G01X1382943Y1139679D01*
X1383038Y1139697D01*
G03X1384100Y1140973I-236J1276D01*
G03X1381506I-1297J0D01*
G03X1381617Y1140447I1297J-1D01*
G01X1381656Y1140358D01*
X1380928Y1138977D01*
X1375835D01*
G02X1375481Y1139564I0J400D01*
G01X1375543Y1139679D01*
X1375638Y1139697D01*
G03X1376700Y1140973I-236J1276D01*
G03X1374106I-1297J0D01*
G03X1374217Y1140447I1297J-1D01*
G01X1374256Y1140358D01*
X1373528Y1138977D01*
X1368435D01*
G02X1368081Y1139564I0J400D01*
G01X1368143Y1139679D01*
X1368238Y1139697D01*
G03X1369300Y1140973I-236J1276D01*
G03X1366706I-1297J0D01*
G03X1366817Y1140447I1297J-1D01*
G01X1366856Y1140358D01*
X1366128Y1138977D01*
X1361035D01*
G02X1360681Y1139564I0J400D01*
G01X1360743Y1139679D01*
X1360838Y1139697D01*
G03X1361900Y1140973I-236J1276D01*
G03X1359306I-1297J0D01*
G03X1359417Y1140447I1297J-1D01*
G01X1359456Y1140358D01*
X1358728Y1138977D01*
X1353635D01*
G02X1353281Y1139564I0J400D01*
G01X1353343Y1139679D01*
X1353438Y1139697D01*
G03X1354500Y1140973I-236J1276D01*
G03X1351906I-1297J0D01*
G03X1352017Y1140447I1297J-1D01*
G01X1352056Y1140358D01*
X1351328Y1138977D01*
X1346235D01*
G02X1345881Y1139564I0J400D01*
G01X1345943Y1139679D01*
X1346038Y1139697D01*
G03X1347100Y1140973I-236J1276D01*
G03X1344506I-1297J0D01*
G03X1344617Y1140447I1297J-1D01*
G01X1344656Y1140358D01*
X1343928Y1138977D01*
X1338835D01*
G02X1338481Y1139564I0J400D01*
G01X1338543Y1139679D01*
X1338638Y1139697D01*
G03X1339700Y1140973I-236J1276D01*
G03X1337106I-1297J0D01*
G03X1337217Y1140447I1297J-1D01*
G01X1337256Y1140358D01*
X1336528Y1138977D01*
X1300799D01*
X1270587Y1169189D01*
Y1306571D01*
X1272064Y1308048D01*
G37*
G36*
G01X1456804Y1030435D02*
G03X1457538Y1030664I0J1291D01*
G01X1459769D01*
G03X1461237I734J1062D01*
G01X1463470D01*
G03X1464938I734J1062D01*
G01X1467170D01*
G03X1468638I734J1062D01*
G01X1470869D01*
G03X1471603Y1030435I734J1062D01*
G01X1471604D01*
G03X1472291Y1030633I0J1292D01*
G01X1472340Y1030664D01*
X1472614D01*
X1476098Y1027180D01*
Y1022860D01*
G03Y1021368I1056J-746D01*
G01Y1016449D01*
G03Y1014961I1055J-744D01*
G01Y1010043D01*
G03Y1008551I1056J-746D01*
G01Y1003634D01*
G03Y1002142I1056J-746D01*
G01Y983888D01*
G03Y981624I621J-1132D01*
G01Y977479D01*
G03Y975215I621J-1132D01*
G01Y971071D01*
G03Y968807I621J-1132D01*
G01Y964662D01*
G03Y962398I623J-1132D01*
G01Y958254D01*
G03Y955990I621J-1132D01*
G01Y951845D01*
G03Y949581I621J-1132D01*
G01Y945436D01*
G03X1475428Y944304I621J-1132D01*
G03X1475663Y943561I1292J0D01*
G01X1475760Y943424D01*
X1474721Y942385D01*
X1474658Y942374D01*
G03X1473597Y941313I213J-1274D01*
G01X1473586Y941250D01*
X1468141Y935805D01*
X1468014Y935863D01*
G03X1467471Y935983I-544J-1172D01*
G03X1466179Y934691I0J-1292D01*
G03X1466299Y934148I1292J1D01*
G01X1466357Y934021D01*
X1464890Y932554D01*
X1464876Y932545D01*
G03X1464563Y932232I744J-1057D01*
G01X1464554Y932218D01*
X1458642Y926306D01*
X1458532Y926333D01*
G03X1458222Y926371I-311J-1254D01*
G01X1458220D01*
G03X1456928Y925079I0J-1292D01*
G01Y925077D01*
G03X1456966Y924767I1292J1D01*
G01X1456993Y924657D01*
X1449091Y916755D01*
X1449005Y916758D01*
X1448970D01*
G03X1447678Y915466I0J-1292D01*
G01Y915431D01*
X1447681Y915345D01*
X1442398Y910062D01*
X1442263Y910148D01*
G03X1441571Y910349I-692J-1091D01*
G03X1440279Y909057I0J-1292D01*
G03X1440480Y908365I1292J0D01*
G01X1440566Y908230D01*
X1439455Y907119D01*
X1439401Y907105D01*
G03X1438468Y906172I319J-1252D01*
G01X1438454Y906118D01*
X1432928Y900592D01*
X1432806Y900642D01*
G03X1432320Y900737I-486J-1196D01*
G03X1431028Y899445I0J-1292D01*
G03X1431123Y898959I1291J0D01*
G01X1431173Y898837D01*
X1429607Y897271D01*
G03X1429391Y896950I706J-708D01*
G03X1429179Y896242I1080J-709D01*
G01Y896240D01*
G03X1429296Y895703I1291J0D01*
G01X1429314Y895663D01*
Y890409D01*
X1429296Y890369D01*
G03Y889295I1174J-537D01*
G01X1429314Y889255D01*
Y884012D01*
X1429295Y883972D01*
G03X1429174Y883423I1176J-547D01*
G03X1429295Y882874I1297J-2D01*
G01X1429314Y882834D01*
Y881433D01*
X1429080D01*
X1429048Y881444D01*
G03X1428861Y881494I-428J-1225D01*
G01X1428771Y881511D01*
X1427965Y882908D01*
X1427996Y882994D01*
G03X1428068Y883423I-1225J426D01*
G03X1425474I-1297J0D01*
G03X1426529Y882148I1298J0D01*
G01X1426619Y882131D01*
X1427426Y880733D01*
X1427396Y880646D01*
G03X1427324Y880221I1225J-426D01*
G01Y880219D01*
G03X1428621Y878922I1297J0D01*
G03X1428845Y878941I3J1297D01*
G02X1429314Y878547I69J-394D01*
G01Y877591D01*
X1429296Y877551D01*
G03Y876477I1174J-537D01*
G01X1429314Y876437D01*
Y871195D01*
X1429295Y871155D01*
G03X1429174Y870606I1176J-547D01*
G03X1429246Y870178I1297J-2D01*
G01X1429277Y870091D01*
X1428470Y868693D01*
X1428380Y868676D01*
G03X1427322Y867401I239J-1275D01*
G03X1428620Y866104I1297J0D01*
G03X1428845Y866123I4J1297D01*
G02X1429314Y865729I69J-394D01*
G01Y864774D01*
X1429296Y864734D01*
G03Y863660I1174J-537D01*
G01X1429314Y863620D01*
Y858378D01*
X1429295Y858338D01*
G03X1429174Y857789I1176J-547D01*
G03X1429246Y857361I1297J-2D01*
G01X1429277Y857274D01*
X1428470Y855876D01*
X1428380Y855859D01*
G03X1427322Y854584I239J-1275D01*
G03X1428620Y853286I1298J0D01*
G03X1428845Y853306I-2J1298D01*
G02X1429314Y852912I69J-394D01*
G01Y851959D01*
X1429296Y851919D01*
G03X1429178Y851380I1174J-539D01*
G03X1429296Y850841I1292J0D01*
G01X1429314Y850801D01*
Y792111D01*
G03X1429607Y791404I999J0D01*
G01X1566088Y654923D01*
G03X1566795Y654630I707J706D01*
G01X1612780D01*
X1614042Y653368D01*
Y622013D01*
X1612228Y620199D01*
X1469197D01*
X1401940Y687456D01*
Y740712D01*
G03X1401647Y741419I-999J0D01*
G01X1399127Y743939D01*
G03X1398420Y744232I-707J-706D01*
G01X1377194D01*
X1375542Y745884D01*
Y840015D01*
G02X1376149Y840357I400J0D01*
G03X1376819Y840170I671J1110D01*
G01X1376821D01*
G03X1378118Y841467I0J1297D01*
G03X1378007Y841994I-1297J2D01*
G01X1377968Y842082D01*
X1378809Y843677D01*
X1378904Y843695D01*
G03X1379966Y844971I-236J1276D01*
G03X1377372I-1297J0D01*
G03X1377483Y844444I1297J-2D01*
G01X1377522Y844356D01*
X1376681Y842761D01*
X1376586Y842743D01*
G03X1376149Y842577I235J-1276D01*
G02X1375542Y842919I-207J342D01*
G01Y843807D01*
G03Y846135I-574J1164D01*
G01Y850221D01*
G03Y852539I-571J1159D01*
G01Y853132D01*
G02X1376149Y853474I400J0D01*
G03X1376820Y853286I673J1110D01*
G03X1378118Y854584I0J1298D01*
G03X1377062Y855859I-1298J0D01*
G01X1376972Y855876D01*
X1376165Y857274D01*
X1376196Y857360D01*
G03X1376268Y857789I-1225J426D01*
G03X1375542Y858954I-1298J0D01*
G01Y862106D01*
X1379773Y866337D01*
X1379904Y866266D01*
G03X1380521Y866109I617J1134D01*
G03X1381813Y867401I0J1292D01*
G03X1381656Y868018I-1291J0D01*
G01X1381585Y868149D01*
X1382045Y868609D01*
G02X1382674Y868526I283J-283D01*
G01X1383026Y867916D01*
X1382995Y867830D01*
G03X1382922Y867401I1224J-429D01*
G03X1385518I1298J0D01*
G03X1384462Y868676I-1298J0D01*
G01X1384372Y868693D01*
X1383563Y870094D01*
G03X1383586Y870150I-1188J521D01*
G01X1386384Y872948D01*
G02X1386962Y872935I283J-283D01*
G03X1387678Y872535I958J875D01*
G01X1387768Y872518D01*
X1388576Y871119D01*
X1388545Y871032D01*
G03X1388474Y870606I1226J-423D01*
G03X1391068I1297J0D01*
G03X1390010Y871881I-1297J0D01*
G01X1389920Y871898D01*
X1389114Y873295D01*
X1389145Y873381D01*
G03X1389218Y873810I-1224J429D01*
G03X1387920Y875108I-1298J0D01*
G03X1387500Y875038I0J-1298D01*
G02X1386971Y875416I-129J378D01*
G01Y876087D01*
G03Y877941I-900J927D01*
G01Y882488D01*
G03X1387368Y883423I-900J934D01*
G03X1387296Y883851I-1297J2D01*
G01X1387265Y883938D01*
X1388072Y885335D01*
X1388162Y885352D01*
G03X1389218Y886627I-242J1275D01*
G03X1387920Y887924I-1297J0D01*
G03X1387500Y887855I-3J-1297D01*
G02X1386971Y888233I-129J378D01*
G01Y888905D01*
G03Y890759I-900J927D01*
G01Y895313D01*
G03X1387363Y896240I-900J927D01*
G03X1386071Y897532I-1292J0D01*
G03X1385928Y897524I1J-1292D01*
G01X1385833Y897513D01*
X1378010Y905336D01*
X1378048Y905452D01*
G03X1378112Y905853I-1228J402D01*
G03X1376820Y907145I-1292J0D01*
G03X1376419Y907081I1J-1292D01*
G01X1376303Y907043D01*
X1370630Y912716D01*
X1370615Y912753D01*
G03X1369911Y913457I-1195J-491D01*
G01X1369874Y913472D01*
X1368632Y914714D01*
X1368704Y914845D01*
G03X1368863Y915466I-1133J621D01*
G03X1367571Y916758I-1292J0D01*
G03X1366950Y916599I0J-1292D01*
G01X1366819Y916527D01*
X1361465Y921881D01*
X1361460Y921956D01*
G03X1360252Y923164I-1289J-81D01*
G01X1360177Y923169D01*
X1357978Y925368D01*
Y998966D01*
G03Y1000402I-1073J718D01*
G01Y1005375D01*
G03Y1006811I-1073J718D01*
G01Y1011783D01*
G03Y1013219I-1073J718D01*
G01Y1018192D01*
G03Y1019628I-1073J718D01*
G01Y1024603D01*
G03X1358194Y1025318I-1075J715D01*
G03X1358192Y1025390I-1292J0D01*
G01X1358187Y1025479D01*
X1359572Y1026864D01*
X1379400D01*
X1379952Y1026312D01*
X1379967Y1026280D01*
G03X1380599Y1025648I1173J541D01*
G01X1380631Y1025633D01*
X1381014Y1025250D01*
Y1023724D01*
X1380856Y1023690D01*
G03Y1021164I272J-1263D01*
G01X1381014Y1021130D01*
Y1008406D01*
X1380888Y1008355D01*
G03X1380077Y1007156I481J-1199D01*
G03X1380426Y1006273I1292J0D01*
G02X1380427Y1005728I-292J-273D01*
G03X1380081Y1004848I946J-880D01*
G03X1380889Y1003650I1292J0D01*
G01X1381014Y1003600D01*
Y996551D01*
X1380872Y996508D01*
G03X1379951Y995271I370J-1237D01*
G03X1380295Y994393I1292J0D01*
G02Y993849I-293J-272D01*
G03X1379951Y992971I948J-878D01*
G03X1380872Y991734I1291J0D01*
G01X1381014Y991691D01*
Y978364D01*
G03X1381307Y977657I999J0D01*
G01X1383207Y975757D01*
G03X1383914Y975464I707J706D01*
G01X1387100D01*
X1389014Y973550D01*
Y969678D01*
X1388300Y968964D01*
X1383914D01*
G03X1383207Y968671I0J-999D01*
G01X1381665Y967129D01*
X1381557Y967154D01*
G03X1381264Y967188I-294J-1258D01*
G03X1379972Y965896I0J-1292D01*
G03X1380316Y965018I1292J0D01*
G02Y964474I-293J-272D01*
G03X1379972Y963596I948J-878D01*
G03X1380701Y962433I1292J0D01*
G01X1380814Y962378D01*
Y949748D01*
X1380704Y949692D01*
G03X1379995Y948539I583J-1153D01*
G03X1380339Y947661I1292J0D01*
G02Y947117I-293J-272D01*
G03X1379995Y946239I948J-878D01*
G03X1380704Y945086I1292J0D01*
G01X1380814Y945030D01*
Y943299D01*
G03X1380138Y942163I617J-1136D01*
G03X1381430Y940871I1292J0D01*
G01X1381432D01*
G03X1381922Y940968I-1J1292D01*
G01X1382045Y941019D01*
X1386407Y936657D01*
G03X1387114Y936364I707J706D01*
G01X1402718D01*
X1402751Y936205D01*
G03X1405281I1265J264D01*
G01X1405314Y936364D01*
X1430214D01*
G03X1430921Y936657I0J999D01*
G01X1432921Y938657D01*
G03X1433214Y939364I-706J707D01*
G01Y944550D01*
X1440128Y951464D01*
X1450414D01*
G03X1451121Y951757I0J999D01*
G01X1453321Y953957D01*
G03X1453614Y954664I-706J707D01*
G01Y957964D01*
G03X1453321Y958671I-999J0D01*
G01X1452221Y959771D01*
G03X1451514Y960064I-707J-706D01*
G01X1449328D01*
X1444814Y964578D01*
Y971550D01*
X1452732Y979468D01*
X1452787Y979482D01*
G03X1453749Y980513I-311J1254D01*
G03X1453914Y981062I-835J550D01*
G01Y1023966D01*
G03X1453901Y1024126I-1000J-1D01*
G01X1453884Y1024227D01*
X1454768Y1025110D01*
G03X1454914Y1025462I-354J353D01*
G01Y1030257D01*
X1455400Y1030743D01*
G02X1455948Y1030760I283J-283D01*
G03X1456804Y1030435I857J967D01*
G37*
G36*
G01X1448007Y1065764D02*
X1449048D01*
G03X1449914Y1065264I866J500D01*
G01X1495600D01*
X1496403Y1064461D01*
X1496341Y1064333D01*
G03X1496212Y1063770I1164J-563D01*
G03X1497504Y1062478I1292J0D01*
G03X1498067Y1062607I0J1293D01*
G01X1498195Y1062669D01*
X1503615Y1057249D01*
X1503624Y1057182D01*
G03X1504725Y1056081I1280J179D01*
G01X1504792Y1056072D01*
X1505817Y1055047D01*
G03X1505461Y1054157I936J-891D01*
G03X1506753Y1052865I1292J0D01*
G03X1507643Y1053221I-1J1292D01*
G01X1524398Y1036466D01*
G02X1524385Y1035887I-282J-283D01*
G03X1523962Y1034931I869J-956D01*
G03X1524962Y1033672I1293J0D01*
G01X1525117Y1033636D01*
Y1017000D01*
X1524962Y1016964D01*
G03Y1014446I293J-1259D01*
G01X1525117Y1014410D01*
Y1001918D01*
X1524981Y1001872D01*
G03Y999424I416J-1224D01*
G01X1525117Y999378D01*
Y963492D01*
G03Y961380I743J-1056D01*
G01Y950883D01*
X1524984Y950835D01*
G03Y948403I436J-1216D01*
G01X1525117Y948355D01*
Y922181D01*
X1510082Y907146D01*
X1510001Y907145D01*
G03X1508729Y905873I20J-1292D01*
G01X1508728Y905792D01*
X1503413Y900477D01*
X1503280Y900556D01*
G03X1502621Y900737I-659J-1111D01*
G03X1501329Y899445I0J-1292D01*
G03X1501595Y898659I1292J-1D01*
G01X1500420Y897484D01*
X1500375Y897470D01*
G03X1499541Y896636I396J-1230D01*
G01X1499527Y896591D01*
X1497800Y894864D01*
X1484914D01*
G03X1484207Y894571I0J-999D01*
G01X1483955Y894319D01*
X1483893Y894308D01*
G03X1482848Y893263I227J-1272D01*
G01X1482837Y893201D01*
X1477907Y888271D01*
G03X1477722Y888016I706J-707D01*
G02X1477213Y887827I-357J181D01*
G03X1476720Y887924I-492J-1200D01*
G03X1475422Y886627I0J-1298D01*
G03X1475495Y886199I1298J1D01*
G01X1475526Y886112D01*
X1474719Y884715D01*
X1474629Y884698D01*
G03X1473574Y883423I243J-1275D01*
G03X1476168I1297J0D01*
G03X1476096Y883851I-1297J2D01*
G01X1476065Y883938D01*
X1476872Y885335D01*
X1476962Y885352D01*
G03X1477098Y885386I-246J1274D01*
G02X1477614Y885003I116J-383D01*
G01Y884299D01*
G03X1477274Y883423I957J-875D01*
G03X1477614Y882547I1297J-1D01*
G01Y877882D01*
G03Y876146I957J-868D01*
G01Y875434D01*
G02X1477098Y875051I-400J0D01*
G03X1476720Y875108I-380J-1241D01*
G03X1475422Y873810I0J-1298D01*
G03X1476478Y872535I1298J0D01*
G01X1476568Y872518D01*
X1477376Y871119D01*
X1477345Y871032D01*
G03X1477274Y870606I1226J-423D01*
G03X1477614Y869730I1297J-1D01*
G01Y865065D01*
G03Y863329I957J-868D01*
G01Y862617D01*
G02X1477098Y862234I-400J0D01*
G03X1476720Y862290I-377J-1241D01*
G03X1475422Y860993I0J-1298D01*
G03X1476478Y859718I1298J0D01*
G01X1476568Y859701D01*
X1477376Y858302D01*
X1477345Y858215D01*
G03X1477274Y857789I1226J-423D01*
G03X1477614Y856913I1297J-1D01*
G01Y852248D01*
G03Y850512I957J-868D01*
G01Y847564D01*
G03X1477907Y846857I999J0D01*
G01X1479807Y844957D01*
G03X1480514Y844664I707J706D01*
G01X1503167D01*
X1503191Y844492D01*
G03X1505751I1280J180D01*
G01X1505775Y844664D01*
X1510567D01*
X1510591Y844492D01*
G03X1513151I1280J180D01*
G01X1513175Y844664D01*
X1611824D01*
X1614042Y842446D01*
Y757503D01*
G03Y754895I747J-1304D01*
G01Y661765D01*
X1614041Y661752D01*
G03X1614033Y661630I992J-126D01*
G03X1614041Y661508I1000J4D01*
G01X1614042Y661495D01*
Y657925D01*
X1612747Y656630D01*
X1567209D01*
X1431314Y792525D01*
Y850402D01*
G03Y852358I-844J978D01*
G01Y856803D01*
G03Y858775I-844J986D01*
G01Y859407D01*
G02X1431857Y859781I400J0D01*
G03X1432078Y859718I465J1211D01*
G01X1432168Y859701D01*
X1432976Y858302D01*
X1432945Y858215D01*
G03X1432874Y857789I1226J-423D01*
G03X1435468I1297J0D01*
G03X1434410Y859064I-1297J0D01*
G01X1434320Y859081D01*
X1433514Y860478D01*
X1433545Y860564D01*
G03X1433618Y860993I-1224J429D01*
G03X1432320Y862290I-1297J0D01*
G03X1431857Y862205I-1J-1297D01*
G02X1431314Y862579I-143J374D01*
G01Y863218D01*
G03Y865176I-843J979D01*
G01Y869620D01*
G03Y871592I-844J986D01*
G01Y872224D01*
G02X1431857Y872598I400J0D01*
G03X1432078Y872535I465J1211D01*
G01X1432168Y872518D01*
X1432976Y871119D01*
X1432945Y871032D01*
G03X1432874Y870606I1226J-423D01*
G03X1435468I1297J0D01*
G03X1434410Y871881I-1297J0D01*
G01X1434320Y871898D01*
X1433514Y873295D01*
X1433545Y873381D01*
G03X1433618Y873810I-1224J429D01*
G03X1432320Y875108I-1298J0D01*
G03X1431857Y875022I2J-1298D01*
G02X1431314Y875396I-143J374D01*
G01Y876035D01*
G03Y877993I-843J979D01*
G01Y882437D01*
G03X1431768Y883423I-844J986D01*
G03X1431696Y883851I-1297J2D01*
G01X1431665Y883938D01*
X1432472Y885335D01*
X1432562Y885352D01*
G03X1433618Y886627I-242J1275D01*
G03X1432320Y887924I-1297J0D01*
G03X1431857Y887839I-1J-1297D01*
G02X1431314Y888213I-143J374D01*
G01Y888853D01*
G03Y890811I-843J979D01*
G01Y895261D01*
G03X1431763Y896240I-843J979D01*
G03X1431744Y896460I-1292J-1D01*
G01X1431726Y896562D01*
X1439723Y904559D01*
X1439798Y904563D01*
G03X1441010Y905775I-78J1290D01*
G01X1441014Y905850D01*
X1446367Y911203D01*
X1446499Y911130D01*
G03X1447122Y910970I623J1133D01*
G03X1448414Y912262I0J1292D01*
G03X1448254Y912885I-1293J0D01*
G01X1448181Y913017D01*
X1449417Y914253D01*
X1449455Y914268D01*
G03X1450168Y914981I-485J1198D01*
G01X1450183Y915019D01*
X1455850Y920686D01*
X1455967Y920648D01*
G03X1456371Y920583I405J1227D01*
G03X1457663Y921875I0J1292D01*
G03X1457598Y922279I-1292J-1D01*
G01X1457560Y922396D01*
X1465379Y930215D01*
X1465475Y930204D01*
G03X1465620Y930196I144J1284D01*
G03X1466912Y931488I0J1292D01*
G03X1466904Y931633I-1292J1D01*
G01X1466893Y931729D01*
X1472119Y936955D01*
X1472257Y936854D01*
G03X1473021Y936604I764J1042D01*
G03X1474313Y937896I0J1292D01*
G03X1473954Y938790I-1293J0D01*
G01X1474974Y939810D01*
X1475041Y939819D01*
G03X1476152Y940930I-170J1281D01*
G01X1476161Y940997D01*
X1477805Y942641D01*
G03X1478098Y943348I-706J707D01*
G01Y1002007D01*
G03Y1003769I-945J881D01*
G01Y1008416D01*
G03Y1010178I-945J881D01*
G01Y1014823D01*
G03Y1016587I-944J882D01*
G01Y1021233D01*
G03Y1022995I-945J881D01*
G01Y1027642D01*
G03X1478445Y1028523I-945J881D01*
G03X1477153Y1029815I-1292J0D01*
G03X1476602Y1029692I-1J-1292D01*
G01X1476475Y1029631D01*
X1473735Y1032371D01*
G03X1473028Y1032664I-707J-706D01*
G01X1472493D01*
G03X1470713I-890J-938D01*
G01X1468794D01*
G03X1467014I-890J-938D01*
G01X1465094D01*
G03X1463314I-890J-938D01*
G01X1461393D01*
G03X1459613I-890J-938D01*
G01X1457694D01*
G03X1456804Y1033019I-890J-938D01*
G03X1455588Y1032163I0J-1292D01*
G03X1455260Y1032018I25J-500D01*
G01X1454908Y1031666D01*
X1454906D01*
X1453912Y1030672D01*
Y1029851D01*
G03Y1027195I1042J-1328D01*
G01Y1025671D01*
X1453566Y1025325D01*
X1452967D01*
X1451921Y1026371D01*
G03X1451214Y1026664I-707J-706D01*
G01X1444386D01*
X1443814Y1027236D01*
Y1035643D01*
X1443951Y1035689D01*
G03Y1038139I-410J1225D01*
G01X1443814Y1038185D01*
Y1063057D01*
X1446521Y1065764D01*
X1447099D01*
X1447131Y1065753D01*
G03X1447553Y1065682I422J1221D01*
G03X1447975Y1065753I0J1292D01*
G01X1448007Y1065764D01*
G37*
G36*
G01X1607838Y1383825D02*
X1689953D01*
X1690360Y1383418D01*
G03X1690010Y1382492I1052J-927D01*
G03X1690402Y1381519I1402J-1D01*
G02Y1380965I-288J-277D01*
G03X1690010Y1379992I1010J-972D01*
G03X1690402Y1379019I1402J-1D01*
G02Y1378465I-288J-277D01*
G03X1690010Y1377492I1010J-972D01*
G03X1690402Y1376519I1402J-1D01*
G02Y1375965I-288J-277D01*
G03X1690010Y1374992I1010J-972D01*
G03X1690402Y1374019I1402J-1D01*
G02Y1373465I-288J-277D01*
G03X1690010Y1372492I1010J-972D01*
G03X1690402Y1371519I1402J-1D01*
G02Y1370965I-288J-277D01*
G03X1690010Y1369992I1010J-972D01*
G03X1690402Y1369019I1402J-1D01*
G02Y1368465I-288J-277D01*
G03X1690010Y1367492I1010J-972D01*
G03X1691058Y1366136I1401J0D01*
G01X1691207Y1366096D01*
Y1298471D01*
X1688707Y1295971D01*
G03X1688414Y1295264I706J-707D01*
G01Y1274513D01*
G03Y1272175I774J-1169D01*
G01Y848521D01*
X1686557Y846664D01*
X1480928D01*
X1479614Y847978D01*
Y850617D01*
G03X1479863Y851380I-1043J763D01*
G03X1479614Y852143I-1292J0D01*
G01Y852936D01*
G02X1480110Y853324I400J0D01*
G03X1480420Y853286I312J1260D01*
G03X1481718Y854584I0J1298D01*
G03X1481645Y855011I-1298J-2D01*
G01X1481615Y855098D01*
X1482423Y856497D01*
X1482513Y856514D01*
G03X1483568Y857789I-243J1275D01*
G03X1480974I-1297J0D01*
G03X1481046Y857361I1297J-2D01*
G01X1481077Y857274D01*
X1480270Y855876D01*
X1480180Y855859D01*
G03X1480110Y855844I237J-1276D01*
G02X1479614Y856232I-96J388D01*
G01Y857017D01*
G03X1479868Y857789I-1043J771D01*
G03X1479614Y858561I-1297J1D01*
G01Y863434D01*
G03X1479863Y864197I-1043J763D01*
G03X1479614Y864960I-1292J0D01*
G01Y865753D01*
G02X1480110Y866141I400J0D01*
G03X1480420Y866104I308J1260D01*
G03X1481718Y867401I0J1298D01*
G03X1481645Y867828I-1298J-2D01*
G01X1481615Y867915D01*
X1482423Y869314D01*
X1482513Y869331D01*
G03X1483568Y870606I-243J1275D01*
G03X1480974I-1297J0D01*
G03X1481046Y870178I1297J-2D01*
G01X1481077Y870091D01*
X1480270Y868693D01*
X1480180Y868676D01*
G03X1480110Y868661I237J-1276D01*
G02X1479614Y869049I-96J388D01*
G01Y869834D01*
G03X1479868Y870606I-1043J771D01*
G03X1479614Y871378I-1297J1D01*
G01Y876251D01*
G03X1479863Y877014I-1043J763D01*
G03X1479614Y877777I-1292J0D01*
G01Y878571D01*
G02X1480110Y878959I400J0D01*
G03X1480420Y878922I308J1260D01*
G03X1481718Y880219I0J1298D01*
G03X1480661Y881494I-1297J0D01*
G01X1480571Y881511D01*
X1479765Y882908D01*
X1479796Y882994D01*
G03X1479868Y883423I-1225J426D01*
G03X1479614Y884195I-1297J1D01*
G01Y887150D01*
X1481362Y888898D01*
X1481500Y888795D01*
G03X1482271Y888540I771J1038D01*
G03X1483563Y889832I0J1292D01*
G03X1483308Y890603I-1293J0D01*
G01X1483205Y890741D01*
X1484209Y891745D01*
X1484278Y891754D01*
G03X1485371Y892714I-158J1282D01*
G01X1485410Y892864D01*
X1486530D01*
X1486569Y892714D01*
G03X1489071I1251J322D01*
G01X1489110Y892864D01*
X1490231D01*
X1490270Y892714D01*
G03X1492772I1251J322D01*
G01X1492811Y892864D01*
X1493930D01*
X1493969Y892714D01*
G03X1496471I1251J322D01*
G01X1496510Y892864D01*
X1498214D01*
G03X1498921Y893157I0J999D01*
G01X1500711Y894947D01*
X1500792Y894948D01*
G03X1502063Y896219I-21J1292D01*
G01X1502064Y896300D01*
X1507380Y901616D01*
X1507513Y901537D01*
G03X1508171Y901357I658J1113D01*
G03X1509463Y902649I0J1292D01*
G03X1509283Y903307I-1293J0D01*
G01X1509204Y903440D01*
X1510373Y904609D01*
X1510419Y904624D01*
G03X1511250Y905455I-398J1229D01*
G01X1511265Y905501D01*
X1526824Y921060D01*
G03X1527117Y921767I-706J707D01*
G01Y962132D01*
X1527122Y962154D01*
G03X1527153Y962436I-1261J281D01*
G03X1527122Y962718I-1292J1D01*
G01X1527117Y962740D01*
Y971337D01*
X1527253Y971383D01*
G03Y973833I-410J1225D01*
G01X1527117Y973879D01*
Y1030423D01*
X1527288Y1030447D01*
G03Y1033005I-185J1279D01*
G01X1527117Y1033029D01*
Y1036161D01*
G03X1526824Y1036868I-999J0D01*
G01X1513414Y1050278D01*
X1513473Y1050405D01*
G03X1513595Y1050952I-1170J548D01*
G03X1512303Y1052244I-1292J0D01*
G03X1511756Y1052122I1J-1292D01*
G01X1511629Y1052063D01*
X1506190Y1057502D01*
X1506180Y1057566D01*
G03X1505109Y1058637I-1276J-205D01*
G01X1505045Y1058647D01*
X1504003Y1059689D01*
G03X1504345Y1060565I-951J876D01*
G03X1503053Y1061857I-1292J0D01*
G03X1502177Y1061515I0J-1293D01*
G01X1496931Y1066761D01*
X1496939Y1066855D01*
G03X1496945Y1066974I-1286J124D01*
G03X1495653Y1068266I-1292J0D01*
G03X1494433Y1067398I0J-1291D01*
G01X1494386Y1067264D01*
X1493220D01*
X1493173Y1067398D01*
G03X1490733I-1220J-423D01*
G01X1490686Y1067264D01*
X1489520D01*
X1489473Y1067398D01*
G03X1487033I-1220J-423D01*
G01X1486986Y1067264D01*
X1485820D01*
X1485773Y1067398D01*
G03X1483333I-1220J-423D01*
G01X1483286Y1067264D01*
X1482120D01*
X1482073Y1067398D01*
G03X1479633I-1220J-423D01*
G01X1479586Y1067264D01*
X1478420D01*
X1478373Y1067398D01*
G03X1475933I-1220J-423D01*
G01X1475886Y1067264D01*
X1474720D01*
X1474673Y1067398D01*
G03X1472233I-1220J-423D01*
G01X1472186Y1067264D01*
X1471020D01*
X1470973Y1067398D01*
G03X1468533I-1220J-423D01*
G01X1468486Y1067264D01*
X1467320D01*
X1467273Y1067398D01*
G03X1464833I-1220J-423D01*
G01X1464786Y1067264D01*
X1463620D01*
X1463573Y1067398D01*
G03X1461133I-1220J-423D01*
G01X1461086Y1067264D01*
X1459921D01*
X1459874Y1067398D01*
G03X1457434I-1220J-423D01*
G01X1457387Y1067264D01*
X1456220D01*
X1456173Y1067398D01*
G03X1453733I-1220J-423D01*
G01X1453686Y1067264D01*
X1452520D01*
X1452473Y1067398D01*
G03X1451253Y1068266I-1220J-423D01*
G03X1449993Y1067261I0J-1292D01*
G03X1449049Y1066766I-79J-997D01*
G01X1446106D01*
X1442812Y1063472D01*
Y1061892D01*
G03Y1059238I1043J-1327D01*
G01Y1055484D01*
G03Y1052830I1043J-1327D01*
G01Y1048516D01*
G03X1442561Y1047750I1041J-765D01*
G03X1442812Y1046984I1292J-1D01*
G01Y1042106D01*
G03X1442561Y1041340I1041J-765D01*
G03X1442812Y1040574I1292J-1D01*
G01Y1037981D01*
G03Y1035847I730J-1067D01*
G01Y1027170D01*
X1442307Y1026664D01*
X1435928D01*
X1433914Y1028678D01*
Y1040772D01*
X1433932Y1040811D01*
G03X1434045Y1041340I-1179J528D01*
G03X1433932Y1041869I-1292J1D01*
G01X1433914Y1041908D01*
Y1047181D01*
X1433932Y1047220D01*
G03X1434045Y1047749I-1179J528D01*
G03X1433932Y1048278I-1292J1D01*
G01X1433914Y1048317D01*
Y1053589D01*
X1433932Y1053628D01*
G03X1434045Y1054157I-1179J528D01*
G03X1433932Y1054686I-1292J1D01*
G01X1433914Y1054725D01*
Y1059997D01*
X1433932Y1060036D01*
G03X1434045Y1060565I-1179J528D01*
G03X1433932Y1061094I-1292J1D01*
G01X1433914Y1061133D01*
Y1066406D01*
X1433932Y1066445D01*
G03X1434045Y1066974I-1179J528D01*
G03X1433932Y1067503I-1292J1D01*
G01X1433914Y1067542D01*
Y1072815D01*
X1433932Y1072854D01*
G03X1434045Y1073383I-1179J528D01*
G03X1433932Y1073912I-1292J1D01*
G01X1433914Y1073951D01*
Y1079220D01*
X1433932Y1079260D01*
G03X1434046Y1079791I-1178J531D01*
G03X1433932Y1080322I-1292J0D01*
G01X1433914Y1080362D01*
Y1085632D01*
X1433932Y1085671D01*
G03X1434045Y1086200I-1179J528D01*
G03X1433932Y1086729I-1292J1D01*
G01X1433914Y1086768D01*
Y1092036D01*
X1433932Y1092076D01*
G03X1434046Y1092607I-1178J531D01*
G03X1433932Y1093138I-1292J0D01*
G01X1433914Y1093178D01*
Y1098449D01*
X1433932Y1098488D01*
G03X1433975Y1098597I-1179J528D01*
G01X1433981Y1098615D01*
X1435535Y1101325D01*
X1435551Y1101342D01*
G03X1435841Y1101848I-947J879D01*
G01X1435848Y1101870D01*
X1437356Y1104501D01*
X1437374Y1104519D01*
G03X1437701Y1105090I-921J906D01*
G01X1437708Y1105115D01*
X1439178Y1107678D01*
X1439199Y1107698D01*
G03X1439560Y1108328I-895J931D01*
G01X1439567Y1108356D01*
X1441002Y1110859D01*
X1441025Y1110880D01*
G03X1441418Y1111564I-870J955D01*
G01X1441424Y1111595D01*
X1442828Y1114043D01*
X1442854Y1114066D01*
G03X1443273Y1114797I-850J973D01*
G01X1443280Y1114830D01*
X1444655Y1117230D01*
X1444683Y1117253D01*
G03X1445127Y1118027I-830J990D01*
G01X1445133Y1118062D01*
X1446475Y1120402D01*
X1446505Y1120426D01*
G03X1446990Y1121271I-801J1021D01*
G01X1446995Y1121310D01*
X1448303Y1123592D01*
X1448336Y1123616D01*
G03X1448841Y1124498I-784J1034D01*
G01X1448846Y1124538D01*
X1449285Y1125304D01*
G02X1449979Y1125305I347J-199D01*
G01X1450059Y1125166D01*
X1450028Y1125080D01*
G03X1449956Y1124651I1225J-426D01*
G03X1452550I1297J0D01*
G03X1451495Y1125926I-1298J0D01*
G01X1451405Y1125943D01*
X1450598Y1127341D01*
X1450629Y1127427D01*
G03X1450695Y1127727I-1225J427D01*
G01X1450699Y1127770D01*
X1451969Y1129983D01*
X1452004Y1130009D01*
G03X1452540Y1130943I-751J1052D01*
G01X1452544Y1130986D01*
X1453792Y1133163D01*
X1453830Y1133189D01*
G03X1454399Y1134180I-726J1076D01*
G01X1454402Y1134227D01*
X1455623Y1136356D01*
X1455663Y1136382D01*
G03X1456144Y1136953I-710J1086D01*
G01X1456197Y1137073D01*
X1457411D01*
X1457464Y1136953D01*
G03X1459844I1190J516D01*
G01X1459897Y1137073D01*
X1460536D01*
G02X1460882Y1136473I0J-400D01*
G01X1460353Y1135556D01*
X1460263Y1135539D01*
G03X1459206Y1134264I240J-1275D01*
G03X1461802I1298J0D01*
G03X1461729Y1134692I-1298J-1D01*
G01X1461699Y1134779D01*
X1462506Y1136177D01*
X1462596Y1136194D01*
G03X1463544Y1136953I-243J1275D01*
G01X1463597Y1137073D01*
X1464811D01*
X1464864Y1136953D01*
G03X1467244I1190J516D01*
G01X1467297Y1137073D01*
X1467936D01*
G02X1468282Y1136473I0J-400D01*
G01X1467753Y1135556D01*
X1467663Y1135539D01*
G03X1466606Y1134264I240J-1275D01*
G03X1469202I1298J0D01*
G03X1469129Y1134692I-1298J-1D01*
G01X1469099Y1134779D01*
X1469906Y1136177D01*
X1469996Y1136194D01*
G03X1470944Y1136953I-243J1275D01*
G01X1470997Y1137073D01*
X1472211D01*
X1472264Y1136953D01*
G03X1474644I1190J516D01*
G01X1474697Y1137073D01*
X1475336D01*
G02X1475682Y1136473I0J-400D01*
G01X1475153Y1135556D01*
X1475063Y1135539D01*
G03X1474006Y1134264I240J-1275D01*
G03X1476602I1298J0D01*
G03X1476529Y1134692I-1298J-1D01*
G01X1476499Y1134779D01*
X1477306Y1136177D01*
X1477396Y1136194D01*
G03X1478344Y1136953I-243J1275D01*
G01X1478397Y1137073D01*
X1479611D01*
X1479664Y1136953D01*
G03X1482044I1190J516D01*
G01X1482097Y1137073D01*
X1482736D01*
G02X1483082Y1136473I0J-400D01*
G01X1482553Y1135556D01*
X1482463Y1135539D01*
G03X1481406Y1134264I240J-1275D01*
G03X1484002I1298J0D01*
G03X1483929Y1134692I-1298J-1D01*
G01X1483899Y1134779D01*
X1484706Y1136177D01*
X1484796Y1136194D01*
G03X1485744Y1136953I-243J1275D01*
G01X1485797Y1137073D01*
X1487011D01*
X1487064Y1136953D01*
G03X1489444I1190J516D01*
G01X1489497Y1137073D01*
X1490136D01*
G02X1490482Y1136473I0J-400D01*
G01X1489953Y1135556D01*
X1489863Y1135539D01*
G03X1488806Y1134264I240J-1275D01*
G03X1491402I1298J0D01*
G03X1491329Y1134692I-1298J-1D01*
G01X1491299Y1134779D01*
X1492106Y1136177D01*
X1492196Y1136194D01*
G03X1493144Y1136953I-243J1275D01*
G01X1493197Y1137073D01*
X1494411D01*
X1494464Y1136953D01*
G03X1496844I1190J516D01*
G01X1496897Y1137073D01*
X1497536D01*
G02X1497882Y1136473I0J-400D01*
G01X1497353Y1135556D01*
X1497263Y1135539D01*
G03X1496206Y1134264I240J-1275D01*
G03X1498802I1298J0D01*
G03X1498729Y1134692I-1298J-1D01*
G01X1498699Y1134779D01*
X1499506Y1136177D01*
X1499596Y1136194D01*
G03X1500544Y1136953I-243J1275D01*
G01X1500597Y1137073D01*
X1501811D01*
X1501864Y1136953D01*
G03X1504244I1190J516D01*
G01X1504297Y1137073D01*
X1505517D01*
X1505570Y1136953D01*
G03X1507938I1184J515D01*
G01X1507991Y1137073D01*
X1508635D01*
G02X1508982Y1136473I1J-400D01*
G01X1508452Y1135556D01*
X1508362Y1135539D01*
G03X1507306Y1134264I242J-1275D01*
G03X1509902I1298J0D01*
G03X1509829Y1134692I-1298J-1D01*
G01X1509798Y1134779D01*
X1510606Y1136177D01*
X1510696Y1136194D01*
G03X1511644Y1136953I-243J1275D01*
G01X1511697Y1137073D01*
X1518575D01*
G03X1519282Y1137366I0J999D01*
G01X1547414Y1165498D01*
G03X1547707Y1166205I-706J707D01*
G01Y1298441D01*
X1549081Y1299815D01*
X1559647D01*
G03X1560354Y1300108I0J999D01*
G01X1561985Y1301739D01*
G03X1562278Y1302446I-706J707D01*
G01Y1338265D01*
X1607838Y1383825D01*
G37*
G36*
G01X1740860Y1230665D02*
X1742033D01*
X1744457Y1228241D01*
Y1225984D01*
G03Y1224542I1083J-721D01*
G01Y1219291D01*
G03Y1217849I1083J-721D01*
G01Y1212598D01*
G03Y1211156I1083J-721D01*
G01Y1205905D01*
G03Y1204463I1083J-721D01*
G01Y1199212D01*
G03Y1197770I1083J-721D01*
G01Y1189173D01*
G03Y1187731I1083J-721D01*
G01Y1182480D01*
G03Y1181038I1083J-721D01*
G01Y1175787D01*
G03Y1174345I1083J-721D01*
G01Y1169094D01*
G03Y1167652I1083J-721D01*
G01Y1162401D01*
G03Y1160959I1083J-721D01*
G01Y1152362D01*
G03Y1150920I1083J-721D01*
G01Y1145669D01*
G03Y1144227I1083J-721D01*
G01Y1138976D01*
G03Y1137534I1083J-721D01*
G01Y1132283D01*
G03Y1130841I1083J-721D01*
G01Y1125590D01*
G03Y1124148I1083J-721D01*
G01Y1115550D01*
G03Y1114108I1083J-721D01*
G01Y1108858D01*
G03Y1107416I1083J-721D01*
G01Y1102165D01*
G03Y1100723I1083J-721D01*
G01Y1095472D01*
G03Y1094030I1083J-721D01*
G01Y1088779D01*
G03Y1087337I1083J-721D01*
G01Y1078739D01*
G03Y1077297I1083J-721D01*
G01Y1072047D01*
G03Y1070605I1083J-721D01*
G01Y1065354D01*
G03Y1063912I1083J-721D01*
G01Y1058661D01*
G03Y1057219I1083J-721D01*
G01Y1055296D01*
G03Y1053890I1084J-703D01*
G01Y1051968D01*
G03Y1050526I1083J-721D01*
G01Y1045275D01*
G03Y1043833I1083J-721D01*
G01Y1038582D01*
G03Y1037140I1083J-721D01*
G01Y1031889D01*
G03Y1030447I1083J-721D01*
G01Y1025196D01*
G03Y1023754I1083J-721D01*
G01Y1018503D01*
G03Y1017061I1083J-721D01*
G01Y991732D01*
G03Y990290I1083J-721D01*
G01Y985039D01*
G03Y983597I1083J-721D01*
G01Y978346D01*
G03Y976904I1083J-721D01*
G01Y971653D01*
G03Y970211I1083J-721D01*
G01Y968288D01*
G03Y966882I1084J-703D01*
G01Y964960D01*
G03Y963518I1083J-721D01*
G01Y961595D01*
G03Y960189I1084J-703D01*
G01Y958249D01*
G03Y956843I1084J-703D01*
G01Y954921D01*
G03Y953479I1083J-721D01*
G01Y948228D01*
G03Y946786I1083J-721D01*
G01Y941535D01*
G03Y940093I1083J-721D01*
G01Y931495D01*
G03Y930053I1083J-721D01*
G01Y924802D01*
G03Y923360I1083J-721D01*
G01Y918110D01*
G03Y916668I1083J-721D01*
G01Y911417D01*
G03Y909975I1083J-721D01*
G01Y904724D01*
G03Y903282I1083J-721D01*
G01Y894684D01*
G03Y893242I1083J-721D01*
G01Y887991D01*
G03Y886549I1083J-721D01*
G01Y881298D01*
G03Y879856I1083J-721D01*
G01Y874606D01*
G03Y873164I1083J-721D01*
G01Y867913D01*
G03Y866471I1083J-721D01*
G01Y857873D01*
G03Y856431I1083J-721D01*
G01Y851180D01*
G03Y849738I1083J-721D01*
G01Y844487D01*
G03Y843045I1083J-721D01*
G01Y837795D01*
G03Y836353I1083J-721D01*
G01Y831102D01*
G03Y829660I1083J-721D01*
G01Y821062D01*
G03Y819620I1083J-721D01*
G01Y814369D01*
G03Y812927I1083J-721D01*
G01Y807676D01*
G03Y806234I1083J-721D01*
G01Y800984D01*
G03Y799542I1083J-721D01*
G01Y794291D01*
G03Y792849I1083J-721D01*
G01Y784251D01*
G03Y782809I1083J-721D01*
G01Y777558D01*
G03Y776116I1083J-721D01*
G01Y770865D01*
G03Y769423I1083J-721D01*
G01Y767687D01*
G03Y765909I1084J-889D01*
G01Y671819D01*
X1742503Y669865D01*
X1686202D01*
X1686162Y670012D01*
G03X1679602I-3280J-903D01*
G01X1679562Y669865D01*
X1659408D01*
G03X1658701Y669572I0J-999D01*
G01X1656995Y667866D01*
G03X1656702Y667159I706J-707D01*
G01Y639742D01*
X1656700Y639726D01*
G03X1656683Y639511I1385J-218D01*
G03X1656700Y639296I1402J3D01*
G01X1656702Y639280D01*
Y621971D01*
X1656592Y621915D01*
G03Y619409I627J-1253D01*
G01X1656702Y619353D01*
Y612578D01*
X1656555Y612538D01*
G03Y609642I400J-1448D01*
G01X1656702Y609602D01*
Y594014D01*
G02X1656289Y593614I-400J0D01*
G03X1656238Y593615I-55J-1501D01*
G03X1654736Y592113I0J-1502D01*
G03X1654945Y591349I1501J0D01*
G01X1655024Y591216D01*
X1648907Y585099D01*
X1617942D01*
G03X1617849Y585206I-799J-601D01*
G01X1616042Y587013D01*
Y648762D01*
X1616159Y648815D01*
G03Y651369I-579J1277D01*
G01X1616042Y651422D01*
Y656432D01*
X1616159Y656485D01*
G03X1616982Y657762I-579J1277D01*
G03X1616551Y658773I-1401J0D01*
G02Y659351I277J289D01*
G03X1616982Y660362I-970J1011D01*
G03X1616159Y661639I-1402J0D01*
G01X1616042Y661692D01*
Y682762D01*
X1616159Y682815D01*
G03Y685369I-579J1277D01*
G01X1616042Y685422D01*
Y690432D01*
X1616159Y690485D01*
G03X1616982Y691762I-579J1277D01*
G03X1616551Y692773I-1401J0D01*
G02Y693351I277J289D01*
G03X1616982Y694362I-970J1011D01*
G03X1616159Y695639I-1402J0D01*
G01X1616042Y695692D01*
Y716762D01*
X1616159Y716815D01*
G03Y719369I-579J1277D01*
G01X1616042Y719422D01*
Y755372D01*
G03Y757026I-1255J827D01*
G01Y842496D01*
X1618210Y844664D01*
X1686971D01*
G03X1687678Y844957I0J999D01*
G01X1690121Y847400D01*
G03X1690414Y848107I-706J707D01*
G01Y1229239D01*
X1690505Y1229299D01*
G03X1690668Y1229431I-544J839D01*
G01X1691902Y1230665D01*
X1702106D01*
X1702119Y1230663D01*
G03X1702283Y1230653I161J1292D01*
G03X1702447Y1230663I3J1302D01*
G01X1702460Y1230665D01*
X1710806D01*
X1710819Y1230663D01*
G03X1710983Y1230653I161J1292D01*
G03X1711147Y1230663I3J1302D01*
G01X1711160Y1230665D01*
X1715774D01*
G03X1715841Y1230663I72J1290D01*
G03X1715908Y1230665I-5J1292D01*
G01X1731806D01*
X1731819Y1230663D01*
G03X1731983Y1230653I161J1292D01*
G03X1732147Y1230663I3J1302D01*
G01X1732160Y1230665D01*
X1740506D01*
X1740519Y1230663D01*
G03X1740683Y1230653I161J1292D01*
G03X1740847Y1230663I3J1302D01*
G01X1740860Y1230665D01*
G37*
%LPD*%
G75*
G36*
G01X447117Y1378173D02*
X455023Y1386079D01*
G02X455730Y1386372I707J-706D01*
G01X472770D01*
G02X473477Y1386079I0J-999D01*
G01X479876Y1379680D01*
X550024D01*
G02X550731Y1379387I0J-999D01*
G01X564488Y1365630D01*
G02X564781Y1364923I-706J-707D01*
G01Y1350314D01*
G02X564488Y1349607I-999J0D01*
G01X563295Y1348414D01*
G02X562588Y1348121I-707J706D01*
G01X552415D01*
X552360Y1348009D01*
G02X549722I-1319J642D01*
G01X549667Y1348121D01*
X543973D01*
X543918Y1348008D01*
G02X542597Y1347179I-1321J638D01*
G02X541576Y1347593I0J1466D01*
G03X541018I-279J-287D01*
G02X539997Y1347179I-1021J1052D01*
G02X538676Y1348008I0J1467D01*
G01X538621Y1348121D01*
X537425D01*
X535750Y1346446D01*
G02X536064Y1345539I-1153J-907D01*
G02X535297Y1344250I-1467J0D01*
G01Y1343721D01*
G02Y1341143I-700J-1289D01*
G01Y1322504D01*
G02X535004Y1321797I-999J0D01*
G01X529627Y1316420D01*
G02X528920Y1316127I-707J706D01*
G01X503719D01*
X502027Y1314435D01*
Y1305702D01*
G02X501734Y1304995I-999J0D01*
G01X499899Y1303160D01*
G02X499192Y1302867I-707J706D01*
G01X493526D01*
G02X492155Y1301978I-1371J613D01*
G02X491128Y1302384I0J1502D01*
G03X490582I-273J-292D01*
G02X489555Y1301978I-1027J1096D01*
G02X488184Y1302867I0J1502D01*
G01X461936D01*
G02X459918I-1009J1114D01*
G01X459336D01*
G02X457318I-1009J1114D01*
G01X433634D01*
X433582Y1302744D01*
G02X430808I-1387J574D01*
G01X430756Y1302867D01*
X429270D01*
G02X427899Y1301978I-1371J613D01*
G02X426872Y1302384I0J1502D01*
G03X426326I-273J-292D01*
G02X425299Y1301978I-1027J1096D01*
G02X423928Y1302867I0J1502D01*
G01X401506D01*
X401454Y1302744D01*
G02X398680I-1387J574D01*
G01X398628Y1302867D01*
X397142D01*
G02X395771Y1301978I-1371J613D01*
G02X394744Y1302384I0J1502D01*
G03X394198I-273J-292D01*
G02X393171Y1301978I-1027J1096D01*
G02X391800Y1302867I0J1502D01*
G01X369378D01*
X369326Y1302744D01*
G02X367939Y1301817I-1387J574D01*
G02X366460Y1303058I0J1502D01*
G01X366449Y1303120D01*
X364379Y1305190D01*
X364254Y1305134D01*
G02X363643Y1305004I-611J1371D01*
G02X362141Y1306506I0J1502D01*
G02X362271Y1307117I1501J0D01*
G01X362327Y1307242D01*
X361779Y1307790D01*
X361654Y1307734D01*
G02X361043Y1307604I-611J1371D01*
G02X359541Y1309106I0J1502D01*
G02X359671Y1309717I1501J0D01*
G01X359727Y1309842D01*
X359385Y1310184D01*
G02X359092Y1310891I706J707D01*
G01Y1315406D01*
X358313Y1316185D01*
X337603D01*
G02X336896Y1316478I0J999D01*
G01X328045Y1325329D01*
G02X327819Y1325677I707J706D01*
G02X327413Y1326704I1096J1027D01*
G02X327752Y1327654I1501J0D01*
G01Y1328354D01*
G02Y1330254I1162J950D01*
G01Y1330954D01*
G02Y1332854I1162J950D01*
G01Y1333554D01*
G02Y1335454I1162J950D01*
G01Y1336154D01*
G02X327413Y1337104I1162J950D01*
G02X327596Y1337823I1502J0D01*
G01X327668Y1337954D01*
X326844Y1338778D01*
X303992D01*
G02X303285Y1339071I0J999D01*
G01X299553Y1342803D01*
G02X299260Y1343510I706J707D01*
G01Y1368455D01*
G02X299553Y1369162I999J0D01*
G01X306125Y1375734D01*
G02X306832Y1376027I707J-706D01*
G01X337511D01*
X346741Y1385257D01*
G02X347448Y1385550I707J-706D01*
G01X377355D01*
G02X378062Y1385257I0J-999D01*
G01X380365Y1382954D01*
X380417Y1382940D01*
G02X381475Y1381882I-392J-1450D01*
G01X381489Y1381830D01*
X385146Y1378173D01*
X447117D01*
G37*
G36*
G01X1394374Y172851D02*
G02X1395334Y173198I960J-1154D01*
G01X1398734D01*
G02X1400236Y171696I0J-1502D01*
G02X1398743Y170194I-1502J0D01*
G02X1398182Y170076I-561J1276D01*
G02X1397656Y170179I0J1394D01*
G01X1397620Y170194D01*
X1395334D01*
G02X1394882Y170264I1J1502D01*
G02X1394184Y170076I-699J1206D01*
G01X1394182D01*
G02Y172864I0J1394D01*
G02X1394374Y172851I2J-1394D01*
G37*
G36*
G01X1358624Y283142D02*
X1355224D01*
G02Y286146I0J1502D01*
G01X1358624D01*
G02Y283142I0J-1502D01*
G37*
G36*
G01X1348084Y278756D02*
X1344684D01*
G02Y281762I0J1503D01*
G01X1348084D01*
G02Y278756I0J-1503D01*
G37*
G36*
G01X1368524Y281242D02*
X1365124D01*
G02Y284246I0J1502D01*
G01X1368524D01*
G02Y281242I0J-1502D01*
G37*
G36*
G01X1328480Y322400D02*
X1325080D01*
G02Y325404I0J1502D01*
G01X1328480D01*
G02Y322400I0J-1502D01*
G37*
G36*
G01X613970Y190254D02*
X617370D01*
G02Y187250I0J-1502D01*
G01X613970D01*
G02Y190254I0J1502D01*
G37*
G36*
G01X626640D02*
X630040D01*
G02Y187250I0J-1502D01*
G01X626640D01*
G02Y190254I0J1502D01*
G37*
G36*
G01X1400985Y242432D02*
X1404385D01*
G02Y239426I0J-1503D01*
G01X1400985D01*
G02Y242432I0J1503D01*
G37*
G36*
G01X1307442Y305496D02*
X1304042D01*
G02Y308500I0J1502D01*
G01X1307442D01*
G02Y305496I0J-1502D01*
G37*
G36*
G01X1307042Y291134D02*
X1303642D01*
G02Y294138I0J1502D01*
G01X1307042D01*
G02Y291134I0J-1502D01*
G37*
G36*
G01X1418630Y221520D02*
X1422030D01*
G02Y218516I0J-1502D01*
G01X1418630D01*
G02Y221520I0J1502D01*
G37*
G36*
G01X1407420D02*
X1410820D01*
G02Y218516I0J-1502D01*
G01X1407420D01*
G02Y221520I0J1502D01*
G37*
G36*
G01X1432660D02*
X1436060D01*
G02Y218516I0J-1502D01*
G01X1432660D01*
G02Y221520I0J1502D01*
G37*
G36*
G01X1348824Y327478D02*
X1345424D01*
G02Y330484I0J1503D01*
G01X1348824D01*
G02Y327478I0J-1503D01*
G37*
G36*
G01X1341431Y321190D02*
X1338031D01*
G02Y324196I0J1503D01*
G01X1341431D01*
G02Y321190I0J-1503D01*
G37*
G36*
G01X1335145Y331114D02*
X1331745D01*
G02Y334118I0J1502D01*
G01X1335145D01*
G02Y331114I0J-1502D01*
G37*
G36*
G01X1319618Y316570D02*
X1316218D01*
G02Y319576I0J1503D01*
G01X1319618D01*
G02Y316570I0J-1503D01*
G37*
G36*
G01X1311077Y321494D02*
X1307677D01*
G02Y324498I0J1502D01*
G01X1311077D01*
G02Y321494I0J-1502D01*
G37*
G36*
G01X1380602Y199170D02*
X1384002D01*
G02Y196166I0J-1502D01*
G01X1380602D01*
G02Y199170I0J1502D01*
G37*
G36*
G01X1398006D02*
X1401406D01*
G02Y196166I0J-1502D01*
G01X1398006D01*
G02Y199170I0J1502D01*
G37*
G36*
G01X1373591Y177932D02*
X1376991D01*
G02Y174928I0J-1502D01*
G01X1373591D01*
G02Y177932I0J1502D01*
G37*
G36*
G01X1406970Y140244D02*
X1410370D01*
G02Y137240I0J-1502D01*
G01X1406970D01*
G02Y140244I0J1502D01*
G37*
G36*
G01X1323303Y297674D02*
X1319903D01*
G02Y300678I0J1502D01*
G01X1323303D01*
G02Y297674I0J-1502D01*
G37*
G36*
G01X1361771Y330772D02*
X1358371D01*
G02Y333778I0J1503D01*
G01X1361771D01*
G02Y330772I0J-1503D01*
G37*
G36*
G01X1404829Y185766D02*
X1408229D01*
G02Y182760I0J-1503D01*
G01X1404829D01*
G02Y185766I0J1503D01*
G37*
G36*
G01X1412284Y173198D02*
X1415684D01*
G02Y170194I0J-1502D01*
G01X1412284D01*
G02Y173198I0J1502D01*
G37*
G36*
G01X1355200Y336340D02*
X1351800D01*
G02Y339346I0J1503D01*
G01X1355200D01*
G02Y336340I0J-1503D01*
G37*
G36*
G01X1328814Y292054D02*
X1325414D01*
G02Y295058I0J1502D01*
G01X1328814D01*
G02Y292054I0J-1502D01*
G37*
G36*
G01X1340161Y291902D02*
X1336761D01*
G02Y294906I0J1502D01*
G01X1340161D01*
G02Y291902I0J-1502D01*
G37*
G36*
G01X1413950Y185766D02*
X1417350D01*
G02Y182760I0J-1503D01*
G01X1413950D01*
G02Y185766I0J1503D01*
G37*
G36*
G01X1423110D02*
X1426510D01*
G02Y182760I0J-1503D01*
G01X1423110D01*
G02Y185766I0J1503D01*
G37*
G36*
G01X1401341Y178662D02*
X1404741D01*
G02Y175656I0J-1503D01*
G01X1401341D01*
G02Y178662I0J1503D01*
G37*
G36*
G01X1403778Y173186D02*
X1407178D01*
G02Y170182I0J-1502D01*
G01X1403778D01*
G02Y173186I0J1502D01*
G37*
G36*
G01X1389256Y199170D02*
X1392656D01*
G02Y196166I0J-1502D01*
G01X1389256D01*
G02Y199170I0J1502D01*
G37*
G36*
G01X987440Y432696D02*
X990840D01*
G02Y429690I0J-1503D01*
G01X987440D01*
G02Y432696I0J1503D01*
G37*
G36*
G01X934047Y459364D02*
X937447D01*
G02Y456360I0J-1502D01*
G01X934047D01*
G02Y459364I0J1502D01*
G37*
G36*
G01X942047Y464514D02*
X945447D01*
G02Y461510I0J-1502D01*
G01X942047D01*
G02Y464514I0J1502D01*
G37*
G36*
G01X909584Y459638D02*
X912984D01*
G02Y456632I0J-1503D01*
G01X909584D01*
G02Y459638I0J1503D01*
G37*
G36*
G01X1406786Y199170D02*
X1410186D01*
G02Y196166I0J-1502D01*
G01X1406786D01*
G02Y199170I0J1502D01*
G37*
G36*
G01X1312136Y283446D02*
X1308736D01*
G02Y286450I0J1502D01*
G01X1312136D01*
G02Y283446I0J-1502D01*
G37*
G36*
G01X921047Y464514D02*
X924447D01*
G02Y461510I0J-1502D01*
G01X921047D01*
G02Y464514I0J1502D01*
G37*
G36*
G01X1012861Y434390D02*
X1016261D01*
G02Y431386I0J-1502D01*
G01X1012861D01*
G02Y434390I0J1502D01*
G37*
G36*
G01X247175Y197050D02*
X253476D01*
G02X264218Y190154I0J-11814D01*
G03X264953Y190170I364J166D01*
G02X277098Y198346I12146J-4933D01*
G02Y172126I0J-13110D01*
G02X264953Y180302I1J13109D01*
G03X264218Y180318I-371J-150D01*
G02X253477Y173422I-10742J4918D01*
G01X247176D01*
G02X247175Y197050I0J11814D01*
G37*
G36*
G01X365287D02*
X371587D01*
G02X382329Y190155I0J-11815D01*
G03X383063Y190171I364J167D01*
G02X395208Y198346I12145J-4934D01*
G02Y172126I0J-13110D01*
G02X383063Y180301I0J13109D01*
G03X382329Y180317I-370J-151D01*
G02X371587Y173422I-10742J4920D01*
G01X365287D01*
G02Y197050I0J11814D01*
G37*
G36*
G01X351817Y1105941D02*
X351010Y1107338D01*
X350920Y1107355D01*
G02X349864Y1108630I242J1275D01*
G02X352460I1298J0D01*
G01Y1108628D01*
G02X352387Y1108201I-1298J2D01*
G01X352357Y1108115D01*
X353164Y1106718D01*
X353254Y1106701D01*
G02X354308Y1105426I-244J-1275D01*
G02X353011Y1104128I-1297J-1D01*
G02X351714Y1105426I1J1298D01*
G02X351787Y1105855I1297J0D01*
G01X351817Y1105941D01*
G37*
G36*
G01X342949Y1106204D02*
X344573D01*
G02X345611Y1106724I1038J-776D01*
G02Y1104128I0J-1298D01*
G02X344573Y1104648I0J1296D01*
G01X342949D01*
G02X341911Y1104128I-1038J776D01*
G02Y1106724I0J1298D01*
G02X342949Y1106204I0J-1296D01*
G37*
G36*
G01X350350Y1112612D02*
X351974D01*
G02X353012Y1113132I1038J-776D01*
G02Y1110536I0J-1298D01*
G02X351974Y1111056I0J1296D01*
G01X350350D01*
G02X349312Y1110536I-1038J776D01*
G02Y1113132I0J1298D01*
G02X350350Y1112612I0J-1296D01*
G37*
G36*
G01X342567Y1109144D02*
X341760Y1110542D01*
X341670Y1110559D01*
G02X340614Y1111834I242J1275D01*
G02X343210I1298J0D01*
G02X343137Y1111406I-1299J1D01*
G01X343107Y1111320D01*
X343914Y1109922D01*
X344004Y1109905D01*
G02X345060Y1108630I-242J-1275D01*
G02X342464I-1298J0D01*
G02X342537Y1109058I1299J-1D01*
G01X342567Y1109144D01*
G37*
G36*
G01X359217Y1112348D02*
X358409Y1113747D01*
X358319Y1113764D01*
G02X357264Y1115039I243J1275D01*
G02X359858I1297J0D01*
G01Y1115037D01*
G02X359786Y1114610I-1298J-1D01*
G01X359756Y1114524D01*
X360563Y1113126D01*
X360653Y1113109D01*
G02X361710Y1111834I-240J-1275D01*
G02X359114I-1298J0D01*
G02X359187Y1112262I1299J-1D01*
G01X359217Y1112348D01*
G37*
G36*
G01X358753Y886198D02*
G02X358680Y886625I1225J429D01*
G01Y886627D01*
G02X361276I1298J0D01*
G02X360220Y885352I-1298J0D01*
G01X360130Y885335D01*
X359324Y883938D01*
X359354Y883852D01*
G02X359426Y883425I-1226J-426D01*
G01Y883423D01*
G02X356832I-1297J0D01*
G02X357887Y884698I1298J0D01*
G01X357977Y884715D01*
X358783Y886112D01*
X358753Y886198D01*
G37*
G36*
G01X363959Y1106718D02*
X364766Y1108116D01*
X364736Y1108202D01*
G02X364664Y1108630I1226J426D01*
G02X367258I1297J0D01*
G02X366203Y1107355I-1298J0D01*
G01X366113Y1107338D01*
X365306Y1105941D01*
X365336Y1105855D01*
G02X365409Y1105426I-1224J-429D01*
G02X364112Y1104128I-1297J-1D01*
G02X362814Y1105426I0J1298D01*
G02X363869Y1106701I1298J0D01*
G01X363959Y1106718D01*
G37*
G36*
G01X337399Y1122224D02*
X339023D01*
G02X340061Y1122744I1038J-776D01*
G02Y1120150I0J-1297D01*
G02X339023Y1120670I0J1296D01*
G01X337399D01*
G02X336361Y1120150I-1038J776D01*
G02Y1122744I0J1297D01*
G02X337399Y1122224I0J-1296D01*
G37*
G36*
G01X362483Y880733D02*
X361677Y882131D01*
X361587Y882148D01*
G02X360532Y883423I243J1275D01*
G02X363126I1297J0D01*
G01Y883421D01*
G02X363054Y882994I-1298J-1D01*
G01X363024Y882908D01*
X363830Y881511D01*
X363920Y881494D01*
G02X364976Y880219I-242J-1275D01*
G02X362380I-1298J0D01*
G02X362453Y880647I1299J-1D01*
G01X362483Y880733D01*
G37*
G36*
G01X344799Y1128634D02*
X346423D01*
G02X347461Y1129154I1038J-776D01*
G02Y1126558I0J-1298D01*
G02X346423Y1127078I0J1296D01*
G01X344799D01*
G02X343761Y1126558I-1038J776D01*
G02Y1129154I0J1298D01*
G02X344799Y1128634I0J-1296D01*
G37*
G36*
G01X355083Y880733D02*
X354277Y882131D01*
X354187Y882148D01*
G02X353132Y883423I243J1275D01*
G02X355726I1297J0D01*
G01Y883421D01*
G02X355654Y882994I-1298J-1D01*
G01X355624Y882908D01*
X356430Y881511D01*
X356520Y881494D01*
G02X357576Y880219I-242J-1275D01*
G02X354980I-1298J0D01*
G02X355053Y880647I1299J-1D01*
G01X355083Y880733D01*
G37*
G36*
G01X346266Y1121961D02*
X345459Y1123359D01*
X345369Y1123376D01*
G02X344314Y1124651I243J1275D01*
G02X346908I1297J0D01*
G02X346836Y1124223I-1298J-2D01*
G01X346806Y1124137D01*
X347613Y1122739D01*
X347703Y1122722D01*
G02X348758Y1121447I-243J-1275D01*
G02X346164I-1297J0D01*
G02X346236Y1121875I1298J2D01*
G01X346266Y1121961D01*
G37*
G36*
G01X366153Y886198D02*
G02X366080Y886625I1225J429D01*
G01Y886627D01*
G02X368676I1298J0D01*
G02X367620Y885352I-1298J0D01*
G01X367530Y885335D01*
X366724Y883938D01*
X366754Y883852D01*
G02X366826Y883425I-1226J-426D01*
G01Y883423D01*
G02X364232I-1297J0D01*
G02X365287Y884698I1298J0D01*
G01X365377Y884715D01*
X366183Y886112D01*
X366153Y886198D01*
G37*
G36*
G01X355084Y867916D02*
X354277Y869314D01*
X354187Y869331D01*
G02X353132Y870606I243J1275D01*
G02X355726I1297J0D01*
G02X355654Y870177I-1297J-3D01*
G01X355623Y870091D01*
X356430Y868693D01*
X356520Y868676D01*
G02X357576Y867401I-242J-1275D01*
G02X354980I-1298J0D01*
G02X355053Y867830I1297J0D01*
G01X355084Y867916D01*
G37*
G36*
G01X362484D02*
X361677Y869314D01*
X361587Y869331D01*
G02X360532Y870606I243J1275D01*
G02X363126I1297J0D01*
G02X363054Y870177I-1297J-3D01*
G01X363023Y870091D01*
X363830Y868693D01*
X363920Y868676D01*
G02X364976Y867401I-242J-1275D01*
G02X362380I-1298J0D01*
G02X362453Y867830I1297J0D01*
G01X362484Y867916D01*
G37*
G36*
G01X369884D02*
X369077Y869314D01*
X368987Y869331D01*
G02X367932Y870606I243J1275D01*
G02X370526I1297J0D01*
G02X370454Y870177I-1297J-3D01*
G01X370423Y870091D01*
X371230Y868693D01*
X371320Y868676D01*
G02X372376Y867401I-242J-1275D01*
G02X369780I-1298J0D01*
G02X369853Y867830I1297J0D01*
G01X369884Y867916D01*
G37*
G36*
G01X350577Y871898D02*
X351384Y873295D01*
X351353Y873382D01*
G02X351280Y873810I1225J429D01*
G02X353876I1298J0D01*
G02X352820Y872535I-1298J0D01*
G01X352730Y872518D01*
X351923Y871121D01*
X351954Y871034D01*
G02X352026Y870606I-1225J-426D01*
G02X349432I-1297J0D01*
G02X350487Y871881I1298J0D01*
G01X350577Y871898D01*
G37*
G36*
G01X357977D02*
X358784Y873295D01*
X358753Y873382D01*
G02X358680Y873810I1225J429D01*
G02X361276I1298J0D01*
G02X360220Y872535I-1298J0D01*
G01X360130Y872518D01*
X359323Y871121D01*
X359354Y871034D01*
G02X359426Y870606I-1225J-426D01*
G02X356832I-1297J0D01*
G02X357887Y871881I1298J0D01*
G01X357977Y871898D01*
G37*
G36*
G01X365377D02*
X366184Y873295D01*
X366153Y873382D01*
G02X366080Y873810I1225J429D01*
G02X368676I1298J0D01*
G02X367620Y872535I-1298J0D01*
G01X367530Y872518D01*
X366723Y871121D01*
X366754Y871034D01*
G02X366826Y870606I-1225J-426D01*
G02X364232I-1297J0D01*
G02X365287Y871881I1298J0D01*
G01X365377Y871898D01*
G37*
G36*
G01X372777D02*
X373584Y873295D01*
X373553Y873382D01*
G02X373480Y873810I1225J429D01*
G02X376076I1298J0D01*
G02X375020Y872535I-1298J0D01*
G01X374930Y872518D01*
X374123Y871121D01*
X374154Y871034D01*
G02X374226Y870606I-1225J-426D01*
G02X371632I-1297J0D01*
G02X372687Y871881I1298J0D01*
G01X372777Y871898D01*
G37*
G36*
G01X369883Y880734D02*
X369077Y882131D01*
X368987Y882148D01*
G02X367932Y883423I243J1275D01*
G02X370526I1297J0D01*
G02X370454Y882994I-1297J-3D01*
G01X370423Y882908D01*
X371229Y881511D01*
X371319Y881494D01*
G02X372376Y880219I-240J-1275D01*
G02X369780I-1298J0D01*
G02X369853Y880647I1298J-1D01*
G01X369883Y880734D01*
G37*
G36*
G01X377283D02*
X376477Y882131D01*
X376387Y882148D01*
G02X375332Y883423I243J1275D01*
G02X377926I1297J0D01*
G02X377854Y882994I-1297J-3D01*
G01X377823Y882908D01*
X378629Y881511D01*
X378719Y881494D01*
G02X379776Y880219I-240J-1275D01*
G02X377180I-1298J0D01*
G02X377253Y880647I1298J-1D01*
G01X377283Y880734D01*
G37*
G36*
G01X372777Y884715D02*
X373584Y886112D01*
X373553Y886199D01*
G02X373480Y886627I1225J429D01*
G02X376076I1298J0D01*
G02X375020Y885352I-1298J0D01*
G01X374930Y885335D01*
X374123Y883938D01*
X374154Y883851D01*
G02X374226Y883423I-1225J-426D01*
G02X371632I-1297J0D01*
G02X372687Y884698I1298J0D01*
G01X372777Y884715D01*
G37*
G36*
G01X404001Y1082218D02*
G02X402962Y1081698I-1039J778D01*
G02Y1084292I0J1297D01*
G02X404001Y1083772I0J-1298D01*
G01X405623D01*
G02X406662Y1084292I1039J-778D01*
G02Y1081698I0J-1297D01*
G02X405623Y1082218I0J1298D01*
G01X404001D01*
G37*
G36*
G01X408361Y1081083D02*
X409168Y1082480D01*
X409137Y1082567D01*
G02X409064Y1082995I1225J429D01*
G02X411660I1298J0D01*
G02X410604Y1081720I-1298J0D01*
G01X410514Y1081703D01*
X409706Y1080304D01*
X409736Y1080218D01*
G02X409808Y1079791I-1225J-426D01*
G02X407214I-1297J0D01*
G02X408271Y1081066I1297J0D01*
G01X408361Y1081083D01*
G37*
G36*
G01X412867Y1083509D02*
X412059Y1084908D01*
X411969Y1084925D01*
G02X410914Y1086200I243J1275D01*
G02X413508I1297J0D01*
G02X413436Y1085772I-1297J-2D01*
G01X413405Y1085685D01*
X414212Y1084287D01*
X414303Y1084270D01*
G02X415360Y1082995I-240J-1275D01*
G02X412764I-1298J0D01*
G02X412837Y1083422I1298J-2D01*
G01X412867Y1083509D01*
G37*
G36*
G01X403616Y1086714D02*
X402809Y1088112D01*
X402719Y1088129D01*
G02X401664Y1089404I243J1275D01*
G02X404258I1297J0D01*
G02X404186Y1088976I-1297J-2D01*
G01X404155Y1088889D01*
X404962Y1087492D01*
X405052Y1087475D01*
G02X406108Y1086200I-242J-1275D01*
G02X403514I-1297J0D01*
G02X403586Y1086628I1297J2D01*
G01X403616Y1086714D01*
G37*
G36*
G01X411401Y1088626D02*
G02X410362Y1088106I-1039J778D01*
G02Y1090702I0J1298D01*
G02X411401Y1090182I0J-1298D01*
G01X413023D01*
G02X414062Y1090702I1039J-778D01*
G02Y1088106I0J-1298D01*
G02X413023Y1088626I0J1298D01*
G01X411401D01*
G37*
G36*
G01X406510Y1090696D02*
X407317Y1092093D01*
X407286Y1092180D01*
G02X407214Y1092608I1225J426D01*
G02X409808I1297J0D01*
G02X408753Y1091333I-1298J0D01*
G01X408663Y1091316D01*
X407856Y1089919D01*
X407887Y1089833D01*
G02X407960Y1089404I-1224J-429D01*
G02X405364I-1298J0D01*
G02X406420Y1090679I1298J0D01*
G01X406510Y1090696D01*
G37*
G36*
G01X420267Y1089917D02*
X419459Y1091316D01*
X419369Y1091333D01*
G02X418314Y1092608I243J1275D01*
G02X420908I1297J0D01*
G02X420836Y1092180I-1297J-2D01*
G01X420805Y1092093D01*
X421612Y1090696D01*
X421702Y1090679D01*
G02X422760Y1089404I-239J-1275D01*
G02X420164I-1298J0D01*
G02X420237Y1089831I1298J-2D01*
G01X420267Y1089917D01*
G37*
G36*
G01X405850Y1098240D02*
G02X404811Y1097720I-1039J778D01*
G02Y1100314I0J1297D01*
G02X405850Y1099794I0J-1298D01*
G01X407472D01*
G02X408511Y1100314I1039J-778D01*
G02Y1097720I0J-1297D01*
G02X407472Y1098240I0J1298D01*
G01X405850D01*
G37*
G36*
G01X352200Y1101444D02*
G02X351161Y1100924I-1039J778D01*
G02Y1103518I0J1297D01*
G02X352200Y1102998I0J-1298D01*
G01X353822D01*
G02X354861Y1103518I1039J-778D01*
G02Y1100924I0J-1297D01*
G02X353822Y1101444I0J1298D01*
G01X352200D01*
G37*
G36*
G01X400961Y1100309D02*
X401768Y1101706D01*
X401737Y1101793D01*
G02X401664Y1102221I1225J429D01*
G02X404260I1298J0D01*
G02X403204Y1100946I-1298J0D01*
G01X403114Y1100929D01*
X402306Y1099530D01*
X402336Y1099444D01*
G02X402408Y1099017I-1225J-426D01*
G02X399814I-1297J0D01*
G02X400871Y1100292I1297J0D01*
G01X400961Y1100309D01*
G37*
G36*
G01X376250Y1104648D02*
G02X375211Y1104128I-1039J778D01*
G02Y1106724I0J1298D01*
G02X376250Y1106204I0J-1298D01*
G01X377873D01*
G02X378912Y1106724I1039J-778D01*
G02Y1104128I0J-1298D01*
G02X377873Y1104648I0J1298D01*
G01X376250D01*
G37*
G36*
G01X380609Y1103513D02*
X381417Y1104911D01*
X381386Y1104998D01*
G02X381314Y1105426I1225J426D01*
G02X383908I1297J0D01*
G02X382853Y1104151I-1298J0D01*
G01X382763Y1104134D01*
X381956Y1102737D01*
X381986Y1102650D01*
G02X382060Y1102221I-1223J-432D01*
G02X379464I-1298J0D01*
G02X380519Y1103496I1298J0D01*
G01X380609Y1103513D01*
G37*
G36*
G01X412867Y1102735D02*
X412059Y1104134D01*
X411969Y1104151D01*
G02X410914Y1105426I243J1275D01*
G02X413508I1297J0D01*
G02X413436Y1104998I-1297J-2D01*
G01X413405Y1104911D01*
X414212Y1103513D01*
X414303Y1103496D01*
G02X415360Y1102221I-240J-1275D01*
G02X412764I-1298J0D01*
G02X412837Y1102648I1298J-2D01*
G01X412867Y1102735D01*
G37*
G36*
G01X359600Y1107852D02*
G02X358561Y1107332I-1039J778D01*
G02Y1109928I0J1298D01*
G02X359600Y1109408I0J-1298D01*
G01X361222D01*
G02X362261Y1109928I1039J-778D01*
G02Y1107332I0J-1298D01*
G02X361222Y1107852I0J1298D01*
G01X359600D01*
G37*
G36*
G01X385117Y1105941D02*
X384310Y1107338D01*
X384220Y1107355D01*
G02X383164Y1108630I242J1275D01*
G02X385760I1298J0D01*
G02X385687Y1108202I-1298J1D01*
G01X385656Y1108115D01*
X386463Y1106718D01*
X386553Y1106701D01*
G02X387608Y1105426I-243J-1275D01*
G02X385014I-1297J0D01*
G02X385086Y1105855I1297J3D01*
G01X385117Y1105941D01*
G37*
G36*
G01X392901Y1107852D02*
G02X391862Y1107332I-1039J778D01*
G02Y1109928I0J1298D01*
G02X392901Y1109408I0J-1298D01*
G01X394523D01*
G02X395562Y1109928I1039J-778D01*
G02Y1107332I0J-1298D01*
G02X394523Y1107852I0J1298D01*
G01X392901D01*
G37*
G36*
G01X397261Y1106718D02*
X398068Y1108115D01*
X398037Y1108202D01*
G02X397964Y1108630I1225J429D01*
G02X400560I1298J0D01*
G02X399504Y1107355I-1298J0D01*
G01X399414Y1107338D01*
X398606Y1105939D01*
X398636Y1105853D01*
G02X398708Y1105426I-1225J-426D01*
G02X396114I-1297J0D01*
G02X397171Y1106701I1297J0D01*
G01X397261Y1106718D01*
G37*
G36*
G01X408361D02*
X409168Y1108115D01*
X409137Y1108202D01*
G02X409064Y1108630I1225J429D01*
G02X411660I1298J0D01*
G02X410604Y1107355I-1298J0D01*
G01X410514Y1107338D01*
X409706Y1105939D01*
X409736Y1105853D01*
G02X409808Y1105426I-1225J-426D01*
G02X407214I-1297J0D01*
G02X408271Y1106701I1297J0D01*
G01X408361Y1106718D01*
G37*
G36*
G01X368467Y1109145D02*
X367660Y1110542D01*
X367570Y1110559D01*
G02X366514Y1111834I242J1275D01*
G02X369110I1298J0D01*
G02X369037Y1111406I-1298J1D01*
G01X369006Y1111319D01*
X369813Y1109922D01*
X369903Y1109905D01*
G02X370958Y1108630I-243J-1275D01*
G02X368364I-1297J0D01*
G02X368436Y1109059I1297J3D01*
G01X368467Y1109145D01*
G37*
G36*
G01X375867Y1109143D02*
X375059Y1110542D01*
X374969Y1110559D01*
G02X373914Y1111834I243J1275D01*
G02X376508I1297J0D01*
G02X376436Y1111406I-1297J-2D01*
G01X376405Y1111319D01*
X377212Y1109922D01*
X377302Y1109905D01*
G02X378360Y1108630I-239J-1275D01*
G02X375764I-1298J0D01*
G02X375837Y1109057I1298J-2D01*
G01X375867Y1109143D01*
G37*
G36*
G01X383650Y1111056D02*
G02X382611Y1110536I-1039J778D01*
G02Y1113132I0J1298D01*
G02X383650Y1112612I0J-1298D01*
G01X385272D01*
G02X386311Y1113132I1039J-778D01*
G02Y1110536I0J-1298D01*
G02X385272Y1111056I0J1298D01*
G01X383650D01*
G37*
G36*
G01X401767Y1109143D02*
X400959Y1110542D01*
X400869Y1110559D01*
G02X399814Y1111834I243J1275D01*
G02X402408I1297J0D01*
G02X402336Y1111406I-1297J-2D01*
G01X402305Y1111319D01*
X403112Y1109922D01*
X403202Y1109905D01*
G02X404260Y1108630I-239J-1275D01*
G02X401664I-1298J0D01*
G02X401737Y1109057I1298J-2D01*
G01X401767Y1109143D01*
G37*
G36*
G01X409550Y1111056D02*
G02X408511Y1110536I-1039J778D01*
G02Y1113132I0J1298D01*
G02X409550Y1112612I0J-1298D01*
G01X411172D01*
G02X412211Y1113132I1039J-778D01*
G02Y1110536I0J-1298D01*
G02X411172Y1111056I0J1298D01*
G01X409550D01*
G37*
G36*
G01X345459Y1113126D02*
X346267Y1114524D01*
X346236Y1114611D01*
G02X346164Y1115039I1225J426D01*
G02X348758I1297J0D01*
G02X347703Y1113764I-1298J0D01*
G01X347613Y1113747D01*
X346805Y1112349D01*
X346836Y1112262D01*
G02X346908Y1111834I-1225J-426D01*
G02X344314I-1297J0D01*
G02X345369Y1113109I1298J0D01*
G01X345459Y1113126D01*
G37*
G36*
G01X367000Y1114262D02*
G02X365961Y1113742I-1039J778D01*
G02Y1116336I0J1297D01*
G02X367000Y1115816I0J-1298D01*
G01X368622D01*
G02X369661Y1116336I1039J-778D01*
G02Y1113742I0J-1297D01*
G02X368622Y1114262I0J1298D01*
G01X367000D01*
G37*
G36*
G01X378761Y1113126D02*
X379568Y1114524D01*
X379537Y1114611D01*
G02X379464Y1115039I1225J429D01*
G02X382060I1298J0D01*
G02X381004Y1113764I-1298J0D01*
G01X380914Y1113747D01*
X380106Y1112348D01*
X380136Y1112261D01*
G02X380208Y1111834I-1225J-426D01*
G02X377614I-1297J0D01*
G02X378670Y1113109I1298J0D01*
G01X378761Y1113126D01*
G37*
G36*
G01X392517Y1112350D02*
X391710Y1113747D01*
X391620Y1113764D01*
G02X390564Y1115039I242J1275D01*
G02X393160I1298J0D01*
G02X393087Y1114611I-1298J1D01*
G01X393056Y1114524D01*
X393864Y1113126D01*
X393954Y1113109D01*
G02X395008Y1111834I-244J-1275D01*
G02X392414I-1297J0D01*
G02X392487Y1112263I1297J0D01*
G01X392517Y1112350D01*
G37*
G36*
G01X400301Y1114262D02*
G02X399262Y1113742I-1039J778D01*
G02Y1116336I0J1297D01*
G02X400301Y1115816I0J-1298D01*
G01X401923D01*
G02X402962Y1116336I1039J-778D01*
G02Y1113742I0J-1297D01*
G02X401923Y1114262I0J1298D01*
G01X400301D01*
G37*
G36*
G01X341760Y1119535D02*
X342567Y1120932D01*
X342536Y1121019D01*
G02X342464Y1121447I1225J426D01*
G02X345058I1297J0D01*
G02X344003Y1120172I-1298J0D01*
G01X343913Y1120155D01*
X343106Y1118758D01*
X343137Y1118671D01*
G02X343210Y1118243I-1225J-429D01*
G02X340614I-1298J0D01*
G02X341670Y1119518I1298J0D01*
G01X341760Y1119535D01*
G37*
G36*
G01X357367Y1121962D02*
X356560Y1123359D01*
X356470Y1123376D01*
G02X355414Y1124651I242J1275D01*
G02X358010I1298J0D01*
G02X357937Y1124223I-1298J1D01*
G01X357906Y1124136D01*
X358713Y1122739D01*
X358803Y1122722D01*
G02X359858Y1121447I-243J-1275D01*
G02X357264I-1297J0D01*
G02X357336Y1121876I1297J3D01*
G01X357367Y1121962D01*
G37*
G36*
G01X364767Y1121960D02*
X363959Y1123359D01*
X363869Y1123376D01*
G02X362814Y1124651I243J1275D01*
G02X365408I1297J0D01*
G02X365336Y1124223I-1297J-2D01*
G01X365305Y1124136D01*
X366112Y1122739D01*
X366202Y1122722D01*
G02X367260Y1121447I-239J-1275D01*
G02X364664I-1298J0D01*
G02X364737Y1121874I1298J-2D01*
G01X364767Y1121960D01*
G37*
G36*
G01X372167D02*
X371359Y1123359D01*
X371269Y1123376D01*
G02X370214Y1124651I243J1275D01*
G02X372808I1297J0D01*
G02X372736Y1124223I-1297J-2D01*
G01X372705Y1124136D01*
X373512Y1122739D01*
X373602Y1122722D01*
G02X374660Y1121447I-239J-1275D01*
G02X372064I-1298J0D01*
G02X372137Y1121874I1298J-2D01*
G01X372167Y1121960D01*
G37*
G36*
G01X379567D02*
X378759Y1123359D01*
X378669Y1123376D01*
G02X377614Y1124651I243J1275D01*
G02X380208I1297J0D01*
G02X380136Y1124223I-1297J-2D01*
G01X380105Y1124136D01*
X380912Y1122739D01*
X381002Y1122722D01*
G02X382060Y1121447I-239J-1275D01*
G02X379464I-1298J0D01*
G02X379537Y1121874I1298J-2D01*
G01X379567Y1121960D01*
G37*
G36*
G01X386967D02*
X386159Y1123359D01*
X386069Y1123376D01*
G02X385014Y1124651I243J1275D01*
G02X387608I1297J0D01*
G02X387536Y1124223I-1297J-2D01*
G01X387505Y1124136D01*
X388312Y1122739D01*
X388402Y1122722D01*
G02X389460Y1121447I-239J-1275D01*
G02X386864I-1298J0D01*
G02X386937Y1121874I1298J-2D01*
G01X386967Y1121960D01*
G37*
G36*
G01X394367D02*
X393559Y1123359D01*
X393469Y1123376D01*
G02X392414Y1124651I243J1275D01*
G02X395008I1297J0D01*
G02X394936Y1124223I-1297J-2D01*
G01X394905Y1124136D01*
X395712Y1122739D01*
X395802Y1122722D01*
G02X396860Y1121447I-239J-1275D01*
G02X394264I-1298J0D01*
G02X394337Y1121874I1298J-2D01*
G01X394367Y1121960D01*
G37*
G36*
G01X401767D02*
X400959Y1123359D01*
X400869Y1123376D01*
G02X399814Y1124651I243J1275D01*
G02X402408I1297J0D01*
G02X402336Y1124223I-1297J-2D01*
G01X402305Y1124136D01*
X403112Y1122739D01*
X403202Y1122722D01*
G02X404260Y1121447I-239J-1275D01*
G02X401664I-1298J0D01*
G02X401737Y1121874I1298J-2D01*
G01X401767Y1121960D01*
G37*
G36*
G01X352859Y1125943D02*
X353667Y1127341D01*
X353636Y1127428D01*
G02X353564Y1127856I1225J426D01*
G02X356158I1297J0D01*
G02X355103Y1126581I-1298J0D01*
G01X355013Y1126564D01*
X354205Y1125166D01*
X354236Y1125079D01*
G02X354308Y1124651I-1225J-426D01*
G02X351714I-1297J0D01*
G02X352769Y1125926I1298J0D01*
G01X352859Y1125943D01*
G37*
G36*
G01X360260D02*
X361068Y1127341D01*
X361037Y1127428D01*
G02X360964Y1127856I1225J429D01*
G02X363560I1298J0D01*
G02X362504Y1126581I-1298J0D01*
G01X362414Y1126564D01*
X361606Y1125166D01*
X361637Y1125079D01*
G02X361710Y1124651I-1225J-429D01*
G02X359114I-1298J0D01*
G02X360170Y1125926I1298J0D01*
G01X360260Y1125943D01*
G37*
G36*
G01X367661D02*
X368468Y1127341D01*
X368437Y1127428D01*
G02X368364Y1127856I1225J429D01*
G02X370960I1298J0D01*
G02X369904Y1126581I-1298J0D01*
G01X369814Y1126564D01*
X369006Y1125165D01*
X369036Y1125078D01*
G02X369108Y1124651I-1225J-426D01*
G02X366514I-1297J0D01*
G02X367570Y1125926I1298J0D01*
G01X367661Y1125943D01*
G37*
G36*
G01X375061D02*
X375868Y1127341D01*
X375837Y1127428D01*
G02X375764Y1127856I1225J429D01*
G02X378360I1298J0D01*
G02X377304Y1126581I-1298J0D01*
G01X377214Y1126564D01*
X376406Y1125165D01*
X376436Y1125078D01*
G02X376508Y1124651I-1225J-426D01*
G02X373914I-1297J0D01*
G02X374970Y1125926I1298J0D01*
G01X375061Y1125943D01*
G37*
G36*
G01X382461D02*
X383268Y1127341D01*
X383237Y1127428D01*
G02X383164Y1127856I1225J429D01*
G02X385760I1298J0D01*
G02X384704Y1126581I-1298J0D01*
G01X384614Y1126564D01*
X383806Y1125165D01*
X383836Y1125078D01*
G02X383908Y1124651I-1225J-426D01*
G02X381314I-1297J0D01*
G02X382370Y1125926I1298J0D01*
G01X382461Y1125943D01*
G37*
G36*
G01X389861D02*
X390668Y1127341D01*
X390637Y1127428D01*
G02X390564Y1127856I1225J429D01*
G02X393160I1298J0D01*
G02X392104Y1126581I-1298J0D01*
G01X392014Y1126564D01*
X391206Y1125165D01*
X391236Y1125078D01*
G02X391308Y1124651I-1225J-426D01*
G02X388714I-1297J0D01*
G02X389770Y1125926I1298J0D01*
G01X389861Y1125943D01*
G37*
G36*
G01X397261D02*
X398068Y1127341D01*
X398037Y1127428D01*
G02X397964Y1127856I1225J429D01*
G02X400560I1298J0D01*
G02X399504Y1126581I-1298J0D01*
G01X399414Y1126564D01*
X398606Y1125165D01*
X398636Y1125078D01*
G02X398708Y1124651I-1225J-426D01*
G02X396114I-1297J0D01*
G02X397170Y1125926I1298J0D01*
G01X397261Y1125943D01*
G37*
G36*
G01X404661D02*
X405468Y1127341D01*
X405437Y1127428D01*
G02X405364Y1127856I1225J429D01*
G02X407960I1298J0D01*
G02X406904Y1126581I-1298J0D01*
G01X406814Y1126564D01*
X406006Y1125165D01*
X406036Y1125078D01*
G02X406108Y1124651I-1225J-426D01*
G02X403514I-1297J0D01*
G02X404570Y1125926I1298J0D01*
G01X404661Y1125943D01*
G37*
G36*
G01X339909Y1129148D02*
X340716Y1130546D01*
X340686Y1130632D01*
G02X340614Y1131060I1225J426D01*
G02X343208I1297J0D01*
G02X342153Y1129785I-1298J0D01*
G01X342063Y1129768D01*
X341256Y1128370D01*
X341286Y1128284D01*
G02X341358Y1127856I-1225J-426D01*
G02X338764I-1297J0D01*
G02X339819Y1129131I1298J0D01*
G01X339909Y1129148D01*
G37*
G36*
G01X459739Y842761D02*
X460580Y844356D01*
X460541Y844444D01*
G02X460430Y844971I1186J525D01*
G02X463024I1297J0D01*
G02X461962Y843695I-1298J0D01*
G01X461867Y843677D01*
X461026Y842082D01*
X461065Y841994D01*
G02X461176Y841467I-1186J-525D01*
G02X458582I-1297J0D01*
G02X459644Y842743I1298J0D01*
G01X459739Y842761D01*
G37*
G36*
G01X467139D02*
X467980Y844356D01*
X467941Y844444D01*
G02X467830Y844971I1186J525D01*
G02X470424I1297J0D01*
G02X469362Y843695I-1298J0D01*
G01X469267Y843677D01*
X468426Y842082D01*
X468465Y841994D01*
G02X468576Y841467I-1186J-525D01*
G02X465982I-1297J0D01*
G02X467044Y842743I1298J0D01*
G01X467139Y842761D01*
G37*
G36*
G01X474539D02*
X475380Y844356D01*
X475341Y844444D01*
G02X475230Y844971I1186J525D01*
G02X477824I1297J0D01*
G02X476762Y843695I-1298J0D01*
G01X476667Y843677D01*
X475826Y842082D01*
X475865Y841994D01*
G02X475976Y841467I-1186J-525D01*
G02X473382I-1297J0D01*
G02X474444Y842743I1298J0D01*
G01X474539Y842761D01*
G37*
G36*
G01X481939D02*
X482780Y844356D01*
X482741Y844444D01*
G02X482630Y844971I1186J525D01*
G02X485224I1297J0D01*
G02X484162Y843695I-1298J0D01*
G01X484067Y843677D01*
X483226Y842082D01*
X483265Y841994D01*
G02X483376Y841467I-1186J-525D01*
G02X480782I-1297J0D01*
G02X481844Y842743I1298J0D01*
G01X481939Y842761D01*
G37*
G36*
G01X489420Y842767D02*
X490213Y844297D01*
X490168Y844389D01*
G02X490030Y844971I1158J582D01*
G02X492624I1297J0D01*
G02X491519Y843688I-1297J0D01*
G01X491418Y843673D01*
X490608Y842112D01*
X490651Y842023D01*
G02X490776Y841467I-1174J-556D01*
G02X488180I-1298J0D01*
G02X489315Y842754I1297J0D01*
G01X489420Y842767D01*
G37*
G36*
G01X496739Y842761D02*
X497580Y844356D01*
X497541Y844444D01*
G02X497430Y844971I1186J525D01*
G02X500024I1297J0D01*
G02X498962Y843695I-1298J0D01*
G01X498867Y843677D01*
X498025Y842081D01*
X498064Y841993D01*
G02X498176Y841467I-1186J-527D01*
G02X495580I-1298J0D01*
G02X496644Y842743I1297J0D01*
G01X496739Y842761D01*
G37*
G36*
G01X464233Y845486D02*
X463426Y846884D01*
X463336Y846901D01*
G02X462280Y848176I242J1275D01*
G02X464876I1298J0D01*
G02X464803Y847747I-1297J0D01*
G01X464772Y847661D01*
X465579Y846263D01*
X465669Y846246D01*
G02X466724Y844971I-243J-1275D01*
G02X464130I-1297J0D01*
G02X464202Y845400I1297J3D01*
G01X464233Y845486D01*
G37*
G36*
G01X471633D02*
X470826Y846884D01*
X470736Y846901D01*
G02X469680Y848176I242J1275D01*
G02X472276I1298J0D01*
G02X472203Y847747I-1297J0D01*
G01X472172Y847661D01*
X472979Y846263D01*
X473069Y846246D01*
G02X474124Y844971I-243J-1275D01*
G02X471530I-1297J0D01*
G02X471602Y845400I1297J3D01*
G01X471633Y845486D01*
G37*
G36*
G01X479033D02*
X478226Y846884D01*
X478136Y846901D01*
G02X477080Y848176I242J1275D01*
G02X479676I1298J0D01*
G02X479603Y847747I-1297J0D01*
G01X479572Y847661D01*
X480379Y846263D01*
X480469Y846246D01*
G02X481524Y844971I-243J-1275D01*
G02X478930I-1297J0D01*
G02X479002Y845400I1297J3D01*
G01X479033Y845486D01*
G37*
G36*
G01X486433D02*
X485626Y846884D01*
X485536Y846901D01*
G02X484480Y848176I242J1275D01*
G02X487076I1298J0D01*
G02X487003Y847747I-1297J0D01*
G01X486972Y847661D01*
X487779Y846263D01*
X487869Y846246D01*
G02X488924Y844971I-243J-1275D01*
G02X486330I-1297J0D01*
G02X486402Y845400I1297J3D01*
G01X486433Y845486D01*
G37*
G36*
G01X493833D02*
X493026Y846884D01*
X492936Y846901D01*
G02X491880Y848176I242J1275D01*
G02X494476I1298J0D01*
G02X494403Y847747I-1297J0D01*
G01X494372Y847661D01*
X495179Y846263D01*
X495269Y846246D01*
G02X496324Y844971I-243J-1275D01*
G02X493730I-1297J0D01*
G02X493802Y845400I1297J3D01*
G01X493833Y845486D01*
G37*
G36*
G01X459728Y855876D02*
X460535Y857274D01*
X460504Y857361D01*
G02X460432Y857789I1225J426D01*
G02X463026I1297J0D01*
G02X461971Y856514I-1298J0D01*
G01X461881Y856497D01*
X461073Y855098D01*
X461103Y855011D01*
G02X461176Y854584I-1225J-429D01*
G02X458580I-1298J0D01*
G02X459638Y855859I1297J0D01*
G01X459728Y855876D01*
G37*
G36*
G01X467128D02*
X467935Y857274D01*
X467904Y857361D01*
G02X467832Y857789I1225J426D01*
G02X470426I1297J0D01*
G02X469371Y856514I-1298J0D01*
G01X469281Y856497D01*
X468473Y855098D01*
X468503Y855011D01*
G02X468576Y854584I-1225J-429D01*
G02X465980I-1298J0D01*
G02X467038Y855859I1297J0D01*
G01X467128Y855876D01*
G37*
G36*
G01X474528D02*
X475335Y857274D01*
X475304Y857361D01*
G02X475232Y857789I1225J426D01*
G02X477826I1297J0D01*
G02X476771Y856514I-1298J0D01*
G01X476681Y856497D01*
X475873Y855098D01*
X475903Y855011D01*
G02X475976Y854584I-1225J-429D01*
G02X473380I-1298J0D01*
G02X474438Y855859I1297J0D01*
G01X474528Y855876D01*
G37*
G36*
G01X481928D02*
X482735Y857274D01*
X482704Y857361D01*
G02X482632Y857789I1225J426D01*
G02X485226I1297J0D01*
G02X484171Y856514I-1298J0D01*
G01X484081Y856497D01*
X483273Y855098D01*
X483303Y855011D01*
G02X483376Y854584I-1225J-429D01*
G02X480780I-1298J0D01*
G02X481838Y855859I1297J0D01*
G01X481928Y855876D01*
G37*
G36*
G01X489328D02*
X490135Y857274D01*
X490104Y857361D01*
G02X490032Y857789I1225J426D01*
G02X492626I1297J0D01*
G02X491571Y856514I-1298J0D01*
G01X491481Y856497D01*
X490673Y855098D01*
X490703Y855011D01*
G02X490776Y854584I-1225J-429D01*
G02X488180I-1298J0D01*
G02X489238Y855859I1297J0D01*
G01X489328Y855876D01*
G37*
G36*
G01X496728D02*
X497535Y857274D01*
X497504Y857361D01*
G02X497432Y857789I1225J426D01*
G02X500026I1297J0D01*
G02X498971Y856514I-1298J0D01*
G01X498881Y856497D01*
X498073Y855098D01*
X498103Y855011D01*
G02X498176Y854584I-1225J-429D01*
G02X495580I-1298J0D01*
G02X496638Y855859I1297J0D01*
G01X496728Y855876D01*
G37*
G36*
G01X464234Y858302D02*
X463426Y859701D01*
X463336Y859718D01*
G02X462280Y860993I242J1275D01*
G02X464876I1298J0D01*
G02X464803Y860564I-1297J0D01*
G01X464772Y860478D01*
X465578Y859081D01*
X465668Y859064D01*
G02X466726Y857789I-239J-1275D01*
G02X464132I-1297J0D01*
G02X464203Y858215I1297J3D01*
G01X464234Y858302D01*
G37*
G36*
G01X471634D02*
X470826Y859701D01*
X470736Y859718D01*
G02X469680Y860993I242J1275D01*
G02X472276I1298J0D01*
G02X472203Y860564I-1297J0D01*
G01X472172Y860478D01*
X472978Y859081D01*
X473068Y859064D01*
G02X474126Y857789I-239J-1275D01*
G02X471532I-1297J0D01*
G02X471603Y858215I1297J3D01*
G01X471634Y858302D01*
G37*
G36*
G01X479034D02*
X478226Y859701D01*
X478136Y859718D01*
G02X477080Y860993I242J1275D01*
G02X479676I1298J0D01*
G02X479603Y860564I-1297J0D01*
G01X479572Y860478D01*
X480378Y859081D01*
X480468Y859064D01*
G02X481526Y857789I-239J-1275D01*
G02X478932I-1297J0D01*
G02X479003Y858215I1297J3D01*
G01X479034Y858302D01*
G37*
G36*
G01X486434D02*
X485626Y859701D01*
X485536Y859718D01*
G02X484480Y860993I242J1275D01*
G02X487076I1298J0D01*
G02X487003Y860564I-1297J0D01*
G01X486972Y860478D01*
X487778Y859081D01*
X487868Y859064D01*
G02X488926Y857789I-239J-1275D01*
G02X486332I-1297J0D01*
G02X486403Y858215I1297J3D01*
G01X486434Y858302D01*
G37*
G36*
G01X493834D02*
X493026Y859701D01*
X492936Y859718D01*
G02X491880Y860993I242J1275D01*
G02X494476I1298J0D01*
G02X494403Y860564I-1297J0D01*
G01X494372Y860478D01*
X495178Y859081D01*
X495268Y859064D01*
G02X496326Y857789I-239J-1275D01*
G02X493732I-1297J0D01*
G02X493803Y858215I1297J3D01*
G01X493834Y858302D01*
G37*
G36*
G01X459728Y868693D02*
X460535Y870091D01*
X460504Y870178D01*
G02X460432Y870606I1225J426D01*
G02X463026I1297J0D01*
G02X461971Y869331I-1298J0D01*
G01X461881Y869314D01*
X461073Y867915D01*
X461103Y867828D01*
G02X461176Y867401I-1225J-429D01*
G02X458580I-1298J0D01*
G02X459638Y868676I1297J0D01*
G01X459728Y868693D01*
G37*
G36*
G01X467128D02*
X467935Y870091D01*
X467904Y870178D01*
G02X467832Y870606I1225J426D01*
G02X470426I1297J0D01*
G02X469371Y869331I-1298J0D01*
G01X469281Y869314D01*
X468473Y867915D01*
X468503Y867828D01*
G02X468576Y867401I-1225J-429D01*
G02X465980I-1298J0D01*
G02X467038Y868676I1297J0D01*
G01X467128Y868693D01*
G37*
G36*
G01X474528D02*
X475335Y870091D01*
X475304Y870178D01*
G02X475232Y870606I1225J426D01*
G02X477826I1297J0D01*
G02X476771Y869331I-1298J0D01*
G01X476681Y869314D01*
X475873Y867915D01*
X475903Y867828D01*
G02X475976Y867401I-1225J-429D01*
G02X473380I-1298J0D01*
G02X474438Y868676I1297J0D01*
G01X474528Y868693D01*
G37*
G36*
G01X481928D02*
X482735Y870091D01*
X482704Y870178D01*
G02X482632Y870606I1225J426D01*
G02X485226I1297J0D01*
G02X484171Y869331I-1298J0D01*
G01X484081Y869314D01*
X483273Y867915D01*
X483303Y867828D01*
G02X483376Y867401I-1225J-429D01*
G02X480780I-1298J0D01*
G02X481838Y868676I1297J0D01*
G01X481928Y868693D01*
G37*
G36*
G01X489328D02*
X490135Y870091D01*
X490104Y870178D01*
G02X490032Y870606I1225J426D01*
G02X492626I1297J0D01*
G02X491571Y869331I-1298J0D01*
G01X491481Y869314D01*
X490673Y867915D01*
X490703Y867828D01*
G02X490776Y867401I-1225J-429D01*
G02X488180I-1298J0D01*
G02X489238Y868676I1297J0D01*
G01X489328Y868693D01*
G37*
G36*
G01X496728D02*
X497535Y870091D01*
X497504Y870178D01*
G02X497432Y870606I1225J426D01*
G02X500026I1297J0D01*
G02X498971Y869331I-1298J0D01*
G01X498881Y869314D01*
X498073Y867915D01*
X498103Y867828D01*
G02X498176Y867401I-1225J-429D01*
G02X495580I-1298J0D01*
G02X496638Y868676I1297J0D01*
G01X496728Y868693D01*
G37*
G36*
G01X464234Y871119D02*
X463426Y872518D01*
X463336Y872535D01*
G02X462280Y873810I242J1275D01*
G02X464876I1298J0D01*
G02X464803Y873381I-1297J0D01*
G01X464772Y873295D01*
X465578Y871898D01*
X465668Y871881D01*
G02X466726Y870606I-239J-1275D01*
G02X464132I-1297J0D01*
G02X464203Y871032I1297J3D01*
G01X464234Y871119D01*
G37*
G36*
G01X479034D02*
X478226Y872518D01*
X478136Y872535D01*
G02X477080Y873810I242J1275D01*
G02X479676I1298J0D01*
G02X479603Y873381I-1297J0D01*
G01X479572Y873295D01*
X480378Y871898D01*
X480468Y871881D01*
G02X481526Y870606I-239J-1275D01*
G02X478932I-1297J0D01*
G02X479003Y871032I1297J3D01*
G01X479034Y871119D01*
G37*
G36*
G01X486434D02*
X485626Y872518D01*
X485536Y872535D01*
G02X484480Y873810I242J1275D01*
G02X487076I1298J0D01*
G02X487003Y873381I-1297J0D01*
G01X486972Y873295D01*
X487778Y871898D01*
X487868Y871881D01*
G02X488926Y870606I-239J-1275D01*
G02X486332I-1297J0D01*
G02X486403Y871032I1297J3D01*
G01X486434Y871119D01*
G37*
G36*
G01X493834D02*
X493026Y872518D01*
X492936Y872535D01*
G02X491880Y873810I242J1275D01*
G02X494476I1298J0D01*
G02X494403Y873381I-1297J0D01*
G01X494372Y873295D01*
X495178Y871898D01*
X495268Y871881D01*
G02X496326Y870606I-239J-1275D01*
G02X493732I-1297J0D01*
G02X493803Y871032I1297J3D01*
G01X493834Y871119D01*
G37*
G36*
G01X458683Y880734D02*
X457877Y882131D01*
X457787Y882148D01*
G02X456732Y883423I243J1275D01*
G02X459326I1297J0D01*
G02X459254Y882994I-1297J-3D01*
G01X459223Y882908D01*
X460029Y881511D01*
X460119Y881494D01*
G02X461176Y880219I-240J-1275D01*
G02X458580I-1298J0D01*
G02X458653Y880647I1298J-1D01*
G01X458683Y880734D01*
G37*
G36*
G01X466083D02*
X465277Y882131D01*
X465187Y882148D01*
G02X464132Y883423I243J1275D01*
G02X466726I1297J0D01*
G02X466654Y882994I-1297J-3D01*
G01X466623Y882908D01*
X467429Y881511D01*
X467519Y881494D01*
G02X468576Y880219I-240J-1275D01*
G02X465980I-1298J0D01*
G02X466053Y880647I1298J-1D01*
G01X466083Y880734D01*
G37*
G36*
G01X473483D02*
X472677Y882131D01*
X472587Y882148D01*
G02X471532Y883423I243J1275D01*
G02X474126I1297J0D01*
G02X474054Y882994I-1297J-3D01*
G01X474023Y882908D01*
X474829Y881511D01*
X474919Y881494D01*
G02X475976Y880219I-240J-1275D01*
G02X473380I-1298J0D01*
G02X473453Y880647I1298J-1D01*
G01X473483Y880734D01*
G37*
G36*
G01X480883D02*
X480077Y882131D01*
X479987Y882148D01*
G02X478932Y883423I243J1275D01*
G02X481526I1297J0D01*
G02X481454Y882994I-1297J-3D01*
G01X481423Y882908D01*
X482229Y881511D01*
X482319Y881494D01*
G02X483376Y880219I-240J-1275D01*
G02X480780I-1298J0D01*
G02X480853Y880647I1298J-1D01*
G01X480883Y880734D01*
G37*
G36*
G01X488283D02*
X487477Y882131D01*
X487387Y882148D01*
G02X486332Y883423I243J1275D01*
G02X488926I1297J0D01*
G02X488854Y882994I-1297J-3D01*
G01X488823Y882908D01*
X489629Y881511D01*
X489719Y881494D01*
G02X490776Y880219I-240J-1275D01*
G02X488180I-1298J0D01*
G02X488253Y880647I1298J-1D01*
G01X488283Y880734D01*
G37*
G36*
G01X495683D02*
X494877Y882131D01*
X494787Y882148D01*
G02X493732Y883423I243J1275D01*
G02X496326I1297J0D01*
G02X496254Y882994I-1297J-3D01*
G01X496223Y882908D01*
X497029Y881511D01*
X497119Y881494D01*
G02X498176Y880219I-240J-1275D01*
G02X495580I-1298J0D01*
G02X495653Y880647I1298J-1D01*
G01X495683Y880734D01*
G37*
G36*
G01X461577Y884715D02*
X462384Y886112D01*
X462353Y886199D01*
G02X462280Y886627I1225J429D01*
G02X464876I1298J0D01*
G02X463820Y885352I-1298J0D01*
G01X463730Y885335D01*
X462923Y883938D01*
X462954Y883851D01*
G02X463026Y883423I-1225J-426D01*
G02X460432I-1297J0D01*
G02X461487Y884698I1298J0D01*
G01X461577Y884715D01*
G37*
G36*
G01X468977D02*
X469784Y886112D01*
X469753Y886199D01*
G02X469680Y886627I1225J429D01*
G02X472276I1298J0D01*
G02X471220Y885352I-1298J0D01*
G01X471130Y885335D01*
X470323Y883938D01*
X470354Y883851D01*
G02X470426Y883423I-1225J-426D01*
G02X467832I-1297J0D01*
G02X468887Y884698I1298J0D01*
G01X468977Y884715D01*
G37*
G36*
G01X476377D02*
X477184Y886112D01*
X477153Y886199D01*
G02X477080Y886627I1225J429D01*
G02X479676I1298J0D01*
G02X478620Y885352I-1298J0D01*
G01X478530Y885335D01*
X477723Y883938D01*
X477754Y883851D01*
G02X477826Y883423I-1225J-426D01*
G02X475232I-1297J0D01*
G02X476287Y884698I1298J0D01*
G01X476377Y884715D01*
G37*
G36*
G01X483777D02*
X484584Y886112D01*
X484553Y886199D01*
G02X484480Y886627I1225J429D01*
G02X487076I1298J0D01*
G02X486020Y885352I-1298J0D01*
G01X485930Y885335D01*
X485123Y883938D01*
X485154Y883851D01*
G02X485226Y883423I-1225J-426D01*
G02X482632I-1297J0D01*
G02X483687Y884698I1298J0D01*
G01X483777Y884715D01*
G37*
G36*
G01X491177D02*
X491984Y886112D01*
X491953Y886199D01*
G02X491880Y886627I1225J429D01*
G02X494476I1298J0D01*
G02X493420Y885352I-1298J0D01*
G01X493330Y885335D01*
X492523Y883938D01*
X492554Y883851D01*
G02X492626Y883423I-1225J-426D01*
G02X490032I-1297J0D01*
G02X491087Y884698I1298J0D01*
G01X491177Y884715D01*
G37*
G36*
G01X444266Y843894D02*
G02X443227Y843374I-1039J778D01*
G02Y845968I0J1297D01*
G02X444266Y845448I0J-1298D01*
G01X445888D01*
G02X446927Y845968I1039J-778D01*
G02Y843374I0J-1297D01*
G02X445888Y843894I0J1298D01*
G01X444266D01*
G37*
G36*
G01X400539Y842761D02*
X401380Y844356D01*
X401341Y844444D01*
G02X401230Y844971I1186J525D01*
G02X403824I1297J0D01*
G02X402762Y843695I-1298J0D01*
G01X402667Y843677D01*
X401826Y842082D01*
X401865Y841994D01*
G02X401976Y841467I-1186J-525D01*
G02X399382I-1297J0D01*
G02X400444Y842743I1298J0D01*
G01X400539Y842761D01*
G37*
G36*
G01X407939D02*
X408780Y844356D01*
X408741Y844444D01*
G02X408630Y844971I1186J525D01*
G02X411224I1297J0D01*
G02X410162Y843695I-1298J0D01*
G01X410067Y843677D01*
X409226Y842082D01*
X409265Y841994D01*
G02X409376Y841467I-1186J-525D01*
G02X406782I-1297J0D01*
G02X407844Y842743I1298J0D01*
G01X407939Y842761D01*
G37*
G36*
G01X415339D02*
X416180Y844356D01*
X416141Y844444D01*
G02X416030Y844971I1186J525D01*
G02X418624I1297J0D01*
G02X417562Y843695I-1298J0D01*
G01X417467Y843677D01*
X416626Y842082D01*
X416665Y841994D01*
G02X416776Y841467I-1186J-525D01*
G02X414182I-1297J0D01*
G02X415244Y842743I1298J0D01*
G01X415339Y842761D01*
G37*
G36*
G01X422739D02*
X423580Y844356D01*
X423541Y844444D01*
G02X423430Y844971I1186J525D01*
G02X426024I1297J0D01*
G02X424962Y843695I-1298J0D01*
G01X424867Y843677D01*
X424026Y842082D01*
X424065Y841994D01*
G02X424176Y841467I-1186J-525D01*
G02X421582I-1297J0D01*
G02X422644Y842743I1298J0D01*
G01X422739Y842761D01*
G37*
G36*
G01X405033Y845486D02*
X404226Y846884D01*
X404136Y846901D01*
G02X403080Y848176I242J1275D01*
G02X405676I1298J0D01*
G02X405603Y847747I-1297J0D01*
G01X405572Y847661D01*
X406379Y846263D01*
X406469Y846246D01*
G02X407524Y844971I-243J-1275D01*
G02X404930I-1297J0D01*
G02X405002Y845400I1297J3D01*
G01X405033Y845486D01*
G37*
G36*
G01X412433D02*
X411626Y846884D01*
X411536Y846901D01*
G02X410480Y848176I242J1275D01*
G02X413076I1298J0D01*
G02X413003Y847747I-1297J0D01*
G01X412972Y847661D01*
X413779Y846263D01*
X413869Y846246D01*
G02X414924Y844971I-243J-1275D01*
G02X412330I-1297J0D01*
G02X412402Y845400I1297J3D01*
G01X412433Y845486D01*
G37*
G36*
G01X419833D02*
X419026Y846884D01*
X418936Y846901D01*
G02X417880Y848176I242J1275D01*
G02X420476I1298J0D01*
G02X420403Y847747I-1297J0D01*
G01X420372Y847661D01*
X421179Y846263D01*
X421269Y846246D01*
G02X422324Y844971I-243J-1275D01*
G02X419730I-1297J0D01*
G02X419802Y845400I1297J3D01*
G01X419833Y845486D01*
G37*
G36*
G01X427233D02*
X426426Y846884D01*
X426336Y846901D01*
G02X425280Y848176I242J1275D01*
G02X427876I1298J0D01*
G02X427803Y847747I-1297J0D01*
G01X427772Y847661D01*
X428579Y846263D01*
X428669Y846246D01*
G02X429724Y844971I-243J-1275D01*
G02X427130I-1297J0D01*
G02X427202Y845400I1297J3D01*
G01X427233Y845486D01*
G37*
G36*
G01X431317Y847398D02*
G02X430278Y846878I-1039J778D01*
G02Y849474I0J1298D01*
G02X431317Y848954I0J-1298D01*
G01X432939D01*
G02X433978Y849474I1039J-778D01*
G02Y846878I0J-1298D01*
G02X432939Y847398I0J1298D01*
G01X431317D01*
G37*
G36*
G01X435689Y845965D02*
X436531Y847561D01*
X436492Y847650D01*
G02X436380Y848176I1186J527D01*
G02X438976I1298J0D01*
G02X437913Y846900I-1297J0D01*
G01X437818Y846882D01*
X436976Y845286D01*
X437015Y845197D01*
G02X437126Y844671I-1186J-525D01*
G02X434532I-1297J0D01*
G02X435594Y845947I1298J0D01*
G01X435689Y845965D01*
G37*
G36*
G01X449434Y845486D02*
X448626Y846884D01*
X448536Y846901D01*
G02X447480Y848176I242J1275D01*
G02X450076I1298J0D01*
G02X450003Y847748I-1298J1D01*
G01X449972Y847661D01*
X450780Y846263D01*
X450870Y846246D01*
G02X451926Y844971I-242J-1275D01*
G02X449330I-1298J0D01*
G02X449403Y845399I1298J-1D01*
G01X449434Y845486D01*
G37*
G36*
G01X406884Y855099D02*
X406077Y856497D01*
X405987Y856514D01*
G02X404932Y857789I243J1275D01*
G02X407526I1297J0D01*
G02X407454Y857360I-1297J-3D01*
G01X407423Y857274D01*
X408230Y855876D01*
X408320Y855859D01*
G02X409376Y854584I-242J-1275D01*
G02X406780I-1298J0D01*
G02X406853Y855013I1297J0D01*
G01X406884Y855099D01*
G37*
G36*
G01X414284D02*
X413477Y856497D01*
X413387Y856514D01*
G02X412332Y857789I243J1275D01*
G02X414926I1297J0D01*
G02X414854Y857360I-1297J-3D01*
G01X414823Y857274D01*
X415630Y855876D01*
X415720Y855859D01*
G02X416776Y854584I-242J-1275D01*
G02X414180I-1298J0D01*
G02X414253Y855013I1297J0D01*
G01X414284Y855099D01*
G37*
G36*
G01X421684D02*
X420877Y856497D01*
X420787Y856514D01*
G02X419732Y857789I243J1275D01*
G02X422326I1297J0D01*
G02X422254Y857360I-1297J-3D01*
G01X422223Y857274D01*
X423030Y855876D01*
X423120Y855859D01*
G02X424176Y854584I-242J-1275D01*
G02X421580I-1298J0D01*
G02X421653Y855013I1297J0D01*
G01X421684Y855099D01*
G37*
G36*
G01X429084D02*
X428277Y856497D01*
X428187Y856514D01*
G02X427132Y857789I243J1275D01*
G02X429726I1297J0D01*
G02X429654Y857360I-1297J-3D01*
G01X429623Y857274D01*
X430430Y855876D01*
X430520Y855859D01*
G02X431576Y854584I-242J-1275D01*
G02X428980I-1298J0D01*
G02X429053Y855013I1297J0D01*
G01X429084Y855099D01*
G37*
G36*
G01X436484Y855098D02*
X435677Y856497D01*
X435587Y856514D01*
G02X434532Y857789I243J1275D01*
G02X437126I1297J0D01*
G02X437054Y857360I-1297J-3D01*
G01X437023Y857274D01*
X437830Y855876D01*
X437920Y855859D01*
G02X438976Y854584I-242J-1275D01*
G02X436382I-1297J0D01*
G02X436454Y855012I1297J2D01*
G01X436484Y855098D01*
G37*
G36*
G01X444928Y855876D02*
X445735Y857274D01*
X445704Y857361D01*
G02X445632Y857789I1225J426D01*
G02X448226I1297J0D01*
G02X447171Y856514I-1298J0D01*
G01X447081Y856497D01*
X446273Y855098D01*
X446303Y855011D01*
G02X446376Y854584I-1225J-429D01*
G02X443780I-1298J0D01*
G02X444838Y855859I1297J0D01*
G01X444928Y855876D01*
G37*
G36*
G01X402377Y859081D02*
X403184Y860478D01*
X403153Y860565D01*
G02X403080Y860993I1225J429D01*
G02X405676I1298J0D01*
G02X404620Y859718I-1298J0D01*
G01X404530Y859701D01*
X403723Y858304D01*
X403754Y858217D01*
G02X403826Y857789I-1225J-426D01*
G02X401232I-1297J0D01*
G02X402287Y859064I1298J0D01*
G01X402377Y859081D01*
G37*
G36*
G01X409777D02*
X410584Y860478D01*
X410553Y860565D01*
G02X410480Y860993I1225J429D01*
G02X413076I1298J0D01*
G02X412020Y859718I-1298J0D01*
G01X411930Y859701D01*
X411123Y858304D01*
X411154Y858217D01*
G02X411226Y857789I-1225J-426D01*
G02X408632I-1297J0D01*
G02X409687Y859064I1298J0D01*
G01X409777Y859081D01*
G37*
G36*
G01X417177D02*
X417984Y860478D01*
X417953Y860565D01*
G02X417880Y860993I1225J429D01*
G02X420476I1298J0D01*
G02X419420Y859718I-1298J0D01*
G01X419330Y859701D01*
X418523Y858304D01*
X418554Y858217D01*
G02X418626Y857789I-1225J-426D01*
G02X416032I-1297J0D01*
G02X417087Y859064I1298J0D01*
G01X417177Y859081D01*
G37*
G36*
G01X424577D02*
X425384Y860478D01*
X425353Y860565D01*
G02X425280Y860993I1225J429D01*
G02X427876I1298J0D01*
G02X426820Y859718I-1298J0D01*
G01X426730Y859701D01*
X425923Y858304D01*
X425954Y858217D01*
G02X426026Y857789I-1225J-426D01*
G02X423432I-1297J0D01*
G02X424487Y859064I1298J0D01*
G01X424577Y859081D01*
G37*
G36*
G01X431978D02*
X432785Y860478D01*
X432754Y860565D01*
G02X432682Y860993I1225J426D01*
G02X435276I1297J0D01*
G02X434221Y859718I-1298J0D01*
G01X434131Y859701D01*
X433324Y858303D01*
X433354Y858217D01*
G02X433426Y857789I-1225J-426D01*
G02X430832I-1297J0D01*
G02X431888Y859064I1298J0D01*
G01X431978Y859081D01*
G37*
G36*
G01X442034Y858302D02*
X441226Y859701D01*
X441136Y859718D01*
G02X440080Y860993I242J1275D01*
G02X442676I1298J0D01*
G02X442603Y860564I-1297J0D01*
G01X442572Y860478D01*
X443378Y859081D01*
X443468Y859064D01*
G02X444526Y857789I-239J-1275D01*
G02X441932I-1297J0D01*
G02X442003Y858215I1297J3D01*
G01X442034Y858302D01*
G37*
G36*
G01X449434Y858303D02*
X448627Y859701D01*
X448537Y859718D01*
G02X447482Y860993I243J1275D01*
G02X450076I1297J0D01*
G02X450004Y860564I-1297J-3D01*
G01X449973Y860478D01*
X450779Y859081D01*
X450869Y859064D01*
G02X451926Y857789I-240J-1275D01*
G02X449332I-1297J0D01*
G02X449404Y858216I1297J1D01*
G01X449434Y858303D01*
G37*
G36*
G01X415328Y868693D02*
X416135Y870091D01*
X416104Y870178D01*
G02X416032Y870606I1225J426D01*
G02X418626I1297J0D01*
G02X417571Y869331I-1298J0D01*
G01X417481Y869314D01*
X416673Y867915D01*
X416703Y867828D01*
G02X416776Y867401I-1225J-429D01*
G02X414180I-1298J0D01*
G02X415238Y868676I1297J0D01*
G01X415328Y868693D01*
G37*
G36*
G01X422728D02*
X423535Y870091D01*
X423504Y870178D01*
G02X423432Y870606I1225J426D01*
G02X426026I1297J0D01*
G02X424971Y869331I-1298J0D01*
G01X424881Y869314D01*
X424073Y867915D01*
X424103Y867828D01*
G02X424176Y867401I-1225J-429D01*
G02X421580I-1298J0D01*
G02X422638Y868676I1297J0D01*
G01X422728Y868693D01*
G37*
G36*
G01X430128D02*
X430935Y870091D01*
X430904Y870178D01*
G02X430832Y870606I1225J426D01*
G02X433426I1297J0D01*
G02X432371Y869331I-1298J0D01*
G01X432281Y869314D01*
X431473Y867915D01*
X431503Y867828D01*
G02X431576Y867401I-1225J-429D01*
G02X428980I-1298J0D01*
G02X430038Y868676I1297J0D01*
G01X430128Y868693D01*
G37*
G36*
G01X437528D02*
X438335Y870091D01*
X438304Y870178D01*
G02X438232Y870606I1225J426D01*
G02X440826I1297J0D01*
G02X439771Y869331I-1298J0D01*
G01X439681Y869314D01*
X438873Y867915D01*
X438903Y867828D01*
G02X438976Y867401I-1225J-429D01*
G02X436380I-1298J0D01*
G02X437438Y868676I1297J0D01*
G01X437528Y868693D01*
G37*
G36*
G01X444928D02*
X445735Y870091D01*
X445704Y870178D01*
G02X445632Y870606I1225J426D01*
G02X448226I1297J0D01*
G02X447171Y869331I-1298J0D01*
G01X447081Y869314D01*
X446273Y867915D01*
X446303Y867828D01*
G02X446376Y867401I-1225J-429D01*
G02X443780I-1298J0D01*
G02X444838Y868676I1297J0D01*
G01X444928Y868693D01*
G37*
G36*
G01X412434Y871119D02*
X411626Y872518D01*
X411536Y872535D01*
G02X410480Y873810I242J1275D01*
G02X413076I1298J0D01*
G02X413003Y873381I-1297J0D01*
G01X412972Y873295D01*
X413778Y871898D01*
X413868Y871881D01*
G02X414926Y870606I-239J-1275D01*
G02X412332I-1297J0D01*
G02X412403Y871032I1297J3D01*
G01X412434Y871119D01*
G37*
G36*
G01X419834D02*
X419026Y872518D01*
X418936Y872535D01*
G02X417880Y873810I242J1275D01*
G02X420476I1298J0D01*
G02X420403Y873381I-1297J0D01*
G01X420372Y873295D01*
X421178Y871898D01*
X421268Y871881D01*
G02X422326Y870606I-239J-1275D01*
G02X419732I-1297J0D01*
G02X419803Y871032I1297J3D01*
G01X419834Y871119D01*
G37*
G36*
G01X427234D02*
X426426Y872518D01*
X426336Y872535D01*
G02X425280Y873810I242J1275D01*
G02X427876I1298J0D01*
G02X427803Y873381I-1297J0D01*
G01X427772Y873295D01*
X428578Y871898D01*
X428668Y871881D01*
G02X429726Y870606I-239J-1275D01*
G02X427132I-1297J0D01*
G02X427203Y871032I1297J3D01*
G01X427234Y871119D01*
G37*
G36*
G01X434634Y871120D02*
X433827Y872518D01*
X433737Y872535D01*
G02X432682Y873810I243J1275D01*
G02X435276I1297J0D01*
G02X435204Y873381I-1297J-3D01*
G01X435173Y873295D01*
X435979Y871898D01*
X436069Y871881D01*
G02X437126Y870606I-240J-1275D01*
G02X434532I-1297J0D01*
G02X434604Y871033I1297J1D01*
G01X434634Y871120D01*
G37*
G36*
G01X442034Y871119D02*
X441226Y872518D01*
X441136Y872535D01*
G02X440080Y873810I242J1275D01*
G02X442676I1298J0D01*
G02X442603Y873381I-1297J0D01*
G01X442572Y873295D01*
X443378Y871898D01*
X443468Y871881D01*
G02X444526Y870606I-239J-1275D01*
G02X441932I-1297J0D01*
G02X442003Y871032I1297J3D01*
G01X442034Y871119D01*
G37*
G36*
G01X449434Y871120D02*
X448627Y872518D01*
X448537Y872535D01*
G02X447482Y873810I243J1275D01*
G02X450076I1297J0D01*
G02X450004Y873381I-1297J-3D01*
G01X449973Y873295D01*
X450779Y871898D01*
X450869Y871881D01*
G02X451926Y870606I-240J-1275D01*
G02X449332I-1297J0D01*
G02X449404Y871033I1297J1D01*
G01X449434Y871120D01*
G37*
G36*
G01X414283Y880734D02*
X413477Y882131D01*
X413387Y882148D01*
G02X412332Y883423I243J1275D01*
G02X414926I1297J0D01*
G02X414854Y882994I-1297J-3D01*
G01X414823Y882908D01*
X415629Y881511D01*
X415719Y881494D01*
G02X416776Y880219I-240J-1275D01*
G02X414180I-1298J0D01*
G02X414253Y880647I1298J-1D01*
G01X414283Y880734D01*
G37*
G36*
G01X421683D02*
X420877Y882131D01*
X420787Y882148D01*
G02X419732Y883423I243J1275D01*
G02X422326I1297J0D01*
G02X422254Y882994I-1297J-3D01*
G01X422223Y882908D01*
X423029Y881511D01*
X423119Y881494D01*
G02X424176Y880219I-240J-1275D01*
G02X421580I-1298J0D01*
G02X421653Y880647I1298J-1D01*
G01X421683Y880734D01*
G37*
G36*
G01X429083D02*
X428277Y882131D01*
X428187Y882148D01*
G02X427132Y883423I243J1275D01*
G02X429726I1297J0D01*
G02X429654Y882994I-1297J-3D01*
G01X429623Y882908D01*
X430429Y881511D01*
X430519Y881494D01*
G02X431576Y880219I-240J-1275D01*
G02X428980I-1298J0D01*
G02X429053Y880647I1298J-1D01*
G01X429083Y880734D01*
G37*
G36*
G01X436483D02*
X435677Y882131D01*
X435587Y882148D01*
G02X434532Y883423I243J1275D01*
G02X437126I1297J0D01*
G02X437054Y882994I-1297J-3D01*
G01X437023Y882908D01*
X437829Y881511D01*
X437919Y881494D01*
G02X438976Y880219I-240J-1275D01*
G02X436380I-1298J0D01*
G02X436453Y880647I1298J-1D01*
G01X436483Y880734D01*
G37*
G36*
G01X443883D02*
X443077Y882131D01*
X442987Y882148D01*
G02X441932Y883423I243J1275D01*
G02X444526I1297J0D01*
G02X444454Y882994I-1297J-3D01*
G01X444423Y882908D01*
X445229Y881511D01*
X445319Y881494D01*
G02X446376Y880219I-240J-1275D01*
G02X443780I-1298J0D01*
G02X443853Y880647I1298J-1D01*
G01X443883Y880734D01*
G37*
G36*
G01X409777Y884715D02*
X410584Y886112D01*
X410553Y886199D01*
G02X410480Y886627I1225J429D01*
G02X413076I1298J0D01*
G02X412020Y885352I-1298J0D01*
G01X411930Y885335D01*
X411123Y883938D01*
X411154Y883851D01*
G02X411226Y883423I-1225J-426D01*
G02X408632I-1297J0D01*
G02X409687Y884698I1298J0D01*
G01X409777Y884715D01*
G37*
G36*
G01X417177D02*
X417984Y886112D01*
X417953Y886199D01*
G02X417880Y886627I1225J429D01*
G02X420476I1298J0D01*
G02X419420Y885352I-1298J0D01*
G01X419330Y885335D01*
X418523Y883938D01*
X418554Y883851D01*
G02X418626Y883423I-1225J-426D01*
G02X416032I-1297J0D01*
G02X417087Y884698I1298J0D01*
G01X417177Y884715D01*
G37*
G36*
G01X424577D02*
X425384Y886112D01*
X425353Y886199D01*
G02X425280Y886627I1225J429D01*
G02X427876I1298J0D01*
G02X426820Y885352I-1298J0D01*
G01X426730Y885335D01*
X425923Y883938D01*
X425954Y883851D01*
G02X426026Y883423I-1225J-426D01*
G02X423432I-1297J0D01*
G02X424487Y884698I1298J0D01*
G01X424577Y884715D01*
G37*
G36*
G01X431977D02*
X432784Y886112D01*
X432753Y886199D01*
G02X432680Y886627I1225J429D01*
G02X435276I1298J0D01*
G02X434220Y885352I-1298J0D01*
G01X434130Y885335D01*
X433323Y883938D01*
X433354Y883851D01*
G02X433426Y883423I-1225J-426D01*
G02X430832I-1297J0D01*
G02X431887Y884698I1298J0D01*
G01X431977Y884715D01*
G37*
G36*
G01X439377D02*
X440184Y886112D01*
X440153Y886199D01*
G02X440080Y886627I1225J429D01*
G02X442676I1298J0D01*
G02X441620Y885352I-1298J0D01*
G01X441530Y885335D01*
X440723Y883938D01*
X440754Y883851D01*
G02X440826Y883423I-1225J-426D01*
G02X438232I-1297J0D01*
G02X439287Y884698I1298J0D01*
G01X439377Y884715D01*
G37*
G36*
G01X446777D02*
X447584Y886112D01*
X447553Y886199D01*
G02X447480Y886627I1225J429D01*
G02X450076I1298J0D01*
G02X449020Y885352I-1298J0D01*
G01X448930Y885335D01*
X448123Y883938D01*
X448154Y883851D01*
G02X448226Y883423I-1225J-426D01*
G02X445632I-1297J0D01*
G02X446687Y884698I1298J0D01*
G01X446777Y884715D01*
G37*
G36*
G01X356139Y842761D02*
X356980Y844356D01*
X356941Y844444D01*
G02X356830Y844971I1186J525D01*
G02X359424I1297J0D01*
G02X358362Y843695I-1298J0D01*
G01X358267Y843677D01*
X357426Y842082D01*
X357465Y841994D01*
G02X357576Y841467I-1186J-525D01*
G02X354982I-1297J0D01*
G02X356044Y842743I1298J0D01*
G01X356139Y842761D01*
G37*
G36*
G01X363539D02*
X364380Y844356D01*
X364341Y844444D01*
G02X364230Y844971I1186J525D01*
G02X366824I1297J0D01*
G02X365762Y843695I-1298J0D01*
G01X365667Y843677D01*
X364826Y842082D01*
X364865Y841994D01*
G02X364976Y841467I-1186J-525D01*
G02X362382I-1297J0D01*
G02X363444Y842743I1298J0D01*
G01X363539Y842761D01*
G37*
G36*
G01X370939D02*
X371780Y844356D01*
X371741Y844444D01*
G02X371630Y844971I1186J525D01*
G02X374224I1297J0D01*
G02X373162Y843695I-1298J0D01*
G01X373067Y843677D01*
X372226Y842082D01*
X372265Y841994D01*
G02X372376Y841467I-1186J-525D01*
G02X369782I-1297J0D01*
G02X370844Y842743I1298J0D01*
G01X370939Y842761D01*
G37*
G36*
G01X378339D02*
X379180Y844356D01*
X379141Y844444D01*
G02X379030Y844971I1186J525D01*
G02X381624I1297J0D01*
G02X380562Y843695I-1298J0D01*
G01X380467Y843677D01*
X379626Y842082D01*
X379665Y841994D01*
G02X379776Y841467I-1186J-525D01*
G02X377182I-1297J0D01*
G02X378244Y842743I1298J0D01*
G01X378339Y842761D01*
G37*
G36*
G01X385739D02*
X386580Y844356D01*
X386541Y844444D01*
G02X386430Y844971I1186J525D01*
G02X389024I1297J0D01*
G02X387962Y843695I-1298J0D01*
G01X387867Y843677D01*
X387026Y842082D01*
X387065Y841994D01*
G02X387176Y841467I-1186J-525D01*
G02X384582I-1297J0D01*
G02X385644Y842743I1298J0D01*
G01X385739Y842761D01*
G37*
G36*
G01X353233Y845486D02*
X352426Y846884D01*
X352336Y846901D01*
G02X351280Y848176I242J1275D01*
G02X353876I1298J0D01*
G02X353803Y847747I-1297J0D01*
G01X353772Y847661D01*
X354579Y846263D01*
X354669Y846246D01*
G02X355724Y844971I-243J-1275D01*
G02X353130I-1297J0D01*
G02X353202Y845400I1297J3D01*
G01X353233Y845486D01*
G37*
G36*
G01X360633D02*
X359826Y846884D01*
X359736Y846901D01*
G02X358680Y848176I242J1275D01*
G02X361276I1298J0D01*
G02X361203Y847747I-1297J0D01*
G01X361172Y847661D01*
X361979Y846263D01*
X362069Y846246D01*
G02X363124Y844971I-243J-1275D01*
G02X360530I-1297J0D01*
G02X360602Y845400I1297J3D01*
G01X360633Y845486D01*
G37*
G36*
G01X368033D02*
X367226Y846884D01*
X367136Y846901D01*
G02X366080Y848176I242J1275D01*
G02X368676I1298J0D01*
G02X368603Y847747I-1297J0D01*
G01X368572Y847661D01*
X369379Y846263D01*
X369469Y846246D01*
G02X370524Y844971I-243J-1275D01*
G02X367930I-1297J0D01*
G02X368002Y845400I1297J3D01*
G01X368033Y845486D01*
G37*
G36*
G01X375433D02*
X374626Y846884D01*
X374536Y846901D01*
G02X373480Y848176I242J1275D01*
G02X376076I1298J0D01*
G02X376003Y847747I-1297J0D01*
G01X375972Y847661D01*
X376779Y846263D01*
X376869Y846246D01*
G02X377924Y844971I-243J-1275D01*
G02X375330I-1297J0D01*
G02X375402Y845400I1297J3D01*
G01X375433Y845486D01*
G37*
G36*
G01X382833D02*
X382026Y846884D01*
X381936Y846901D01*
G02X380880Y848176I242J1275D01*
G02X383476I1298J0D01*
G02X383403Y847747I-1297J0D01*
G01X383372Y847661D01*
X384179Y846263D01*
X384269Y846246D01*
G02X385324Y844971I-243J-1275D01*
G02X382730I-1297J0D01*
G02X382802Y845400I1297J3D01*
G01X382833Y845486D01*
G37*
G36*
G01X390233D02*
X389426Y846884D01*
X389336Y846901D01*
G02X388280Y848176I242J1275D01*
G02X390876I1298J0D01*
G02X390803Y847747I-1297J0D01*
G01X390772Y847661D01*
X391579Y846263D01*
X391669Y846246D01*
G02X392724Y844971I-243J-1275D01*
G02X390130I-1297J0D01*
G02X390202Y845400I1297J3D01*
G01X390233Y845486D01*
G37*
G36*
G01X348726Y849468D02*
X349533Y850865D01*
X349502Y850952D01*
G02X349430Y851380I1225J426D01*
G02X352024I1297J0D01*
G02X350969Y850105I-1298J0D01*
G01X350879Y850088D01*
X350072Y848691D01*
X350103Y848604D01*
G02X350176Y848176I-1225J-429D01*
G02X347580I-1298J0D01*
G02X348636Y849451I1298J0D01*
G01X348726Y849468D01*
G37*
G36*
G01X384684Y855099D02*
X383877Y856497D01*
X383787Y856514D01*
G02X382732Y857789I243J1275D01*
G02X385326I1297J0D01*
G02X385254Y857360I-1297J-3D01*
G01X385223Y857274D01*
X386030Y855876D01*
X386120Y855859D01*
G02X387176Y854584I-242J-1275D01*
G02X384580I-1298J0D01*
G02X384653Y855013I1297J0D01*
G01X384684Y855099D01*
G37*
G36*
G01X392084D02*
X391277Y856497D01*
X391187Y856514D01*
G02X390132Y857789I243J1275D01*
G02X392726I1297J0D01*
G02X392654Y857360I-1297J-3D01*
G01X392623Y857274D01*
X393430Y855876D01*
X393520Y855859D01*
G02X394576Y854584I-242J-1275D01*
G02X391980I-1298J0D01*
G02X392053Y855013I1297J0D01*
G01X392084Y855099D01*
G37*
G36*
G01X380177Y859081D02*
X380984Y860478D01*
X380953Y860565D01*
G02X380880Y860993I1225J429D01*
G02X383476I1298J0D01*
G02X382420Y859718I-1298J0D01*
G01X382330Y859701D01*
X381523Y858304D01*
X381554Y858217D01*
G02X381626Y857789I-1225J-426D01*
G02X379032I-1297J0D01*
G02X380087Y859064I1298J0D01*
G01X380177Y859081D01*
G37*
G36*
G01X387577D02*
X388384Y860478D01*
X388353Y860565D01*
G02X388280Y860993I1225J429D01*
G02X390876I1298J0D01*
G02X389820Y859718I-1298J0D01*
G01X389730Y859701D01*
X388923Y858304D01*
X388954Y858217D01*
G02X389026Y857789I-1225J-426D01*
G02X386432I-1297J0D01*
G02X387487Y859064I1298J0D01*
G01X387577Y859081D01*
G37*
G36*
G01X392084Y867916D02*
X391277Y869314D01*
X391187Y869331D01*
G02X390132Y870606I243J1275D01*
G02X392726I1297J0D01*
G02X392654Y870177I-1297J-3D01*
G01X392623Y870091D01*
X393430Y868693D01*
X393520Y868676D01*
G02X394576Y867401I-242J-1275D01*
G02X391980I-1298J0D01*
G02X392053Y867830I1297J0D01*
G01X392084Y867916D01*
G37*
G36*
G01X387577Y871898D02*
X388384Y873295D01*
X388353Y873382D01*
G02X388280Y873810I1225J429D01*
G02X390876I1298J0D01*
G02X389820Y872535I-1298J0D01*
G01X389730Y872518D01*
X388923Y871121D01*
X388954Y871034D01*
G02X389026Y870606I-1225J-426D01*
G02X386432I-1297J0D01*
G02X387487Y871881I1298J0D01*
G01X387577Y871898D01*
G37*
G36*
G01X394977D02*
X395784Y873295D01*
X395753Y873382D01*
G02X395680Y873810I1225J429D01*
G02X398276I1298J0D01*
G02X397220Y872535I-1298J0D01*
G01X397130Y872518D01*
X396323Y871121D01*
X396354Y871034D01*
G02X396426Y870606I-1225J-426D01*
G02X393832I-1297J0D01*
G02X394887Y871881I1298J0D01*
G01X394977Y871898D01*
G37*
G36*
G01X392083Y880734D02*
X391277Y882131D01*
X391187Y882148D01*
G02X390132Y883423I243J1275D01*
G02X392726I1297J0D01*
G02X392654Y882994I-1297J-3D01*
G01X392623Y882908D01*
X393429Y881511D01*
X393519Y881494D01*
G02X394576Y880219I-240J-1275D01*
G02X391980I-1298J0D01*
G02X392053Y880647I1298J-1D01*
G01X392083Y880734D01*
G37*
G36*
G01X399483D02*
X398677Y882131D01*
X398587Y882148D01*
G02X397532Y883423I243J1275D01*
G02X400126I1297J0D01*
G02X400054Y882994I-1297J-3D01*
G01X400023Y882908D01*
X400829Y881511D01*
X400919Y881494D01*
G02X401976Y880219I-240J-1275D01*
G02X399380I-1298J0D01*
G02X399453Y880647I1298J-1D01*
G01X399483Y880734D01*
G37*
G36*
G01X387577Y884715D02*
X388384Y886112D01*
X388353Y886199D01*
G02X388280Y886627I1225J429D01*
G02X390876I1298J0D01*
G02X389820Y885352I-1298J0D01*
G01X389730Y885335D01*
X388923Y883938D01*
X388954Y883851D01*
G02X389026Y883423I-1225J-426D01*
G02X386432I-1297J0D01*
G02X387487Y884698I1298J0D01*
G01X387577Y884715D01*
G37*
G36*
G01X394977D02*
X395784Y886112D01*
X395753Y886199D01*
G02X395680Y886627I1225J429D01*
G02X398276I1298J0D01*
G02X397220Y885352I-1298J0D01*
G01X397130Y885335D01*
X396323Y883938D01*
X396354Y883851D01*
G02X396426Y883423I-1225J-426D01*
G02X393832I-1297J0D01*
G02X394887Y884698I1298J0D01*
G01X394977Y884715D01*
G37*
G36*
G01X428710Y1077879D02*
X429517Y1079276D01*
X429486Y1079363D01*
G02X429414Y1079791I1225J426D01*
G02X432008I1297J0D01*
G02X430953Y1078516I-1298J0D01*
G01X430863Y1078499D01*
X430056Y1077101D01*
X430086Y1077015D01*
G02X430158Y1076587I-1225J-426D01*
G02X427564I-1297J0D01*
G02X428620Y1077862I1298J0D01*
G01X428710Y1077879D01*
G37*
G36*
G01X429516Y1086715D02*
X428709Y1088112D01*
X428619Y1088129D01*
G02X427564Y1089404I243J1275D01*
G02X430158I1297J0D01*
G02X430086Y1088976I-1297J-2D01*
G01X430055Y1088889D01*
X430862Y1087492D01*
X430952Y1087475D01*
G02X432008Y1086200I-242J-1275D01*
G02X429412I-1298J0D01*
G02X429485Y1086629I1297J0D01*
G01X429516Y1086715D01*
G37*
G36*
G01X473965Y1138083D02*
X473121Y1139679D01*
X473026Y1139697D01*
G02X471964Y1140973I236J1276D01*
G02X474558I1297J0D01*
G02X474447Y1140448I-1297J0D01*
G01X474408Y1140359D01*
X475252Y1138763D01*
X475347Y1138745D01*
G02X476410Y1137469I-234J-1276D01*
G02X473814I-1298J0D01*
G02X473926Y1137994I1297J-2D01*
G01X473965Y1138083D01*
G37*
G36*
G01X517883Y880733D02*
X517077Y882131D01*
X516987Y882148D01*
G02X515932Y883423I243J1275D01*
G02X518526I1297J0D01*
G01Y883421D01*
G02X518454Y882994I-1298J-1D01*
G01X518424Y882908D01*
X519230Y881511D01*
X519320Y881494D01*
G02X520376Y880219I-242J-1275D01*
G02X517780I-1298J0D01*
G02X517853Y880647I1299J-1D01*
G01X517883Y880733D01*
G37*
G36*
G01X523433Y871118D02*
X522626Y872518D01*
X522536Y872535D01*
G02X521480Y873810I242J1275D01*
G02X524076I1298J0D01*
G01Y873808D01*
G02X524003Y873381I-1298J2D01*
G01X523973Y873295D01*
X524779Y871898D01*
X524869Y871881D01*
G02X525926Y870606I-240J-1275D01*
G02X523332I-1297J0D01*
G01Y870607D01*
G02X523403Y871032I1297J2D01*
G01X523433Y871118D01*
G37*
G36*
G01X528954Y886198D02*
G02X528882Y886625I1226J426D01*
G01Y886627D01*
G02X531476I1297J0D01*
G02X530421Y885352I-1298J0D01*
G01X530331Y885335D01*
X529524Y883937D01*
X529554Y883851D01*
G02X529626Y883423I-1226J-426D01*
G02X527032I-1297J0D01*
G02X528088Y884698I1298J0D01*
G01X528178Y884715D01*
X528984Y886112D01*
X528954Y886198D01*
G37*
G36*
G01X525284Y880732D02*
X524477Y882131D01*
X524387Y882148D01*
G02X523332Y883423I243J1275D01*
G02X525926I1297J0D01*
G01Y883421D01*
G02X525854Y882994I-1298J-1D01*
G01X525824Y882908D01*
X526630Y881511D01*
X526720Y881494D01*
G02X527776Y880219I-242J-1275D01*
G02X525182I-1297J0D01*
G02X525254Y880646I1297J1D01*
G01X525284Y880732D01*
G37*
G36*
G01X530833Y871118D02*
X530026Y872518D01*
X529936Y872535D01*
G02X528880Y873810I242J1275D01*
G02X531476I1298J0D01*
G01Y873808D01*
G02X531403Y873381I-1298J2D01*
G01X531373Y873295D01*
X532179Y871898D01*
X532269Y871881D01*
G02X533326Y870606I-240J-1275D01*
G02X530732I-1297J0D01*
G01Y870607D01*
G02X530803Y871032I1297J2D01*
G01X530833Y871118D01*
G37*
G36*
G01X511528Y855876D02*
X512335Y857274D01*
X512304Y857361D01*
G02X512232Y857789I1225J426D01*
G02X514826I1297J0D01*
G02X513771Y856514I-1298J0D01*
G01X513681Y856497D01*
X512873Y855098D01*
X512903Y855011D01*
G02X512976Y854584I-1225J-429D01*
G02X510380I-1298J0D01*
G02X511438Y855859I1297J0D01*
G01X511528Y855876D01*
G37*
G36*
G01X518928D02*
X519735Y857274D01*
X519704Y857361D01*
G02X519632Y857789I1225J426D01*
G02X522226I1297J0D01*
G02X521171Y856514I-1298J0D01*
G01X521081Y856497D01*
X520273Y855098D01*
X520303Y855011D01*
G02X520376Y854584I-1225J-429D01*
G02X517780I-1298J0D01*
G02X518838Y855859I1297J0D01*
G01X518928Y855876D01*
G37*
G36*
G01X526328D02*
X527135Y857274D01*
X527104Y857361D01*
G02X527032Y857789I1225J426D01*
G02X529626I1297J0D01*
G02X528571Y856514I-1298J0D01*
G01X528481Y856497D01*
X527673Y855098D01*
X527703Y855011D01*
G02X527776Y854584I-1225J-429D01*
G02X525180I-1298J0D01*
G02X526238Y855859I1297J0D01*
G01X526328Y855876D01*
G37*
G36*
G01X508634Y858302D02*
X507826Y859701D01*
X507736Y859718D01*
G02X506680Y860993I242J1275D01*
G02X509276I1298J0D01*
G02X509203Y860564I-1297J0D01*
G01X509172Y860478D01*
X509978Y859081D01*
X510068Y859064D01*
G02X511126Y857789I-239J-1275D01*
G02X508532I-1297J0D01*
G02X508603Y858215I1297J3D01*
G01X508634Y858302D01*
G37*
G36*
G01X516034D02*
X515226Y859701D01*
X515136Y859718D01*
G02X514080Y860993I242J1275D01*
G02X516676I1298J0D01*
G02X516603Y860564I-1297J0D01*
G01X516572Y860478D01*
X517378Y859081D01*
X517468Y859064D01*
G02X518526Y857789I-239J-1275D01*
G02X515932I-1297J0D01*
G02X516003Y858215I1297J3D01*
G01X516034Y858302D01*
G37*
G36*
G01X523434D02*
X522626Y859701D01*
X522536Y859718D01*
G02X521480Y860993I242J1275D01*
G02X524076I1298J0D01*
G02X524003Y860564I-1297J0D01*
G01X523972Y860478D01*
X524778Y859081D01*
X524868Y859064D01*
G02X525926Y857789I-239J-1275D01*
G02X523332I-1297J0D01*
G02X523403Y858215I1297J3D01*
G01X523434Y858302D01*
G37*
G36*
G01X511528Y868693D02*
X512335Y870091D01*
X512304Y870178D01*
G02X512232Y870606I1225J426D01*
G02X514826I1297J0D01*
G02X513771Y869331I-1298J0D01*
G01X513681Y869314D01*
X512873Y867915D01*
X512903Y867828D01*
G02X512976Y867401I-1225J-429D01*
G02X510380I-1298J0D01*
G02X511438Y868676I1297J0D01*
G01X511528Y868693D01*
G37*
G36*
G01X518928D02*
X519735Y870091D01*
X519704Y870178D01*
G02X519632Y870606I1225J426D01*
G02X522226I1297J0D01*
G02X521171Y869331I-1298J0D01*
G01X521081Y869314D01*
X520273Y867915D01*
X520303Y867828D01*
G02X520376Y867401I-1225J-429D01*
G02X517780I-1298J0D01*
G02X518838Y868676I1297J0D01*
G01X518928Y868693D01*
G37*
G36*
G01X526328D02*
X527135Y870091D01*
X527104Y870178D01*
G02X527032Y870606I1225J426D01*
G02X529626I1297J0D01*
G02X528571Y869331I-1298J0D01*
G01X528481Y869314D01*
X527674Y867916D01*
X527704Y867829D01*
G02X527776Y867401I-1225J-426D01*
G02X525182I-1297J0D01*
G02X526238Y868676I1298J0D01*
G01X526328Y868693D01*
G37*
G36*
G01X508634Y871119D02*
X507826Y872518D01*
X507736Y872535D01*
G02X506680Y873810I242J1275D01*
G02X509276I1298J0D01*
G02X509203Y873381I-1297J0D01*
G01X509172Y873295D01*
X509978Y871898D01*
X510068Y871881D01*
G02X511126Y870606I-239J-1275D01*
G02X508532I-1297J0D01*
G02X508603Y871032I1297J3D01*
G01X508634Y871119D01*
G37*
G36*
G01X516034D02*
X515226Y872518D01*
X515136Y872535D01*
G02X514080Y873810I242J1275D01*
G02X516676I1298J0D01*
G02X516603Y873381I-1297J0D01*
G01X516572Y873295D01*
X517378Y871898D01*
X517468Y871881D01*
G02X518526Y870606I-239J-1275D01*
G02X515932I-1297J0D01*
G02X516003Y871032I1297J3D01*
G01X516034Y871119D01*
G37*
G36*
G01X510483Y880734D02*
X509677Y882131D01*
X509587Y882148D01*
G02X508532Y883423I243J1275D01*
G02X511126I1297J0D01*
G02X511054Y882994I-1297J-3D01*
G01X511023Y882908D01*
X511829Y881511D01*
X511919Y881494D01*
G02X512976Y880219I-240J-1275D01*
G02X510380I-1298J0D01*
G02X510453Y880647I1298J-1D01*
G01X510483Y880734D01*
G37*
G36*
G01X505977Y884715D02*
X506784Y886112D01*
X506753Y886199D01*
G02X506680Y886627I1225J429D01*
G02X509276I1298J0D01*
G02X508220Y885352I-1298J0D01*
G01X508130Y885335D01*
X507323Y883938D01*
X507354Y883851D01*
G02X507426Y883423I-1225J-426D01*
G02X504832I-1297J0D01*
G02X505887Y884698I1298J0D01*
G01X505977Y884715D01*
G37*
G36*
G01X513377D02*
X514184Y886112D01*
X514153Y886199D01*
G02X514080Y886627I1225J429D01*
G02X516676I1298J0D01*
G02X515620Y885352I-1298J0D01*
G01X515530Y885335D01*
X514723Y883938D01*
X514754Y883851D01*
G02X514826Y883423I-1225J-426D01*
G02X512232I-1297J0D01*
G02X513287Y884698I1298J0D01*
G01X513377Y884715D01*
G37*
G36*
G01X520777D02*
X521584Y886112D01*
X521553Y886199D01*
G02X521480Y886627I1225J429D01*
G02X524076I1298J0D01*
G02X523020Y885352I-1298J0D01*
G01X522930Y885335D01*
X522123Y883938D01*
X522154Y883851D01*
G02X522226Y883423I-1225J-426D01*
G02X519632I-1297J0D01*
G02X520687Y884698I1298J0D01*
G01X520777Y884715D01*
G37*
G36*
G01X476810Y1122739D02*
X477617Y1124136D01*
X477586Y1124223D01*
G02X477514Y1124651I1225J426D01*
G02X480108I1297J0D01*
G02X479053Y1123376I-1298J0D01*
G01X478963Y1123359D01*
X478156Y1121962D01*
X478187Y1121875D01*
G02X478260Y1121447I-1225J-429D01*
G02X475664I-1298J0D01*
G02X476720Y1122722I1298J0D01*
G01X476810Y1122739D01*
G37*
G36*
G01X484210D02*
X485017Y1124136D01*
X484986Y1124223D01*
G02X484914Y1124651I1225J426D01*
G02X487508I1297J0D01*
G02X486453Y1123376I-1298J0D01*
G01X486363Y1123359D01*
X485556Y1121962D01*
X485587Y1121875D01*
G02X485660Y1121447I-1225J-429D01*
G02X483064I-1298J0D01*
G02X484120Y1122722I1298J0D01*
G01X484210Y1122739D01*
G37*
G36*
G01X491610D02*
X492417Y1124136D01*
X492386Y1124223D01*
G02X492314Y1124651I1225J426D01*
G02X494908I1297J0D01*
G02X493853Y1123376I-1298J0D01*
G01X493763Y1123359D01*
X492956Y1121962D01*
X492987Y1121875D01*
G02X493060Y1121447I-1225J-429D01*
G02X490464I-1298J0D01*
G02X491520Y1122722I1298J0D01*
G01X491610Y1122739D01*
G37*
G36*
G01X499010D02*
X499817Y1124136D01*
X499786Y1124223D01*
G02X499714Y1124651I1225J426D01*
G02X502308I1297J0D01*
G02X501253Y1123376I-1298J0D01*
G01X501163Y1123359D01*
X500356Y1121962D01*
X500387Y1121875D01*
G02X500460Y1121447I-1225J-429D01*
G02X497864I-1298J0D01*
G02X498920Y1122722I1298J0D01*
G01X499010Y1122739D01*
G37*
G36*
G01X506410D02*
X507217Y1124136D01*
X507186Y1124223D01*
G02X507114Y1124651I1225J426D01*
G02X509708I1297J0D01*
G02X508653Y1123376I-1298J0D01*
G01X508563Y1123359D01*
X507756Y1121962D01*
X507787Y1121875D01*
G02X507860Y1121447I-1225J-429D01*
G02X505264I-1298J0D01*
G02X506320Y1122722I1298J0D01*
G01X506410Y1122739D01*
G37*
G36*
G01X513810D02*
X514617Y1124136D01*
X514586Y1124223D01*
G02X514514Y1124651I1225J426D01*
G02X517108I1297J0D01*
G02X516053Y1123376I-1298J0D01*
G01X515963Y1123359D01*
X515156Y1121962D01*
X515187Y1121875D01*
G02X515260Y1121447I-1225J-429D01*
G02X512664I-1298J0D01*
G02X513720Y1122722I1298J0D01*
G01X513810Y1122739D01*
G37*
G36*
G01X521210D02*
X522017Y1124136D01*
X521986Y1124223D01*
G02X521914Y1124651I1225J426D01*
G02X524508I1297J0D01*
G02X523453Y1123376I-1298J0D01*
G01X523363Y1123359D01*
X522556Y1121962D01*
X522587Y1121875D01*
G02X522660Y1121447I-1225J-429D01*
G02X520064I-1298J0D01*
G02X521120Y1122722I1298J0D01*
G01X521210Y1122739D01*
G37*
G36*
G01X481317Y1125166D02*
X480510Y1126564D01*
X480420Y1126581D01*
G02X479364Y1127856I242J1275D01*
G02X481960I1298J0D01*
G02X481887Y1127427I-1297J0D01*
G01X481856Y1127341D01*
X482663Y1125943D01*
X482753Y1125926D01*
G02X483808Y1124651I-243J-1275D01*
G02X481214I-1297J0D01*
G02X481286Y1125080I1297J3D01*
G01X481317Y1125166D01*
G37*
G36*
G01X488717D02*
X487910Y1126564D01*
X487820Y1126581D01*
G02X486764Y1127856I242J1275D01*
G02X489360I1298J0D01*
G02X489287Y1127427I-1297J0D01*
G01X489256Y1127341D01*
X490063Y1125943D01*
X490153Y1125926D01*
G02X491208Y1124651I-243J-1275D01*
G02X488614I-1297J0D01*
G02X488686Y1125080I1297J3D01*
G01X488717Y1125166D01*
G37*
G36*
G01X496117D02*
X495310Y1126564D01*
X495220Y1126581D01*
G02X494164Y1127856I242J1275D01*
G02X496760I1298J0D01*
G02X496687Y1127427I-1297J0D01*
G01X496656Y1127341D01*
X497463Y1125943D01*
X497553Y1125926D01*
G02X498608Y1124651I-243J-1275D01*
G02X496014I-1297J0D01*
G02X496086Y1125080I1297J3D01*
G01X496117Y1125166D01*
G37*
G36*
G01X503517D02*
X502710Y1126564D01*
X502620Y1126581D01*
G02X501564Y1127856I242J1275D01*
G02X504160I1298J0D01*
G02X504087Y1127427I-1297J0D01*
G01X504056Y1127341D01*
X504863Y1125943D01*
X504953Y1125926D01*
G02X506008Y1124651I-243J-1275D01*
G02X503414I-1297J0D01*
G02X503486Y1125080I1297J3D01*
G01X503517Y1125166D01*
G37*
G36*
G01X510917D02*
X510110Y1126564D01*
X510020Y1126581D01*
G02X508964Y1127856I242J1275D01*
G02X511560I1298J0D01*
G02X511487Y1127427I-1297J0D01*
G01X511456Y1127341D01*
X512263Y1125943D01*
X512353Y1125926D01*
G02X513408Y1124651I-243J-1275D01*
G02X510814I-1297J0D01*
G02X510886Y1125080I1297J3D01*
G01X510917Y1125166D01*
G37*
G36*
G01X518317D02*
X517510Y1126564D01*
X517420Y1126581D01*
G02X516364Y1127856I242J1275D01*
G02X518960I1298J0D01*
G02X518887Y1127427I-1297J0D01*
G01X518856Y1127341D01*
X519663Y1125943D01*
X519753Y1125926D01*
G02X520808Y1124651I-243J-1275D01*
G02X518214I-1297J0D01*
G02X518286Y1125080I1297J3D01*
G01X518317Y1125166D01*
G37*
G36*
G01X525717D02*
X524910Y1126564D01*
X524820Y1126581D01*
G02X523764Y1127856I242J1275D01*
G02X526360I1298J0D01*
G02X526287Y1127427I-1297J0D01*
G01X526256Y1127341D01*
X527063Y1125943D01*
X527153Y1125926D01*
G02X528208Y1124651I-243J-1275D01*
G02X525614I-1297J0D01*
G02X525686Y1125080I1297J3D01*
G01X525717Y1125166D01*
G37*
G36*
G01X1422586Y1378172D02*
X1430753Y1386339D01*
G02X1431460Y1386632I707J-706D01*
G01X1448630D01*
G02X1449337Y1386339I0J-999D01*
G01X1456026Y1379650D01*
X1526194D01*
G02X1526901Y1379357I0J-999D01*
G01X1540629Y1365629D01*
G02X1540922Y1364922I-706J-707D01*
G01Y1350313D01*
G02X1540629Y1349606I-999J0D01*
G01X1539436Y1348413D01*
G02X1538729Y1348120I-707J706D01*
G01X1528555D01*
X1528500Y1348008D01*
G02X1525864I-1318J642D01*
G01X1525809Y1348120D01*
X1520113D01*
X1520059Y1348007D01*
G02X1518738Y1347179I-1321J640D01*
G02X1517717Y1347593I0J1466D01*
G03X1517159I-279J-287D01*
G02X1516138Y1347179I-1021J1052D01*
G02X1514817Y1348007I0J1468D01*
G01X1514763Y1348120D01*
X1513566D01*
X1511891Y1346445D01*
G02X1512205Y1345539I-1153J-907D01*
G02X1511438Y1344250I-1467J0D01*
G01Y1343721D01*
G02Y1341143I-700J-1289D01*
G01Y1322503D01*
G02X1511145Y1321796I-999J0D01*
G01X1505768Y1316419D01*
G02X1505061Y1316126I-707J706D01*
G01X1479860D01*
X1478168Y1314434D01*
Y1305701D01*
G02X1477875Y1304994I-999J0D01*
G01X1476040Y1303159D01*
G02X1475333Y1302866I-707J706D01*
G01X1469667D01*
G02X1468296Y1301978I-1371J614D01*
G02X1467269Y1302384I0J1502D01*
G03X1466723I-273J-292D01*
G02X1465696Y1301978I-1027J1096D01*
G02X1464325Y1302866I0J1502D01*
G01X1437891D01*
X1437849Y1302845D01*
G02X1437182Y1302689I-667J1346D01*
G02X1436515Y1302845I0J1502D01*
G01X1436473Y1302866D01*
X1435291D01*
X1435249Y1302845D01*
G02X1434582Y1302689I-667J1346D01*
G02X1433915Y1302845I0J1502D01*
G01X1433873Y1302866D01*
X1409774D01*
X1409723Y1302743D01*
G02X1406949I-1387J576D01*
G01X1406898Y1302866D01*
X1405411D01*
G02X1404040Y1301978I-1371J614D01*
G02X1403013Y1302384I0J1502D01*
G03X1402467I-273J-292D01*
G02X1401440Y1301978I-1027J1096D01*
G02X1400069Y1302866I0J1502D01*
G01X1377646D01*
X1377595Y1302743D01*
G02X1374821I-1387J576D01*
G01X1374770Y1302866D01*
X1373283D01*
G02X1371912Y1301978I-1371J614D01*
G02X1370885Y1302384I0J1502D01*
G03X1370339I-273J-292D01*
G02X1369312Y1301978I-1027J1096D01*
G02X1367941Y1302866I0J1502D01*
G01X1343257D01*
G02X1342550Y1303159I0J999D01*
G01X1340520Y1305189D01*
X1340394Y1305134D01*
G02X1339784Y1305004I-611J1372D01*
G02X1338282Y1306506I0J1502D01*
G02X1338412Y1307116I1502J-1D01*
G01X1338467Y1307242D01*
X1337920Y1307789D01*
X1337794Y1307734D01*
G02X1337184Y1307604I-611J1372D01*
G02X1335682Y1309106I0J1502D01*
G02X1335812Y1309716I1502J-1D01*
G01X1335867Y1309842D01*
X1335526Y1310183D01*
G02X1335233Y1310890I706J707D01*
G01Y1315405D01*
X1334454Y1316184D01*
X1313744D01*
G02X1313037Y1316477I0J999D01*
G01X1304186Y1325328D01*
G02X1303959Y1325678I707J707D01*
G02X1303554Y1326704I1097J1026D01*
G02X1303893Y1327654I1501J0D01*
G01Y1328354D01*
G02Y1330254I1162J950D01*
G01Y1330954D01*
G02Y1332854I1162J950D01*
G01Y1333554D01*
G02Y1335454I1162J950D01*
G01Y1336154D01*
G02X1303554Y1337104I1162J950D01*
G02X1303814Y1337948I1502J-1D01*
G01X1302985Y1338777D01*
X1281004D01*
G02X1280135Y1338500I-869J1225D01*
G02X1278648Y1339791I0J1502D01*
G01X1278638Y1339858D01*
X1275694Y1342802D01*
G02X1275401Y1343509I706J707D01*
G01Y1356660D01*
X1275278Y1356712D01*
G02Y1359484I577J1386D01*
G01X1275401Y1359536D01*
Y1362701D01*
X1275400Y1362713D01*
G02X1275389Y1362891I1491J181D01*
G02X1275400Y1363069I1502J-3D01*
G01X1275401Y1363081D01*
Y1368454D01*
G02X1275694Y1369161I999J0D01*
G01X1282266Y1375733D01*
G02X1282973Y1376026I707J-706D01*
G01X1313652D01*
X1322882Y1385256D01*
G02X1323589Y1385549I707J-706D01*
G01X1353496D01*
G02X1354203Y1385256I0J-999D01*
G01X1361287Y1378172D01*
X1422586D01*
G37*
G36*
G01X1335359Y1112348D02*
X1334551Y1113747D01*
X1334461Y1113764D01*
G02X1333406Y1115039I243J1275D01*
G02X1336000I1297J0D01*
G01Y1115037D01*
G02X1335928Y1114610I-1298J-1D01*
G01X1335898Y1114524D01*
X1336705Y1113126D01*
X1336795Y1113109D01*
G02X1337852Y1111834I-240J-1275D01*
G02X1335256I-1298J0D01*
G02X1335329Y1112262I1299J-1D01*
G01X1335359Y1112348D01*
G37*
G36*
G01X1313541Y1122224D02*
X1315165D01*
G02X1316203Y1122744I1038J-776D01*
G02Y1120150I0J-1297D01*
G02X1315165Y1120670I0J1296D01*
G01X1313541D01*
G02X1312503Y1120150I-1038J776D01*
G02Y1122744I0J1297D01*
G02X1313541Y1122224I0J-1296D01*
G37*
G36*
G01X1318709Y1109144D02*
X1317902Y1110542D01*
X1317812Y1110559D01*
G02X1316756Y1111834I242J1275D01*
G02X1319352I1298J0D01*
G02X1319279Y1111406I-1299J1D01*
G01X1319249Y1111320D01*
X1320056Y1109922D01*
X1320146Y1109905D01*
G02X1321202Y1108630I-242J-1275D01*
G02X1318606I-1298J0D01*
G02X1318679Y1109058I1299J-1D01*
G01X1318709Y1109144D01*
G37*
G36*
G01X1331225Y880733D02*
X1330419Y882131D01*
X1330329Y882148D01*
G02X1329274Y883423I243J1275D01*
G02X1331868I1297J0D01*
G01Y883421D01*
G02X1331796Y882994I-1298J-1D01*
G01X1331766Y882908D01*
X1332572Y881511D01*
X1332662Y881494D01*
G02X1333718Y880219I-242J-1275D01*
G02X1331122I-1298J0D01*
G02X1331195Y880647I1299J-1D01*
G01X1331225Y880733D01*
G37*
G36*
G01X1322408Y1121961D02*
X1321601Y1123359D01*
X1321511Y1123376D01*
G02X1320456Y1124651I243J1275D01*
G02X1323050I1297J0D01*
G02X1322978Y1124223I-1298J-2D01*
G01X1322948Y1124137D01*
X1323755Y1122739D01*
X1323845Y1122722D01*
G02X1324900Y1121447I-243J-1275D01*
G02X1322306I-1297J0D01*
G02X1322378Y1121875I1298J2D01*
G01X1322408Y1121961D01*
G37*
G36*
G01X1327959Y1105941D02*
X1327152Y1107338D01*
X1327062Y1107355D01*
G02X1326006Y1108630I242J1275D01*
G02X1328602I1298J0D01*
G01Y1108628D01*
G02X1328529Y1108201I-1298J2D01*
G01X1328499Y1108115D01*
X1329306Y1106718D01*
X1329396Y1106701D01*
G02X1330450Y1105426I-244J-1275D01*
G02X1329153Y1104128I-1297J-1D01*
G02X1327856Y1105426I1J1298D01*
G02X1327929Y1105855I1297J0D01*
G01X1327959Y1105941D01*
G37*
G36*
G01X1320941Y1128634D02*
X1322565D01*
G02X1323603Y1129154I1038J-776D01*
G02Y1126558I0J-1298D01*
G02X1322565Y1127078I0J1296D01*
G01X1320941D01*
G02X1319903Y1126558I-1038J776D01*
G02Y1129154I0J1298D01*
G02X1320941Y1128634I0J-1296D01*
G37*
G36*
G01X1326492Y1112612D02*
X1328116D01*
G02X1329154Y1113132I1038J-776D01*
G02Y1110536I0J-1298D01*
G02X1328116Y1111056I0J1296D01*
G01X1326492D01*
G02X1325454Y1110536I-1038J776D01*
G02Y1113132I0J1298D01*
G02X1326492Y1112612I0J-1296D01*
G37*
G36*
G01X1319091Y1106204D02*
X1320715D01*
G02X1321753Y1106724I1038J-776D01*
G02Y1104128I0J-1298D01*
G02X1320715Y1104648I0J1296D01*
G01X1319091D01*
G02X1318053Y1104128I-1038J776D01*
G02Y1106724I0J1298D01*
G02X1319091Y1106204I0J-1296D01*
G37*
G36*
G01X1338625Y880733D02*
X1337819Y882131D01*
X1337729Y882148D01*
G02X1336674Y883423I243J1275D01*
G02X1339268I1297J0D01*
G01Y883421D01*
G02X1339196Y882994I-1298J-1D01*
G01X1339166Y882908D01*
X1339972Y881511D01*
X1340062Y881494D01*
G02X1341118Y880219I-242J-1275D01*
G02X1338522I-1298J0D01*
G02X1338595Y880647I1299J-1D01*
G01X1338625Y880733D01*
G37*
G36*
G01X1334895Y886198D02*
G02X1334822Y886625I1225J429D01*
G01Y886627D01*
G02X1337418I1298J0D01*
G02X1336362Y885352I-1298J0D01*
G01X1336272Y885335D01*
X1335466Y883938D01*
X1335496Y883852D01*
G02X1335568Y883425I-1226J-426D01*
G01Y883423D01*
G02X1332974I-1297J0D01*
G02X1334029Y884698I1298J0D01*
G01X1334119Y884715D01*
X1334925Y886112D01*
X1334895Y886198D01*
G37*
G36*
G01X1342295D02*
G02X1342222Y886625I1225J429D01*
G01Y886627D01*
G02X1344818I1298J0D01*
G02X1343762Y885352I-1298J0D01*
G01X1343672Y885335D01*
X1342866Y883938D01*
X1342896Y883852D01*
G02X1342968Y883425I-1226J-426D01*
G01Y883423D01*
G02X1340374I-1297J0D01*
G02X1341429Y884698I1298J0D01*
G01X1341519Y884715D01*
X1342325Y886112D01*
X1342295Y886198D01*
G37*
G36*
G01X1340101Y1106718D02*
X1340908Y1108116D01*
X1340878Y1108202D01*
G02X1340806Y1108630I1226J426D01*
G02X1343400I1297J0D01*
G02X1342345Y1107355I-1298J0D01*
G01X1342255Y1107338D01*
X1341448Y1105941D01*
X1341478Y1105855D01*
G02X1341551Y1105426I-1224J-429D01*
G02X1340254Y1104128I-1297J-1D01*
G02X1338956Y1105426I0J1298D01*
G02X1340011Y1106701I1298J0D01*
G01X1340101Y1106718D01*
G37*
G36*
G01X1331226Y867916D02*
X1330419Y869314D01*
X1330329Y869331D01*
G02X1329274Y870606I243J1275D01*
G02X1331868I1297J0D01*
G02X1331796Y870177I-1297J-3D01*
G01X1331765Y870091D01*
X1332572Y868693D01*
X1332662Y868676D01*
G02X1333718Y867401I-242J-1275D01*
G02X1331122I-1298J0D01*
G02X1331195Y867830I1297J0D01*
G01X1331226Y867916D01*
G37*
G36*
G01X1338626D02*
X1337819Y869314D01*
X1337729Y869331D01*
G02X1336674Y870606I243J1275D01*
G02X1339268I1297J0D01*
G02X1339196Y870177I-1297J-3D01*
G01X1339165Y870091D01*
X1339972Y868693D01*
X1340062Y868676D01*
G02X1341118Y867401I-242J-1275D01*
G02X1338522I-1298J0D01*
G02X1338595Y867830I1297J0D01*
G01X1338626Y867916D01*
G37*
G36*
G01X1346026D02*
X1345219Y869314D01*
X1345129Y869331D01*
G02X1344074Y870606I243J1275D01*
G02X1346668I1297J0D01*
G02X1346596Y870177I-1297J-3D01*
G01X1346565Y870091D01*
X1347372Y868693D01*
X1347462Y868676D01*
G02X1348518Y867401I-242J-1275D01*
G02X1345922I-1298J0D01*
G02X1345995Y867830I1297J0D01*
G01X1346026Y867916D01*
G37*
G36*
G01X1326719Y871898D02*
X1327526Y873295D01*
X1327495Y873382D01*
G02X1327422Y873810I1225J429D01*
G02X1330018I1298J0D01*
G02X1328962Y872535I-1298J0D01*
G01X1328872Y872518D01*
X1328065Y871121D01*
X1328096Y871034D01*
G02X1328168Y870606I-1225J-426D01*
G02X1325574I-1297J0D01*
G02X1326629Y871881I1298J0D01*
G01X1326719Y871898D01*
G37*
G36*
G01X1334119D02*
X1334926Y873295D01*
X1334895Y873382D01*
G02X1334822Y873810I1225J429D01*
G02X1337418I1298J0D01*
G02X1336362Y872535I-1298J0D01*
G01X1336272Y872518D01*
X1335465Y871121D01*
X1335496Y871034D01*
G02X1335568Y870606I-1225J-426D01*
G02X1332974I-1297J0D01*
G02X1334029Y871881I1298J0D01*
G01X1334119Y871898D01*
G37*
G36*
G01X1341519D02*
X1342326Y873295D01*
X1342295Y873382D01*
G02X1342222Y873810I1225J429D01*
G02X1344818I1298J0D01*
G02X1343762Y872535I-1298J0D01*
G01X1343672Y872518D01*
X1342865Y871121D01*
X1342896Y871034D01*
G02X1342968Y870606I-1225J-426D01*
G02X1340374I-1297J0D01*
G02X1341429Y871881I1298J0D01*
G01X1341519Y871898D01*
G37*
G36*
G01X1348919D02*
X1349726Y873295D01*
X1349695Y873382D01*
G02X1349622Y873810I1225J429D01*
G02X1352218I1298J0D01*
G02X1351162Y872535I-1298J0D01*
G01X1351072Y872518D01*
X1350265Y871121D01*
X1350296Y871034D01*
G02X1350368Y870606I-1225J-426D01*
G02X1347774I-1297J0D01*
G02X1348829Y871881I1298J0D01*
G01X1348919Y871898D01*
G37*
G36*
G01X1346025Y880734D02*
X1345219Y882131D01*
X1345129Y882148D01*
G02X1344074Y883423I243J1275D01*
G02X1346668I1297J0D01*
G02X1346596Y882994I-1297J-3D01*
G01X1346565Y882908D01*
X1347371Y881511D01*
X1347461Y881494D01*
G02X1348518Y880219I-240J-1275D01*
G02X1345922I-1298J0D01*
G02X1345995Y880647I1298J-1D01*
G01X1346025Y880734D01*
G37*
G36*
G01X1353425D02*
X1352619Y882131D01*
X1352529Y882148D01*
G02X1351474Y883423I243J1275D01*
G02X1354068I1297J0D01*
G02X1353996Y882994I-1297J-3D01*
G01X1353965Y882908D01*
X1354771Y881511D01*
X1354861Y881494D01*
G02X1355918Y880219I-240J-1275D01*
G02X1353322I-1298J0D01*
G02X1353395Y880647I1298J-1D01*
G01X1353425Y880734D01*
G37*
G36*
G01X1348919Y884715D02*
X1349726Y886112D01*
X1349695Y886199D01*
G02X1349622Y886627I1225J429D01*
G02X1352218I1298J0D01*
G02X1351162Y885352I-1298J0D01*
G01X1351072Y885335D01*
X1350265Y883938D01*
X1350296Y883851D01*
G02X1350368Y883423I-1225J-426D01*
G02X1347774I-1297J0D01*
G02X1348829Y884698I1298J0D01*
G01X1348919Y884715D01*
G37*
G36*
G01X1380143Y1082218D02*
G02X1379104Y1081698I-1039J778D01*
G02Y1084292I0J1297D01*
G02X1380143Y1083772I0J-1298D01*
G01X1381765D01*
G02X1382804Y1084292I1039J-778D01*
G02Y1081698I0J-1297D01*
G02X1381765Y1082218I0J1298D01*
G01X1380143D01*
G37*
G36*
G01X1384503Y1081083D02*
X1385310Y1082480D01*
X1385279Y1082567D01*
G02X1385206Y1082995I1225J429D01*
G02X1387802I1298J0D01*
G02X1386746Y1081720I-1298J0D01*
G01X1386656Y1081703D01*
X1385848Y1080304D01*
X1385878Y1080218D01*
G02X1385950Y1079791I-1225J-426D01*
G02X1383356I-1297J0D01*
G02X1384413Y1081066I1297J0D01*
G01X1384503Y1081083D01*
G37*
G36*
G01X1389009Y1083509D02*
X1388201Y1084908D01*
X1388111Y1084925D01*
G02X1387056Y1086200I243J1275D01*
G02X1389650I1297J0D01*
G02X1389578Y1085772I-1297J-2D01*
G01X1389547Y1085685D01*
X1390354Y1084287D01*
X1390445Y1084270D01*
G02X1391502Y1082995I-240J-1275D01*
G02X1388906I-1298J0D01*
G02X1388979Y1083422I1298J-2D01*
G01X1389009Y1083509D01*
G37*
G36*
G01X1379758Y1086714D02*
X1378951Y1088112D01*
X1378861Y1088129D01*
G02X1377806Y1089404I243J1275D01*
G02X1380400I1297J0D01*
G02X1380328Y1088976I-1297J-2D01*
G01X1380297Y1088889D01*
X1381104Y1087492D01*
X1381194Y1087475D01*
G02X1382250Y1086200I-242J-1275D01*
G02X1379656I-1297J0D01*
G02X1379728Y1086628I1297J2D01*
G01X1379758Y1086714D01*
G37*
G36*
G01X1387543Y1088626D02*
G02X1386504Y1088106I-1039J778D01*
G02Y1090702I0J1298D01*
G02X1387543Y1090182I0J-1298D01*
G01X1389165D01*
G02X1390204Y1090702I1039J-778D01*
G02Y1088106I0J-1298D01*
G02X1389165Y1088626I0J1298D01*
G01X1387543D01*
G37*
G36*
G01X1382652Y1090696D02*
X1383459Y1092093D01*
X1383428Y1092180D01*
G02X1383356Y1092608I1225J426D01*
G02X1385950I1297J0D01*
G02X1384895Y1091333I-1298J0D01*
G01X1384805Y1091316D01*
X1383998Y1089919D01*
X1384029Y1089833D01*
G02X1384102Y1089404I-1224J-429D01*
G02X1381506I-1298J0D01*
G02X1382562Y1090679I1298J0D01*
G01X1382652Y1090696D01*
G37*
G36*
G01X1396409Y1089917D02*
X1395601Y1091316D01*
X1395511Y1091333D01*
G02X1394456Y1092608I243J1275D01*
G02X1397050I1297J0D01*
G02X1396978Y1092180I-1297J-2D01*
G01X1396947Y1092093D01*
X1397754Y1090696D01*
X1397844Y1090679D01*
G02X1398902Y1089404I-239J-1275D01*
G02X1396306I-1298J0D01*
G02X1396379Y1089831I1298J-2D01*
G01X1396409Y1089917D01*
G37*
G36*
G01X1381992Y1098240D02*
G02X1380953Y1097720I-1039J778D01*
G02Y1100314I0J1297D01*
G02X1381992Y1099794I0J-1298D01*
G01X1383614D01*
G02X1384653Y1100314I1039J-778D01*
G02Y1097720I0J-1297D01*
G02X1383614Y1098240I0J1298D01*
G01X1381992D01*
G37*
G36*
G01X1328342Y1101444D02*
G02X1327303Y1100924I-1039J778D01*
G02Y1103518I0J1297D01*
G02X1328342Y1102998I0J-1298D01*
G01X1329964D01*
G02X1331003Y1103518I1039J-778D01*
G02Y1100924I0J-1297D01*
G02X1329964Y1101444I0J1298D01*
G01X1328342D01*
G37*
G36*
G01X1377103Y1100309D02*
X1377910Y1101706D01*
X1377879Y1101793D01*
G02X1377806Y1102221I1225J429D01*
G02X1380402I1298J0D01*
G02X1379346Y1100946I-1298J0D01*
G01X1379256Y1100929D01*
X1378448Y1099530D01*
X1378478Y1099444D01*
G02X1378550Y1099017I-1225J-426D01*
G02X1375956I-1297J0D01*
G02X1377013Y1100292I1297J0D01*
G01X1377103Y1100309D01*
G37*
G36*
G01X1352392Y1104648D02*
G02X1351353Y1104128I-1039J778D01*
G02Y1106724I0J1298D01*
G02X1352392Y1106204I0J-1298D01*
G01X1354015D01*
G02X1355054Y1106724I1039J-778D01*
G02Y1104128I0J-1298D01*
G02X1354015Y1104648I0J1298D01*
G01X1352392D01*
G37*
G36*
G01X1356751Y1103513D02*
X1357559Y1104911D01*
X1357528Y1104998D01*
G02X1357456Y1105426I1225J426D01*
G02X1360050I1297J0D01*
G02X1358995Y1104151I-1298J0D01*
G01X1358905Y1104134D01*
X1358098Y1102737D01*
X1358128Y1102650D01*
G02X1358202Y1102221I-1223J-432D01*
G02X1355606I-1298J0D01*
G02X1356661Y1103496I1298J0D01*
G01X1356751Y1103513D01*
G37*
G36*
G01X1389009Y1102735D02*
X1388201Y1104134D01*
X1388111Y1104151D01*
G02X1387056Y1105426I243J1275D01*
G02X1389650I1297J0D01*
G02X1389578Y1104998I-1297J-2D01*
G01X1389547Y1104911D01*
X1390354Y1103513D01*
X1390445Y1103496D01*
G02X1391502Y1102221I-240J-1275D01*
G02X1388906I-1298J0D01*
G02X1388979Y1102648I1298J-2D01*
G01X1389009Y1102735D01*
G37*
G36*
G01X1335742Y1107852D02*
G02X1334703Y1107332I-1039J778D01*
G02Y1109928I0J1298D01*
G02X1335742Y1109408I0J-1298D01*
G01X1337364D01*
G02X1338403Y1109928I1039J-778D01*
G02Y1107332I0J-1298D01*
G02X1337364Y1107852I0J1298D01*
G01X1335742D01*
G37*
G36*
G01X1361259Y1105941D02*
X1360452Y1107338D01*
X1360362Y1107355D01*
G02X1359306Y1108630I242J1275D01*
G02X1361902I1298J0D01*
G02X1361829Y1108202I-1298J1D01*
G01X1361798Y1108115D01*
X1362605Y1106718D01*
X1362695Y1106701D01*
G02X1363750Y1105426I-243J-1275D01*
G02X1361156I-1297J0D01*
G02X1361228Y1105855I1297J3D01*
G01X1361259Y1105941D01*
G37*
G36*
G01X1369043Y1107852D02*
G02X1368004Y1107332I-1039J778D01*
G02Y1109928I0J1298D01*
G02X1369043Y1109408I0J-1298D01*
G01X1370665D01*
G02X1371704Y1109928I1039J-778D01*
G02Y1107332I0J-1298D01*
G02X1370665Y1107852I0J1298D01*
G01X1369043D01*
G37*
G36*
G01X1373403Y1106718D02*
X1374210Y1108115D01*
X1374179Y1108202D01*
G02X1374106Y1108630I1225J429D01*
G02X1376702I1298J0D01*
G02X1375646Y1107355I-1298J0D01*
G01X1375556Y1107338D01*
X1374748Y1105939D01*
X1374778Y1105853D01*
G02X1374850Y1105426I-1225J-426D01*
G02X1372256I-1297J0D01*
G02X1373313Y1106701I1297J0D01*
G01X1373403Y1106718D01*
G37*
G36*
G01X1384503D02*
X1385310Y1108115D01*
X1385279Y1108202D01*
G02X1385206Y1108630I1225J429D01*
G02X1387802I1298J0D01*
G02X1386746Y1107355I-1298J0D01*
G01X1386656Y1107338D01*
X1385848Y1105939D01*
X1385878Y1105853D01*
G02X1385950Y1105426I-1225J-426D01*
G02X1383356I-1297J0D01*
G02X1384413Y1106701I1297J0D01*
G01X1384503Y1106718D01*
G37*
G36*
G01X1344609Y1109145D02*
X1343802Y1110542D01*
X1343712Y1110559D01*
G02X1342656Y1111834I242J1275D01*
G02X1345252I1298J0D01*
G02X1345179Y1111406I-1298J1D01*
G01X1345148Y1111319D01*
X1345955Y1109922D01*
X1346045Y1109905D01*
G02X1347100Y1108630I-243J-1275D01*
G02X1344506I-1297J0D01*
G02X1344578Y1109059I1297J3D01*
G01X1344609Y1109145D01*
G37*
G36*
G01X1352009Y1109143D02*
X1351201Y1110542D01*
X1351111Y1110559D01*
G02X1350056Y1111834I243J1275D01*
G02X1352650I1297J0D01*
G02X1352578Y1111406I-1297J-2D01*
G01X1352547Y1111319D01*
X1353354Y1109922D01*
X1353444Y1109905D01*
G02X1354502Y1108630I-239J-1275D01*
G02X1351906I-1298J0D01*
G02X1351979Y1109057I1298J-2D01*
G01X1352009Y1109143D01*
G37*
G36*
G01X1359792Y1111056D02*
G02X1358753Y1110536I-1039J778D01*
G02Y1113132I0J1298D01*
G02X1359792Y1112612I0J-1298D01*
G01X1361414D01*
G02X1362453Y1113132I1039J-778D01*
G02Y1110536I0J-1298D01*
G02X1361414Y1111056I0J1298D01*
G01X1359792D01*
G37*
G36*
G01X1377909Y1109143D02*
X1377101Y1110542D01*
X1377011Y1110559D01*
G02X1375956Y1111834I243J1275D01*
G02X1378550I1297J0D01*
G02X1378478Y1111406I-1297J-2D01*
G01X1378447Y1111319D01*
X1379254Y1109922D01*
X1379344Y1109905D01*
G02X1380402Y1108630I-239J-1275D01*
G02X1377806I-1298J0D01*
G02X1377879Y1109057I1298J-2D01*
G01X1377909Y1109143D01*
G37*
G36*
G01X1385692Y1111056D02*
G02X1384653Y1110536I-1039J778D01*
G02Y1113132I0J1298D01*
G02X1385692Y1112612I0J-1298D01*
G01X1387314D01*
G02X1388353Y1113132I1039J-778D01*
G02Y1110536I0J-1298D01*
G02X1387314Y1111056I0J1298D01*
G01X1385692D01*
G37*
G36*
G01X1321601Y1113126D02*
X1322409Y1114524D01*
X1322378Y1114611D01*
G02X1322306Y1115039I1225J426D01*
G02X1324900I1297J0D01*
G02X1323845Y1113764I-1298J0D01*
G01X1323755Y1113747D01*
X1322947Y1112349D01*
X1322978Y1112262D01*
G02X1323050Y1111834I-1225J-426D01*
G02X1320456I-1297J0D01*
G02X1321511Y1113109I1298J0D01*
G01X1321601Y1113126D01*
G37*
G36*
G01X1343142Y1114262D02*
G02X1342103Y1113742I-1039J778D01*
G02Y1116336I0J1297D01*
G02X1343142Y1115816I0J-1298D01*
G01X1344764D01*
G02X1345803Y1116336I1039J-778D01*
G02Y1113742I0J-1297D01*
G02X1344764Y1114262I0J1298D01*
G01X1343142D01*
G37*
G36*
G01X1354903Y1113126D02*
X1355710Y1114524D01*
X1355679Y1114611D01*
G02X1355606Y1115039I1225J429D01*
G02X1358202I1298J0D01*
G02X1357146Y1113764I-1298J0D01*
G01X1357056Y1113747D01*
X1356248Y1112348D01*
X1356278Y1112261D01*
G02X1356350Y1111834I-1225J-426D01*
G02X1353756I-1297J0D01*
G02X1354812Y1113109I1298J0D01*
G01X1354903Y1113126D01*
G37*
G36*
G01X1368659Y1112350D02*
X1367852Y1113747D01*
X1367762Y1113764D01*
G02X1366706Y1115039I242J1275D01*
G02X1369302I1298J0D01*
G02X1369229Y1114611I-1298J1D01*
G01X1369198Y1114524D01*
X1370006Y1113126D01*
X1370096Y1113109D01*
G02X1371150Y1111834I-244J-1275D01*
G02X1368556I-1297J0D01*
G02X1368629Y1112263I1297J0D01*
G01X1368659Y1112350D01*
G37*
G36*
G01X1376443Y1114262D02*
G02X1375404Y1113742I-1039J778D01*
G02Y1116336I0J1297D01*
G02X1376443Y1115816I0J-1298D01*
G01X1378065D01*
G02X1379104Y1116336I1039J-778D01*
G02Y1113742I0J-1297D01*
G02X1378065Y1114262I0J1298D01*
G01X1376443D01*
G37*
G36*
G01X1317902Y1119535D02*
X1318709Y1120932D01*
X1318678Y1121019D01*
G02X1318606Y1121447I1225J426D01*
G02X1321200I1297J0D01*
G02X1320145Y1120172I-1298J0D01*
G01X1320055Y1120155D01*
X1319248Y1118758D01*
X1319279Y1118671D01*
G02X1319352Y1118243I-1225J-429D01*
G02X1316756I-1298J0D01*
G02X1317812Y1119518I1298J0D01*
G01X1317902Y1119535D01*
G37*
G36*
G01X1333509Y1121962D02*
X1332702Y1123359D01*
X1332612Y1123376D01*
G02X1331556Y1124651I242J1275D01*
G02X1334152I1298J0D01*
G02X1334079Y1124223I-1298J1D01*
G01X1334048Y1124136D01*
X1334855Y1122739D01*
X1334945Y1122722D01*
G02X1336000Y1121447I-243J-1275D01*
G02X1333406I-1297J0D01*
G02X1333478Y1121876I1297J3D01*
G01X1333509Y1121962D01*
G37*
G36*
G01X1340909Y1121960D02*
X1340101Y1123359D01*
X1340011Y1123376D01*
G02X1338956Y1124651I243J1275D01*
G02X1341550I1297J0D01*
G02X1341478Y1124223I-1297J-2D01*
G01X1341447Y1124136D01*
X1342254Y1122739D01*
X1342344Y1122722D01*
G02X1343402Y1121447I-239J-1275D01*
G02X1340806I-1298J0D01*
G02X1340879Y1121874I1298J-2D01*
G01X1340909Y1121960D01*
G37*
G36*
G01X1348309D02*
X1347501Y1123359D01*
X1347411Y1123376D01*
G02X1346356Y1124651I243J1275D01*
G02X1348950I1297J0D01*
G02X1348878Y1124223I-1297J-2D01*
G01X1348847Y1124136D01*
X1349654Y1122739D01*
X1349744Y1122722D01*
G02X1350802Y1121447I-239J-1275D01*
G02X1348206I-1298J0D01*
G02X1348279Y1121874I1298J-2D01*
G01X1348309Y1121960D01*
G37*
G36*
G01X1355709D02*
X1354901Y1123359D01*
X1354811Y1123376D01*
G02X1353756Y1124651I243J1275D01*
G02X1356350I1297J0D01*
G02X1356278Y1124223I-1297J-2D01*
G01X1356247Y1124136D01*
X1357054Y1122739D01*
X1357144Y1122722D01*
G02X1358202Y1121447I-239J-1275D01*
G02X1355606I-1298J0D01*
G02X1355679Y1121874I1298J-2D01*
G01X1355709Y1121960D01*
G37*
G36*
G01X1363109D02*
X1362301Y1123359D01*
X1362211Y1123376D01*
G02X1361156Y1124651I243J1275D01*
G02X1363750I1297J0D01*
G02X1363678Y1124223I-1297J-2D01*
G01X1363647Y1124136D01*
X1364454Y1122739D01*
X1364544Y1122722D01*
G02X1365602Y1121447I-239J-1275D01*
G02X1363006I-1298J0D01*
G02X1363079Y1121874I1298J-2D01*
G01X1363109Y1121960D01*
G37*
G36*
G01X1370509D02*
X1369701Y1123359D01*
X1369611Y1123376D01*
G02X1368556Y1124651I243J1275D01*
G02X1371150I1297J0D01*
G02X1371078Y1124223I-1297J-2D01*
G01X1371047Y1124136D01*
X1371854Y1122739D01*
X1371944Y1122722D01*
G02X1373002Y1121447I-239J-1275D01*
G02X1370406I-1298J0D01*
G02X1370479Y1121874I1298J-2D01*
G01X1370509Y1121960D01*
G37*
G36*
G01X1377909D02*
X1377101Y1123359D01*
X1377011Y1123376D01*
G02X1375956Y1124651I243J1275D01*
G02X1378550I1297J0D01*
G02X1378478Y1124223I-1297J-2D01*
G01X1378447Y1124136D01*
X1379254Y1122739D01*
X1379344Y1122722D01*
G02X1380402Y1121447I-239J-1275D01*
G02X1377806I-1298J0D01*
G02X1377879Y1121874I1298J-2D01*
G01X1377909Y1121960D01*
G37*
G36*
G01X1329001Y1125943D02*
X1329809Y1127341D01*
X1329778Y1127428D01*
G02X1329706Y1127856I1225J426D01*
G02X1332300I1297J0D01*
G02X1331245Y1126581I-1298J0D01*
G01X1331155Y1126564D01*
X1330347Y1125166D01*
X1330378Y1125079D01*
G02X1330450Y1124651I-1225J-426D01*
G02X1327856I-1297J0D01*
G02X1328911Y1125926I1298J0D01*
G01X1329001Y1125943D01*
G37*
G36*
G01X1336402D02*
X1337210Y1127341D01*
X1337179Y1127428D01*
G02X1337106Y1127856I1225J429D01*
G02X1339702I1298J0D01*
G02X1338646Y1126581I-1298J0D01*
G01X1338556Y1126564D01*
X1337748Y1125166D01*
X1337779Y1125079D01*
G02X1337852Y1124651I-1225J-429D01*
G02X1335256I-1298J0D01*
G02X1336312Y1125926I1298J0D01*
G01X1336402Y1125943D01*
G37*
G36*
G01X1343803D02*
X1344610Y1127341D01*
X1344579Y1127428D01*
G02X1344506Y1127856I1225J429D01*
G02X1347102I1298J0D01*
G02X1346046Y1126581I-1298J0D01*
G01X1345956Y1126564D01*
X1345148Y1125165D01*
X1345178Y1125078D01*
G02X1345250Y1124651I-1225J-426D01*
G02X1342656I-1297J0D01*
G02X1343712Y1125926I1298J0D01*
G01X1343803Y1125943D01*
G37*
G36*
G01X1351203D02*
X1352010Y1127341D01*
X1351979Y1127428D01*
G02X1351906Y1127856I1225J429D01*
G02X1354502I1298J0D01*
G02X1353446Y1126581I-1298J0D01*
G01X1353356Y1126564D01*
X1352548Y1125165D01*
X1352578Y1125078D01*
G02X1352650Y1124651I-1225J-426D01*
G02X1350056I-1297J0D01*
G02X1351112Y1125926I1298J0D01*
G01X1351203Y1125943D01*
G37*
G36*
G01X1358603D02*
X1359410Y1127341D01*
X1359379Y1127428D01*
G02X1359306Y1127856I1225J429D01*
G02X1361902I1298J0D01*
G02X1360846Y1126581I-1298J0D01*
G01X1360756Y1126564D01*
X1359948Y1125165D01*
X1359978Y1125078D01*
G02X1360050Y1124651I-1225J-426D01*
G02X1357456I-1297J0D01*
G02X1358512Y1125926I1298J0D01*
G01X1358603Y1125943D01*
G37*
G36*
G01X1366003D02*
X1366810Y1127341D01*
X1366779Y1127428D01*
G02X1366706Y1127856I1225J429D01*
G02X1369302I1298J0D01*
G02X1368246Y1126581I-1298J0D01*
G01X1368156Y1126564D01*
X1367348Y1125165D01*
X1367378Y1125078D01*
G02X1367450Y1124651I-1225J-426D01*
G02X1364856I-1297J0D01*
G02X1365912Y1125926I1298J0D01*
G01X1366003Y1125943D01*
G37*
G36*
G01X1373403D02*
X1374210Y1127341D01*
X1374179Y1127428D01*
G02X1374106Y1127856I1225J429D01*
G02X1376702I1298J0D01*
G02X1375646Y1126581I-1298J0D01*
G01X1375556Y1126564D01*
X1374748Y1125165D01*
X1374778Y1125078D01*
G02X1374850Y1124651I-1225J-426D01*
G02X1372256I-1297J0D01*
G02X1373312Y1125926I1298J0D01*
G01X1373403Y1125943D01*
G37*
G36*
G01X1380803D02*
X1381610Y1127341D01*
X1381579Y1127428D01*
G02X1381506Y1127856I1225J429D01*
G02X1384102I1298J0D01*
G02X1383046Y1126581I-1298J0D01*
G01X1382956Y1126564D01*
X1382148Y1125165D01*
X1382178Y1125078D01*
G02X1382250Y1124651I-1225J-426D01*
G02X1379656I-1297J0D01*
G02X1380712Y1125926I1298J0D01*
G01X1380803Y1125943D01*
G37*
G36*
G01X1316051Y1129148D02*
X1316858Y1130546D01*
X1316828Y1130632D01*
G02X1316756Y1131060I1225J426D01*
G02X1319350I1297J0D01*
G02X1318295Y1129785I-1298J0D01*
G01X1318205Y1129768D01*
X1317398Y1128370D01*
X1317428Y1128284D01*
G02X1317500Y1127856I-1225J-426D01*
G02X1314906I-1297J0D01*
G02X1315961Y1129131I1298J0D01*
G01X1316051Y1129148D01*
G37*
G36*
G01X1388976Y739200D02*
G02X1390978Y737198I0J-2002D01*
G02X1389977Y735464I-2002J0D01*
G01X1386339Y733363D01*
G02X1385340Y733096I-999J1736D01*
G01X1385338D01*
G02X1383336Y735098I0J2002D01*
G02X1384337Y736832I2002J0D01*
G01X1387975Y738933D01*
G02X1388974Y739200I999J-1736D01*
G01X1388976D01*
G37*
G36*
G01X1393206Y724738D02*
G02X1395208Y722735I-1J-2003D01*
G02X1394207Y721001I-2002J0D01*
G01X1390569Y718900D01*
G02X1389570Y718632I-1001J1735D01*
G01X1389568D01*
G02X1387566Y720635I1J2003D01*
G02X1388567Y722369I2002J0D01*
G01X1392205Y724470D01*
G02X1393204Y724738I1001J-1735D01*
G01X1393206D01*
G37*
G36*
G01Y695710D02*
G02X1395208Y693708I0J-2002D01*
G02X1394207Y691974I-2002J0D01*
G01X1390569Y689873D01*
G02X1389570Y689606I-999J1736D01*
G01X1389568D01*
G02X1387566Y691608I0J2002D01*
G02X1388567Y693342I2002J0D01*
G01X1392205Y695443D01*
G02X1393204Y695710I999J-1736D01*
G01X1393206D01*
G37*
G36*
G01Y710210D02*
G02X1395208Y708208I0J-2002D01*
G02X1394207Y706474I-2002J0D01*
G01X1390569Y704373D01*
G02X1389570Y704106I-999J1736D01*
G01X1389568D01*
G02X1387566Y706108I0J2002D01*
G02X1388567Y707842I2002J0D01*
G01X1392205Y709943D01*
G02X1393204Y710210I999J-1736D01*
G01X1393206D01*
G37*
G36*
G01Y681210D02*
G02X1395208Y679208I0J-2002D01*
G02X1394207Y677474I-2002J0D01*
G01X1390569Y675373D01*
G02X1389570Y675106I-999J1736D01*
G01X1389568D01*
G02X1387566Y677108I0J2002D01*
G02X1388567Y678842I2002J0D01*
G01X1392205Y680943D01*
G02X1393204Y681210I999J-1736D01*
G01X1393206D01*
G37*
G36*
G01Y666710D02*
G02X1395208Y664708I0J-2002D01*
G02X1394207Y662974I-2002J0D01*
G01X1390569Y660873D01*
G02X1389570Y660606I-999J1736D01*
G01X1389568D01*
G02X1387566Y662608I0J2002D01*
G02X1388567Y664342I2002J0D01*
G01X1392205Y666443D01*
G02X1393204Y666710I999J-1736D01*
G01X1393206D01*
G37*
G36*
G01X1372666Y719708D02*
G02X1374668Y721710I2002J0D01*
G01X1374670D01*
G02X1375669Y721443I0J-2003D01*
G01X1379307Y719342D01*
G02X1380308Y717608I-1001J-1734D01*
G02X1378306Y715606I-2002J0D01*
G01X1378304D01*
G02X1377305Y715873I0J2003D01*
G01X1373667Y717974D01*
G02X1372666Y719708I1001J1734D01*
G37*
G36*
G01Y695708D02*
G02X1374668Y697710I2002J0D01*
G01X1374670D01*
G02X1375669Y697443I0J-2003D01*
G01X1379307Y695342D01*
G02X1380308Y693608I-1001J-1734D01*
G02X1378306Y691606I-2002J0D01*
G01X1378304D01*
G02X1377305Y691873I0J2003D01*
G01X1373667Y693974D01*
G02X1372666Y695708I1001J1734D01*
G37*
G36*
G01Y707708D02*
G02X1374668Y709710I2002J0D01*
G01X1374670D01*
G02X1375669Y709443I0J-2003D01*
G01X1379307Y707342D01*
G02X1380308Y705608I-1001J-1734D01*
G02X1378306Y703606I-2002J0D01*
G01X1378304D01*
G02X1377305Y703873I0J2003D01*
G01X1373667Y705974D01*
G02X1372666Y707708I1001J1734D01*
G37*
G36*
G01Y683708D02*
G02X1374668Y685710I2002J0D01*
G01X1374670D01*
G02X1375669Y685443I0J-2003D01*
G01X1379307Y683342D01*
G02X1380308Y681608I-1001J-1734D01*
G02X1378306Y679606I-2002J0D01*
G01X1378304D01*
G02X1377305Y679873I0J2003D01*
G01X1373667Y681974D01*
G02X1372666Y683708I1001J1734D01*
G37*
G36*
G01Y671708D02*
G02X1374668Y673710I2002J0D01*
G01X1374670D01*
G02X1375669Y673443I0J-2003D01*
G01X1379307Y671342D01*
G02X1380308Y669608I-1001J-1734D01*
G02X1378306Y667606I-2002J0D01*
G01X1378304D01*
G02X1377305Y667873I0J2003D01*
G01X1373667Y669974D01*
G02X1372666Y671708I1001J1734D01*
G37*
G36*
G01Y659708D02*
G02X1374668Y661710I2002J0D01*
G01X1374670D01*
G02X1375669Y661443I0J-2003D01*
G01X1379307Y659342D01*
G02X1380308Y657608I-1001J-1734D01*
G02X1378306Y655606I-2002J0D01*
G01X1378304D01*
G02X1377305Y655873I0J2003D01*
G01X1373667Y657974D01*
G02X1372666Y659708I1001J1734D01*
G37*
G36*
G01X1332281Y842761D02*
X1333122Y844356D01*
X1333083Y844444D01*
G02X1332972Y844971I1186J525D01*
G02X1335566I1297J0D01*
G02X1334504Y843695I-1298J0D01*
G01X1334409Y843677D01*
X1333568Y842082D01*
X1333607Y841994D01*
G02X1333718Y841467I-1186J-525D01*
G02X1331124I-1297J0D01*
G02X1332186Y842743I1298J0D01*
G01X1332281Y842761D01*
G37*
G36*
G01X1339681D02*
X1340522Y844356D01*
X1340483Y844444D01*
G02X1340372Y844971I1186J525D01*
G02X1342966I1297J0D01*
G02X1341904Y843695I-1298J0D01*
G01X1341809Y843677D01*
X1340968Y842082D01*
X1341007Y841994D01*
G02X1341118Y841467I-1186J-525D01*
G02X1338524I-1297J0D01*
G02X1339586Y842743I1298J0D01*
G01X1339681Y842761D01*
G37*
G36*
G01X1347081D02*
X1347922Y844356D01*
X1347883Y844444D01*
G02X1347772Y844971I1186J525D01*
G02X1350366I1297J0D01*
G02X1349304Y843695I-1298J0D01*
G01X1349209Y843677D01*
X1348368Y842082D01*
X1348407Y841994D01*
G02X1348518Y841467I-1186J-525D01*
G02X1345924I-1297J0D01*
G02X1346986Y842743I1298J0D01*
G01X1347081Y842761D01*
G37*
G36*
G01X1354481D02*
X1355322Y844356D01*
X1355283Y844444D01*
G02X1355172Y844971I1186J525D01*
G02X1357766I1297J0D01*
G02X1356704Y843695I-1298J0D01*
G01X1356609Y843677D01*
X1355768Y842082D01*
X1355807Y841994D01*
G02X1355918Y841467I-1186J-525D01*
G02X1353324I-1297J0D01*
G02X1354386Y842743I1298J0D01*
G01X1354481Y842761D01*
G37*
G36*
G01X1361881D02*
X1362722Y844356D01*
X1362683Y844444D01*
G02X1362572Y844971I1186J525D01*
G02X1365166I1297J0D01*
G02X1364104Y843695I-1298J0D01*
G01X1364009Y843677D01*
X1363168Y842082D01*
X1363207Y841994D01*
G02X1363318Y841467I-1186J-525D01*
G02X1360724I-1297J0D01*
G02X1361786Y842743I1298J0D01*
G01X1361881Y842761D01*
G37*
G36*
G01X1369281D02*
X1370122Y844356D01*
X1370083Y844444D01*
G02X1369972Y844971I1186J525D01*
G02X1372566I1297J0D01*
G02X1371504Y843695I-1298J0D01*
G01X1371409Y843677D01*
X1370568Y842082D01*
X1370607Y841994D01*
G02X1370718Y841467I-1186J-525D01*
G02X1368124I-1297J0D01*
G02X1369186Y842743I1298J0D01*
G01X1369281Y842761D01*
G37*
G36*
G01X1329375Y845486D02*
X1328568Y846884D01*
X1328478Y846901D01*
G02X1327422Y848176I242J1275D01*
G02X1330018I1298J0D01*
G02X1329945Y847747I-1297J0D01*
G01X1329914Y847661D01*
X1330721Y846263D01*
X1330811Y846246D01*
G02X1331866Y844971I-243J-1275D01*
G02X1329272I-1297J0D01*
G02X1329344Y845400I1297J3D01*
G01X1329375Y845486D01*
G37*
G36*
G01X1336775D02*
X1335968Y846884D01*
X1335878Y846901D01*
G02X1334822Y848176I242J1275D01*
G02X1337418I1298J0D01*
G02X1337345Y847747I-1297J0D01*
G01X1337314Y847661D01*
X1338121Y846263D01*
X1338211Y846246D01*
G02X1339266Y844971I-243J-1275D01*
G02X1336672I-1297J0D01*
G02X1336744Y845400I1297J3D01*
G01X1336775Y845486D01*
G37*
G36*
G01X1344175D02*
X1343368Y846884D01*
X1343278Y846901D01*
G02X1342222Y848176I242J1275D01*
G02X1344818I1298J0D01*
G02X1344745Y847747I-1297J0D01*
G01X1344714Y847661D01*
X1345521Y846263D01*
X1345611Y846246D01*
G02X1346666Y844971I-243J-1275D01*
G02X1344072I-1297J0D01*
G02X1344144Y845400I1297J3D01*
G01X1344175Y845486D01*
G37*
G36*
G01X1351575D02*
X1350768Y846884D01*
X1350678Y846901D01*
G02X1349622Y848176I242J1275D01*
G02X1352218I1298J0D01*
G02X1352145Y847747I-1297J0D01*
G01X1352114Y847661D01*
X1352921Y846263D01*
X1353011Y846246D01*
G02X1354066Y844971I-243J-1275D01*
G02X1351472I-1297J0D01*
G02X1351544Y845400I1297J3D01*
G01X1351575Y845486D01*
G37*
G36*
G01X1358975D02*
X1358168Y846884D01*
X1358078Y846901D01*
G02X1357022Y848176I242J1275D01*
G02X1359618I1298J0D01*
G02X1359545Y847747I-1297J0D01*
G01X1359514Y847661D01*
X1360321Y846263D01*
X1360411Y846246D01*
G02X1361466Y844971I-243J-1275D01*
G02X1358872I-1297J0D01*
G02X1358944Y845400I1297J3D01*
G01X1358975Y845486D01*
G37*
G36*
G01X1366375D02*
X1365568Y846884D01*
X1365478Y846901D01*
G02X1364422Y848176I242J1275D01*
G02X1367018I1298J0D01*
G02X1366945Y847747I-1297J0D01*
G01X1366914Y847661D01*
X1367721Y846263D01*
X1367811Y846246D01*
G02X1368866Y844971I-243J-1275D01*
G02X1366272I-1297J0D01*
G02X1366344Y845400I1297J3D01*
G01X1366375Y845486D01*
G37*
G36*
G01X1324868Y849468D02*
X1325675Y850865D01*
X1325644Y850952D01*
G02X1325572Y851380I1225J426D01*
G02X1328166I1297J0D01*
G02X1327111Y850105I-1298J0D01*
G01X1327021Y850088D01*
X1326214Y848691D01*
X1326245Y848604D01*
G02X1326318Y848176I-1225J-429D01*
G02X1323722I-1298J0D01*
G02X1324778Y849451I1298J0D01*
G01X1324868Y849468D01*
G37*
G36*
G01X1353426Y855099D02*
X1352619Y856497D01*
X1352529Y856514D01*
G02X1351474Y857789I243J1275D01*
G02X1354068I1297J0D01*
G02X1353996Y857360I-1297J-3D01*
G01X1353965Y857274D01*
X1354772Y855876D01*
X1354862Y855859D01*
G02X1355918Y854584I-242J-1275D01*
G02X1353322I-1298J0D01*
G02X1353395Y855013I1297J0D01*
G01X1353426Y855099D01*
G37*
G36*
G01X1360826D02*
X1360019Y856497D01*
X1359929Y856514D01*
G02X1358874Y857789I243J1275D01*
G02X1361468I1297J0D01*
G02X1361396Y857360I-1297J-3D01*
G01X1361365Y857274D01*
X1362172Y855876D01*
X1362262Y855859D01*
G02X1363318Y854584I-242J-1275D01*
G02X1360722I-1298J0D01*
G02X1360795Y855013I1297J0D01*
G01X1360826Y855099D01*
G37*
G36*
G01X1368226D02*
X1367419Y856497D01*
X1367329Y856514D01*
G02X1366274Y857789I243J1275D01*
G02X1368868I1297J0D01*
G02X1368796Y857360I-1297J-3D01*
G01X1368765Y857274D01*
X1369572Y855876D01*
X1369662Y855859D01*
G02X1370718Y854584I-242J-1275D01*
G02X1368122I-1298J0D01*
G02X1368195Y855013I1297J0D01*
G01X1368226Y855099D01*
G37*
G36*
G01X1356319Y859081D02*
X1357126Y860478D01*
X1357095Y860565D01*
G02X1357022Y860993I1225J429D01*
G02X1359618I1298J0D01*
G02X1358562Y859718I-1298J0D01*
G01X1358472Y859701D01*
X1357665Y858304D01*
X1357696Y858217D01*
G02X1357768Y857789I-1225J-426D01*
G02X1355174I-1297J0D01*
G02X1356229Y859064I1298J0D01*
G01X1356319Y859081D01*
G37*
G36*
G01X1363719D02*
X1364526Y860478D01*
X1364495Y860565D01*
G02X1364422Y860993I1225J429D01*
G02X1367018I1298J0D01*
G02X1365962Y859718I-1298J0D01*
G01X1365872Y859701D01*
X1365065Y858304D01*
X1365096Y858217D01*
G02X1365168Y857789I-1225J-426D01*
G02X1362574I-1297J0D01*
G02X1363629Y859064I1298J0D01*
G01X1363719Y859081D01*
G37*
G36*
G01X1368226Y867916D02*
X1367419Y869314D01*
X1367329Y869331D01*
G02X1366274Y870606I243J1275D01*
G02X1368868I1297J0D01*
G02X1368796Y870177I-1297J-3D01*
G01X1368765Y870091D01*
X1369572Y868693D01*
X1369662Y868676D01*
G02X1370718Y867401I-242J-1275D01*
G02X1368122I-1298J0D01*
G02X1368195Y867830I1297J0D01*
G01X1368226Y867916D01*
G37*
G36*
G01X1363719Y871898D02*
X1364526Y873295D01*
X1364495Y873382D01*
G02X1364422Y873810I1225J429D01*
G02X1367018I1298J0D01*
G02X1365962Y872535I-1298J0D01*
G01X1365872Y872518D01*
X1365065Y871121D01*
X1365096Y871034D01*
G02X1365168Y870606I-1225J-426D01*
G02X1362574I-1297J0D01*
G02X1363629Y871881I1298J0D01*
G01X1363719Y871898D01*
G37*
G36*
G01X1371119D02*
X1371926Y873295D01*
X1371895Y873382D01*
G02X1371822Y873810I1225J429D01*
G02X1374418I1298J0D01*
G02X1373362Y872535I-1298J0D01*
G01X1373272Y872518D01*
X1372465Y871121D01*
X1372496Y871034D01*
G02X1372568Y870606I-1225J-426D01*
G02X1369974I-1297J0D01*
G02X1371029Y871881I1298J0D01*
G01X1371119Y871898D01*
G37*
G36*
G01X1378519D02*
X1379326Y873295D01*
X1379295Y873382D01*
G02X1379222Y873810I1225J429D01*
G02X1381818I1298J0D01*
G02X1380762Y872535I-1298J0D01*
G01X1380672Y872518D01*
X1379865Y871121D01*
X1379896Y871034D01*
G02X1379968Y870606I-1225J-426D01*
G02X1377374I-1297J0D01*
G02X1378429Y871881I1298J0D01*
G01X1378519Y871898D01*
G37*
G36*
G01X1368225Y880734D02*
X1367419Y882131D01*
X1367329Y882148D01*
G02X1366274Y883423I243J1275D01*
G02X1368868I1297J0D01*
G02X1368796Y882994I-1297J-3D01*
G01X1368765Y882908D01*
X1369571Y881511D01*
X1369661Y881494D01*
G02X1370718Y880219I-240J-1275D01*
G02X1368122I-1298J0D01*
G02X1368195Y880647I1298J-1D01*
G01X1368225Y880734D01*
G37*
G36*
G01X1375625D02*
X1374819Y882131D01*
X1374729Y882148D01*
G02X1373674Y883423I243J1275D01*
G02X1376268I1297J0D01*
G02X1376196Y882994I-1297J-3D01*
G01X1376165Y882908D01*
X1376971Y881511D01*
X1377061Y881494D01*
G02X1378118Y880219I-240J-1275D01*
G02X1375522I-1298J0D01*
G02X1375595Y880647I1298J-1D01*
G01X1375625Y880734D01*
G37*
G36*
G01X1363719Y884715D02*
X1364526Y886112D01*
X1364495Y886199D01*
G02X1364422Y886627I1225J429D01*
G02X1367018I1298J0D01*
G02X1365962Y885352I-1298J0D01*
G01X1365872Y885335D01*
X1365065Y883938D01*
X1365096Y883851D01*
G02X1365168Y883423I-1225J-426D01*
G02X1362574I-1297J0D01*
G02X1363629Y884698I1298J0D01*
G01X1363719Y884715D01*
G37*
G36*
G01X1371119D02*
X1371926Y886112D01*
X1371895Y886199D01*
G02X1371822Y886627I1225J429D01*
G02X1374418I1298J0D01*
G02X1373362Y885352I-1298J0D01*
G01X1373272Y885335D01*
X1372465Y883938D01*
X1372496Y883851D01*
G02X1372568Y883423I-1225J-426D01*
G02X1369974I-1297J0D01*
G02X1371029Y884698I1298J0D01*
G01X1371119Y884715D01*
G37*
G36*
G01X1378519D02*
X1379326Y886112D01*
X1379295Y886199D01*
G02X1379222Y886627I1225J429D01*
G02X1381818I1298J0D01*
G02X1380762Y885352I-1298J0D01*
G01X1380672Y885335D01*
X1379865Y883938D01*
X1379896Y883851D01*
G02X1379968Y883423I-1225J-426D01*
G02X1377374I-1297J0D01*
G02X1378429Y884698I1298J0D01*
G01X1378519Y884715D01*
G37*
G36*
G01X1404852Y1077879D02*
X1405659Y1079276D01*
X1405628Y1079363D01*
G02X1405556Y1079791I1225J426D01*
G02X1408150I1297J0D01*
G02X1407095Y1078516I-1298J0D01*
G01X1407005Y1078499D01*
X1406198Y1077101D01*
X1406228Y1077015D01*
G02X1406300Y1076587I-1225J-426D01*
G02X1403706I-1297J0D01*
G02X1404762Y1077862I1298J0D01*
G01X1404852Y1077879D01*
G37*
G36*
G01X1405658Y1086715D02*
X1404851Y1088112D01*
X1404761Y1088129D01*
G02X1403706Y1089404I243J1275D01*
G02X1406300I1297J0D01*
G02X1406228Y1088976I-1297J-2D01*
G01X1406197Y1088889D01*
X1407004Y1087492D01*
X1407094Y1087475D01*
G02X1408150Y1086200I-242J-1275D01*
G02X1405554I-1298J0D01*
G02X1405627Y1086629I1297J0D01*
G01X1405658Y1086715D01*
G37*
G36*
G01X1450107Y1138083D02*
X1449263Y1139679D01*
X1449168Y1139697D01*
G02X1448106Y1140973I236J1276D01*
G02X1450700I1297J0D01*
G02X1450589Y1140448I-1297J0D01*
G01X1450550Y1140359D01*
X1451394Y1138763D01*
X1451489Y1138745D01*
G02X1452552Y1137469I-234J-1276D01*
G02X1449956I-1298J0D01*
G02X1450068Y1137994I1297J-2D01*
G01X1450107Y1138083D01*
G37*
G36*
G01X1474516Y730492D02*
G02X1473515Y728758I-2002J0D01*
G01X1469877Y726657D01*
G02X1468878Y726390I-999J1736D01*
G01X1468876D01*
G02X1466874Y728392I0J2002D01*
G02X1467875Y730126I2002J0D01*
G01X1471513Y732227D01*
G02X1472512Y732494I999J-1736D01*
G01X1472514D01*
G02X1474516Y730492I0J-2002D01*
G37*
G36*
G01X1477716Y717492D02*
G02X1476715Y715758I-2002J0D01*
G01X1473077Y713657D01*
G02X1472078Y713390I-999J1736D01*
G01X1472076D01*
G02X1470074Y715392I0J2002D01*
G02X1471075Y717126I2002J0D01*
G01X1474713Y719227D01*
G02X1475712Y719494I999J-1736D01*
G01X1475714D01*
G02X1477716Y717492I0J-2002D01*
G37*
G36*
G01Y702992D02*
G02X1476715Y701258I-2002J0D01*
G01X1473077Y699157D01*
G02X1472078Y698890I-999J1736D01*
G01X1472076D01*
G02X1470074Y700892I0J2002D01*
G02X1471075Y702626I2002J0D01*
G01X1474713Y704727D01*
G02X1475712Y704994I999J-1736D01*
G01X1475714D01*
G02X1477716Y702992I0J-2002D01*
G37*
G36*
G01Y688492D02*
G02X1476715Y686758I-2002J0D01*
G01X1473077Y684657D01*
G02X1472078Y684390I-999J1736D01*
G01X1472076D01*
G02X1470074Y686392I0J2002D01*
G02X1471075Y688126I2002J0D01*
G01X1474713Y690227D01*
G02X1475712Y690494I999J-1736D01*
G01X1475714D01*
G02X1477716Y688492I0J-2002D01*
G37*
G36*
G01Y673992D02*
G02X1476715Y672258I-2002J0D01*
G01X1473077Y670157D01*
G02X1472078Y669890I-999J1736D01*
G01X1472076D01*
G02X1470074Y671892I0J2002D01*
G02X1471075Y673626I2002J0D01*
G01X1474713Y675727D01*
G02X1475712Y675994I999J-1736D01*
G01X1475714D01*
G02X1477716Y673992I0J-2002D01*
G37*
G36*
G01Y659492D02*
G02X1476715Y657758I-2002J0D01*
G01X1473077Y655657D01*
G02X1472078Y655390I-999J1736D01*
G01X1472076D01*
G02X1470074Y657392I0J2002D01*
G02X1471075Y659126I2002J0D01*
G01X1474713Y661227D01*
G02X1475712Y661494I999J-1736D01*
G01X1475714D01*
G02X1477716Y659492I0J-2002D01*
G37*
G36*
G01X1455174Y716992D02*
G02X1457176Y718994I2002J0D01*
G01X1457178D01*
G02X1458177Y718727I0J-2003D01*
G01X1461815Y716626D01*
G02X1462816Y714892I-1001J-1734D01*
G02X1460814Y712890I-2002J0D01*
G01X1460812D01*
G02X1459813Y713157I0J2003D01*
G01X1456175Y715258D01*
G02X1455174Y716992I1001J1734D01*
G37*
G36*
G01Y704992D02*
G02X1457176Y706994I2002J0D01*
G01X1457178D01*
G02X1458177Y706727I0J-2003D01*
G01X1461815Y704626D01*
G02X1462816Y702892I-1001J-1734D01*
G02X1460814Y700890I-2002J0D01*
G01X1460812D01*
G02X1459813Y701157I0J2003D01*
G01X1456175Y703258D01*
G02X1455174Y704992I1001J1734D01*
G37*
G36*
G01Y692992D02*
G02X1457176Y694994I2002J0D01*
G01X1457178D01*
G02X1458177Y694727I0J-2003D01*
G01X1461815Y692626D01*
G02X1462816Y690892I-1001J-1734D01*
G02X1460814Y688890I-2002J0D01*
G01X1460812D01*
G02X1459813Y689157I0J2003D01*
G01X1456175Y691258D01*
G02X1455174Y692992I1001J1734D01*
G37*
G36*
G01Y680992D02*
G02X1457176Y682994I2002J0D01*
G01X1457178D01*
G02X1458177Y682727I0J-2003D01*
G01X1461815Y680626D01*
G02X1462816Y678892I-1001J-1734D01*
G02X1460814Y676890I-2002J0D01*
G01X1460812D01*
G02X1459813Y677157I0J2003D01*
G01X1456175Y679258D01*
G02X1455174Y680992I1001J1734D01*
G37*
G36*
G01Y668992D02*
G02X1457176Y670994I2002J0D01*
G01X1457178D01*
G02X1458177Y670727I0J-2003D01*
G01X1461815Y668626D01*
G02X1462816Y666892I-1001J-1734D01*
G02X1460814Y664890I-2002J0D01*
G01X1460812D01*
G02X1459813Y665157I0J2003D01*
G01X1456175Y667258D01*
G02X1455174Y668992I1001J1734D01*
G37*
G36*
G01Y656992D02*
G02X1457176Y658994I2002J0D01*
G01X1457178D01*
G02X1458177Y658727I0J-2003D01*
G01X1461815Y656626D01*
G02X1462816Y654892I-1001J-1734D01*
G02X1460814Y652890I-2002J0D01*
G01X1460812D01*
G02X1459813Y653157I0J2003D01*
G01X1456175Y655258D01*
G02X1455174Y656992I1001J1734D01*
G37*
G36*
G01X1471460Y631900D02*
X1468060D01*
G02Y634904I0J1502D01*
G01X1471460D01*
G02Y631900I0J-1502D01*
G37*
G36*
G01X1384772Y844971D02*
G02X1387366I1297J0D01*
G02X1386304Y843695I-1298J0D01*
G01X1386209Y843677D01*
X1385368Y842082D01*
X1385407Y841994D01*
G02X1385518Y841467I-1186J-525D01*
G02X1382924I-1297J0D01*
G02X1383986Y842743I1298J0D01*
G01X1384081Y842761D01*
X1384922Y844356D01*
X1384883Y844444D01*
G02X1384772Y844971I1186J525D01*
G37*
G36*
G01X1392172D02*
G02X1394766I1297J0D01*
G02X1393704Y843695I-1298J0D01*
G01X1393609Y843677D01*
X1392768Y842082D01*
X1392807Y841994D01*
G02X1392918Y841467I-1186J-525D01*
G02X1390324I-1297J0D01*
G02X1391386Y842743I1298J0D01*
G01X1391481Y842761D01*
X1392322Y844356D01*
X1392283Y844444D01*
G02X1392172Y844971I1186J525D01*
G37*
G36*
G01X1399572D02*
G02X1402166I1297J0D01*
G02X1401104Y843695I-1298J0D01*
G01X1401009Y843677D01*
X1400168Y842082D01*
X1400207Y841994D01*
G02X1400318Y841467I-1186J-525D01*
G02X1397724I-1297J0D01*
G02X1398786Y842743I1298J0D01*
G01X1398881Y842761D01*
X1399722Y844356D01*
X1399683Y844444D01*
G02X1399572Y844971I1186J525D01*
G37*
G36*
G01X1379222Y848176D02*
G02X1381818I1298J0D01*
G02X1381745Y847747I-1297J0D01*
G01X1381714Y847661D01*
X1382521Y846263D01*
X1382611Y846246D01*
G02X1383666Y844971I-243J-1275D01*
G02X1381072I-1297J0D01*
G02X1381144Y845400I1297J3D01*
G01X1381175Y845486D01*
X1380368Y846884D01*
X1380278Y846901D01*
G02X1379222Y848176I242J1275D01*
G37*
G36*
G01X1386622D02*
G02X1389218I1298J0D01*
G02X1389145Y847747I-1297J0D01*
G01X1389114Y847661D01*
X1389921Y846263D01*
X1390011Y846246D01*
G02X1391066Y844971I-243J-1275D01*
G02X1388472I-1297J0D01*
G02X1388544Y845400I1297J3D01*
G01X1388575Y845486D01*
X1387768Y846884D01*
X1387678Y846901D01*
G02X1386622Y848176I242J1275D01*
G37*
G36*
G01X1394022D02*
G02X1396618I1298J0D01*
G02X1396545Y847747I-1297J0D01*
G01X1396514Y847661D01*
X1397321Y846263D01*
X1397411Y846246D01*
G02X1398466Y844971I-243J-1275D01*
G02X1395872I-1297J0D01*
G02X1395944Y845400I1297J3D01*
G01X1395975Y845486D01*
X1395168Y846884D01*
X1395078Y846901D01*
G02X1394022Y848176I242J1275D01*
G37*
G36*
G01X1401422D02*
G02X1404018I1298J0D01*
G02X1403945Y847747I-1297J0D01*
G01X1403914Y847661D01*
X1404721Y846263D01*
X1404811Y846246D01*
G02X1405866Y844971I-243J-1275D01*
G02X1403272I-1297J0D01*
G02X1403344Y845400I1297J3D01*
G01X1403375Y845486D01*
X1402568Y846884D01*
X1402478Y846901D01*
G02X1401422Y848176I242J1275D01*
G37*
G36*
G01X1406420Y849474D02*
G02X1407459Y848954I0J-1298D01*
G01X1409081D01*
G02X1410120Y849474I1039J-778D01*
G02Y846878I0J-1298D01*
G02X1409081Y847398I0J1298D01*
G01X1407459D01*
G02X1406420Y846878I-1039J778D01*
G02Y849474I0J1298D01*
G37*
G36*
G01X1412522Y848176D02*
G02X1415118I1298J0D01*
G02X1414062Y846901I-1298J0D01*
G01X1413972Y846884D01*
X1413164Y845485D01*
X1413194Y845398D01*
G02X1413266Y844973I-1225J-426D01*
G01Y844971D01*
G02X1410672I-1297J0D01*
G02X1411728Y846246I1298J0D01*
G01X1411818Y846263D01*
X1412625Y847662D01*
X1412595Y847748D01*
G02X1412522Y848176I1225J429D01*
G37*
G36*
G01X1381074Y857789D02*
G02X1383668I1297J0D01*
G02X1383596Y857360I-1297J-3D01*
G01X1383565Y857274D01*
X1384372Y855876D01*
X1384462Y855859D01*
G02X1385518Y854584I-242J-1275D01*
G02X1382922I-1298J0D01*
G02X1382995Y855013I1297J0D01*
G01X1383026Y855099D01*
X1382219Y856497D01*
X1382129Y856514D01*
G02X1381074Y857789I243J1275D01*
G37*
G36*
G01X1388474D02*
G02X1391068I1297J0D01*
G02X1390996Y857360I-1297J-3D01*
G01X1390965Y857274D01*
X1391772Y855876D01*
X1391862Y855859D01*
G02X1392918Y854584I-242J-1275D01*
G02X1390322I-1298J0D01*
G02X1390395Y855013I1297J0D01*
G01X1390426Y855099D01*
X1389619Y856497D01*
X1389529Y856514D01*
G02X1388474Y857789I243J1275D01*
G37*
G36*
G01X1395874D02*
G02X1398468I1297J0D01*
G02X1398396Y857360I-1297J-3D01*
G01X1398365Y857274D01*
X1399172Y855876D01*
X1399262Y855859D01*
G02X1400318Y854584I-242J-1275D01*
G02X1397722I-1298J0D01*
G02X1397795Y855013I1297J0D01*
G01X1397826Y855099D01*
X1397019Y856497D01*
X1396929Y856514D01*
G02X1395874Y857789I243J1275D01*
G37*
G36*
G01X1403274D02*
G02X1405868I1297J0D01*
G02X1405796Y857360I-1297J-3D01*
G01X1405765Y857274D01*
X1406572Y855876D01*
X1406662Y855859D01*
G02X1407718Y854584I-242J-1275D01*
G02X1405122I-1298J0D01*
G02X1405195Y855013I1297J0D01*
G01X1405226Y855099D01*
X1404419Y856497D01*
X1404329Y856514D01*
G02X1403274Y857789I243J1275D01*
G37*
G36*
G01X1410674D02*
G02X1413268I1297J0D01*
G02X1413196Y857360I-1297J-3D01*
G01X1413165Y857274D01*
X1413972Y855876D01*
X1414062Y855859D01*
G02X1415118Y854584I-242J-1275D01*
G02X1412524I-1297J0D01*
G02X1412596Y855012I1297J2D01*
G01X1412626Y855098D01*
X1411819Y856497D01*
X1411729Y856514D01*
G02X1410674Y857789I243J1275D01*
G37*
G36*
G01X1421774D02*
G02X1424368I1297J0D01*
G02X1423313Y856514I-1298J0D01*
G01X1423223Y856497D01*
X1422415Y855098D01*
X1422445Y855011D01*
G02X1422518Y854584I-1225J-429D01*
G02X1419922I-1298J0D01*
G02X1420980Y855859I1297J0D01*
G01X1421070Y855876D01*
X1421877Y857274D01*
X1421846Y857361D01*
G02X1421774Y857789I1225J426D01*
G37*
G36*
G01X1379222Y860993D02*
G02X1381818I1298J0D01*
G02X1380762Y859718I-1298J0D01*
G01X1380672Y859701D01*
X1379865Y858304D01*
X1379896Y858217D01*
G02X1379968Y857789I-1225J-426D01*
G02X1377374I-1297J0D01*
G02X1378429Y859064I1298J0D01*
G01X1378519Y859081D01*
X1379326Y860478D01*
X1379295Y860565D01*
G02X1379222Y860993I1225J429D01*
G37*
G36*
G01X1386622D02*
G02X1389218I1298J0D01*
G02X1388162Y859718I-1298J0D01*
G01X1388072Y859701D01*
X1387265Y858304D01*
X1387296Y858217D01*
G02X1387368Y857789I-1225J-426D01*
G02X1384774I-1297J0D01*
G02X1385829Y859064I1298J0D01*
G01X1385919Y859081D01*
X1386726Y860478D01*
X1386695Y860565D01*
G02X1386622Y860993I1225J429D01*
G37*
G36*
G01X1394022D02*
G02X1396618I1298J0D01*
G02X1395562Y859718I-1298J0D01*
G01X1395472Y859701D01*
X1394665Y858304D01*
X1394696Y858217D01*
G02X1394768Y857789I-1225J-426D01*
G02X1392174I-1297J0D01*
G02X1393229Y859064I1298J0D01*
G01X1393319Y859081D01*
X1394126Y860478D01*
X1394095Y860565D01*
G02X1394022Y860993I1225J429D01*
G37*
G36*
G01X1401422D02*
G02X1404018I1298J0D01*
G02X1402962Y859718I-1298J0D01*
G01X1402872Y859701D01*
X1402065Y858304D01*
X1402096Y858217D01*
G02X1402168Y857789I-1225J-426D01*
G02X1399574I-1297J0D01*
G02X1400629Y859064I1298J0D01*
G01X1400719Y859081D01*
X1401526Y860478D01*
X1401495Y860565D01*
G02X1401422Y860993I1225J429D01*
G37*
G36*
G01X1408824D02*
G02X1411418I1297J0D01*
G02X1410363Y859718I-1298J0D01*
G01X1410273Y859701D01*
X1409466Y858303D01*
X1409496Y858217D01*
G02X1409568Y857789I-1225J-426D01*
G02X1406974I-1297J0D01*
G02X1408030Y859064I1298J0D01*
G01X1408120Y859081D01*
X1408927Y860478D01*
X1408896Y860565D01*
G02X1408824Y860993I1225J426D01*
G37*
G36*
G01X1416222D02*
G02X1418818I1298J0D01*
G02X1418745Y860564I-1297J0D01*
G01X1418714Y860478D01*
X1419520Y859081D01*
X1419610Y859064D01*
G02X1420668Y857789I-239J-1275D01*
G02X1418074I-1297J0D01*
G02X1418145Y858215I1297J3D01*
G01X1418176Y858302D01*
X1417368Y859701D01*
X1417278Y859718D01*
G02X1416222Y860993I242J1275D01*
G37*
G36*
G01X1423624D02*
G02X1426218I1297J0D01*
G02X1426146Y860564I-1297J-3D01*
G01X1426115Y860478D01*
X1426921Y859081D01*
X1427011Y859064D01*
G02X1428068Y857789I-240J-1275D01*
G02X1425474I-1297J0D01*
G01Y857791D01*
G02X1425546Y858216I1297J-1D01*
G01X1425576Y858303D01*
X1424769Y859701D01*
X1424679Y859718D01*
G02X1423624Y860993I243J1275D01*
G37*
G36*
G01X1392174Y870606D02*
G02X1394768I1297J0D01*
G02X1393713Y869331I-1298J0D01*
G01X1393623Y869314D01*
X1392815Y867915D01*
X1392845Y867828D01*
G02X1392918Y867401I-1225J-429D01*
G02X1390322I-1298J0D01*
G02X1391380Y868676I1297J0D01*
G01X1391470Y868693D01*
X1392277Y870091D01*
X1392246Y870178D01*
G02X1392174Y870606I1225J426D01*
G37*
G36*
G01X1399574D02*
G02X1402168I1297J0D01*
G02X1401113Y869331I-1298J0D01*
G01X1401023Y869314D01*
X1400215Y867915D01*
X1400245Y867828D01*
G02X1400318Y867401I-1225J-429D01*
G02X1397722I-1298J0D01*
G02X1398780Y868676I1297J0D01*
G01X1398870Y868693D01*
X1399677Y870091D01*
X1399646Y870178D01*
G02X1399574Y870606I1225J426D01*
G37*
G36*
G01X1406974D02*
G02X1409568I1297J0D01*
G02X1408513Y869331I-1298J0D01*
G01X1408423Y869314D01*
X1407615Y867915D01*
X1407645Y867828D01*
G02X1407718Y867401I-1225J-429D01*
G02X1405122I-1298J0D01*
G02X1406180Y868676I1297J0D01*
G01X1406270Y868693D01*
X1407077Y870091D01*
X1407046Y870178D01*
G02X1406974Y870606I1225J426D01*
G37*
G36*
G01X1414374D02*
G02X1416968I1297J0D01*
G02X1415913Y869331I-1298J0D01*
G01X1415823Y869314D01*
X1415015Y867915D01*
X1415045Y867828D01*
G02X1415118Y867401I-1225J-429D01*
G02X1412522I-1298J0D01*
G02X1413580Y868676I1297J0D01*
G01X1413670Y868693D01*
X1414477Y870091D01*
X1414446Y870178D01*
G02X1414374Y870606I1225J426D01*
G37*
G36*
G01X1421774D02*
G02X1424368I1297J0D01*
G02X1423313Y869331I-1298J0D01*
G01X1423223Y869314D01*
X1422415Y867915D01*
X1422445Y867828D01*
G02X1422518Y867401I-1225J-429D01*
G02X1419922I-1298J0D01*
G02X1420980Y868676I1297J0D01*
G01X1421070Y868693D01*
X1421877Y870091D01*
X1421846Y870178D01*
G02X1421774Y870606I1225J426D01*
G37*
G36*
G01X1394022Y873810D02*
G02X1396618I1298J0D01*
G02X1396545Y873381I-1297J0D01*
G01X1396514Y873295D01*
X1397320Y871898D01*
X1397410Y871881D01*
G02X1398468Y870606I-239J-1275D01*
G02X1395874I-1297J0D01*
G02X1395945Y871032I1297J3D01*
G01X1395976Y871119D01*
X1395168Y872518D01*
X1395078Y872535D01*
G02X1394022Y873810I242J1275D01*
G37*
G36*
G01X1401422D02*
G02X1404018I1298J0D01*
G02X1403945Y873381I-1297J0D01*
G01X1403914Y873295D01*
X1404720Y871898D01*
X1404810Y871881D01*
G02X1405868Y870606I-239J-1275D01*
G02X1403274I-1297J0D01*
G02X1403345Y871032I1297J3D01*
G01X1403376Y871119D01*
X1402568Y872518D01*
X1402478Y872535D01*
G02X1401422Y873810I242J1275D01*
G37*
G36*
G01X1408824D02*
G02X1411418I1297J0D01*
G02X1411346Y873381I-1297J-3D01*
G01X1411315Y873295D01*
X1412121Y871898D01*
X1412211Y871881D01*
G02X1413268Y870606I-240J-1275D01*
G02X1410674I-1297J0D01*
G01Y870608D01*
G02X1410746Y871033I1297J-1D01*
G01X1410776Y871120D01*
X1409969Y872518D01*
X1409879Y872535D01*
G02X1408824Y873810I243J1275D01*
G37*
G36*
G01X1416222D02*
G02X1418818I1298J0D01*
G02X1418745Y873381I-1297J0D01*
G01X1418714Y873295D01*
X1419520Y871898D01*
X1419610Y871881D01*
G02X1420668Y870606I-239J-1275D01*
G02X1418074I-1297J0D01*
G02X1418145Y871032I1297J3D01*
G01X1418176Y871119D01*
X1417368Y872518D01*
X1417278Y872535D01*
G02X1416222Y873810I242J1275D01*
G37*
G36*
G01X1423624D02*
G02X1426218I1297J0D01*
G02X1426146Y873381I-1297J-3D01*
G01X1426115Y873295D01*
X1426921Y871898D01*
X1427011Y871881D01*
G02X1428068Y870606I-240J-1275D01*
G02X1425474I-1297J0D01*
G01Y870608D01*
G02X1425546Y871033I1297J-1D01*
G01X1425576Y871120D01*
X1424769Y872518D01*
X1424679Y872535D01*
G02X1423624Y873810I243J1275D01*
G37*
G36*
G01X1388474Y883423D02*
G02X1391068I1297J0D01*
G02X1390996Y882994I-1297J-3D01*
G01X1390965Y882908D01*
X1391771Y881511D01*
X1391861Y881494D01*
G02X1392918Y880219I-240J-1275D01*
G02X1390322I-1298J0D01*
G02X1390395Y880647I1298J-1D01*
G01X1390425Y880734D01*
X1389619Y882131D01*
X1389529Y882148D01*
G02X1388474Y883423I243J1275D01*
G37*
G36*
G01X1395874D02*
G02X1398468I1297J0D01*
G02X1398396Y882994I-1297J-3D01*
G01X1398365Y882908D01*
X1399171Y881511D01*
X1399261Y881494D01*
G02X1400318Y880219I-240J-1275D01*
G02X1397722I-1298J0D01*
G02X1397795Y880647I1298J-1D01*
G01X1397825Y880734D01*
X1397019Y882131D01*
X1396929Y882148D01*
G02X1395874Y883423I243J1275D01*
G37*
G36*
G01X1403274D02*
G02X1405868I1297J0D01*
G02X1405796Y882994I-1297J-3D01*
G01X1405765Y882908D01*
X1406571Y881511D01*
X1406661Y881494D01*
G02X1407718Y880219I-240J-1275D01*
G02X1405122I-1298J0D01*
G02X1405195Y880647I1298J-1D01*
G01X1405225Y880734D01*
X1404419Y882131D01*
X1404329Y882148D01*
G02X1403274Y883423I243J1275D01*
G37*
G36*
G01X1410674D02*
G02X1413268I1297J0D01*
G02X1413196Y882994I-1297J-3D01*
G01X1413165Y882908D01*
X1413971Y881511D01*
X1414061Y881494D01*
G02X1415118Y880219I-240J-1275D01*
G02X1412522I-1298J0D01*
G02X1412595Y880647I1298J-1D01*
G01X1412625Y880734D01*
X1411819Y882131D01*
X1411729Y882148D01*
G02X1410674Y883423I243J1275D01*
G37*
G36*
G01X1418074D02*
G02X1420668I1297J0D01*
G02X1420596Y882994I-1297J-3D01*
G01X1420565Y882908D01*
X1421371Y881511D01*
X1421461Y881494D01*
G02X1422518Y880219I-240J-1275D01*
G02X1419922I-1298J0D01*
G02X1419995Y880647I1298J-1D01*
G01X1420025Y880734D01*
X1419219Y882131D01*
X1419129Y882148D01*
G02X1418074Y883423I243J1275D01*
G37*
G36*
G01X1394022Y886627D02*
G02X1396618I1298J0D01*
G02X1395562Y885352I-1298J0D01*
G01X1395472Y885335D01*
X1394665Y883938D01*
X1394696Y883851D01*
G02X1394768Y883423I-1225J-426D01*
G02X1392174I-1297J0D01*
G02X1393229Y884698I1298J0D01*
G01X1393319Y884715D01*
X1394126Y886112D01*
X1394095Y886199D01*
G02X1394022Y886627I1225J429D01*
G37*
G36*
G01X1401422D02*
G02X1404018I1298J0D01*
G02X1402962Y885352I-1298J0D01*
G01X1402872Y885335D01*
X1402065Y883938D01*
X1402096Y883851D01*
G02X1402168Y883423I-1225J-426D01*
G02X1399574I-1297J0D01*
G02X1400629Y884698I1298J0D01*
G01X1400719Y884715D01*
X1401526Y886112D01*
X1401495Y886199D01*
G02X1401422Y886627I1225J429D01*
G37*
G36*
G01X1408822D02*
G02X1411418I1298J0D01*
G02X1410362Y885352I-1298J0D01*
G01X1410272Y885335D01*
X1409465Y883938D01*
X1409496Y883851D01*
G02X1409568Y883423I-1225J-426D01*
G02X1406974I-1297J0D01*
G02X1408029Y884698I1298J0D01*
G01X1408119Y884715D01*
X1408926Y886112D01*
X1408895Y886199D01*
G02X1408822Y886627I1225J429D01*
G37*
G36*
G01X1416222D02*
G02X1418818I1298J0D01*
G02X1417762Y885352I-1298J0D01*
G01X1417672Y885335D01*
X1416865Y883938D01*
X1416896Y883851D01*
G02X1416968Y883423I-1225J-426D01*
G02X1414374I-1297J0D01*
G02X1415429Y884698I1298J0D01*
G01X1415519Y884715D01*
X1416326Y886112D01*
X1416295Y886199D01*
G02X1416222Y886627I1225J429D01*
G37*
G36*
G01X1423622D02*
G02X1426218I1298J0D01*
G02X1425162Y885352I-1298J0D01*
G01X1425072Y885335D01*
X1424265Y883938D01*
X1424296Y883851D01*
G02X1424368Y883423I-1225J-426D01*
G02X1421774I-1297J0D01*
G02X1422829Y884698I1298J0D01*
G01X1422919Y884715D01*
X1423726Y886112D01*
X1423695Y886199D01*
G02X1423622Y886627I1225J429D01*
G37*
G36*
G01X1435870Y855876D02*
X1436677Y857274D01*
X1436646Y857361D01*
G02X1436574Y857789I1225J426D01*
G02X1439168I1297J0D01*
G02X1438113Y856514I-1298J0D01*
G01X1438023Y856497D01*
X1437215Y855098D01*
X1437245Y855011D01*
G02X1437318Y854584I-1225J-429D01*
G02X1434722I-1298J0D01*
G02X1435780Y855859I1297J0D01*
G01X1435870Y855876D01*
G37*
G36*
G01X1443270D02*
X1444077Y857274D01*
X1444046Y857361D01*
G02X1443974Y857789I1225J426D01*
G02X1446568I1297J0D01*
G02X1445513Y856514I-1298J0D01*
G01X1445423Y856497D01*
X1444615Y855098D01*
X1444645Y855011D01*
G02X1444718Y854584I-1225J-429D01*
G02X1442122I-1298J0D01*
G02X1443180Y855859I1297J0D01*
G01X1443270Y855876D01*
G37*
G36*
G01X1450670D02*
X1451477Y857274D01*
X1451446Y857361D01*
G02X1451374Y857789I1225J426D01*
G02X1453968I1297J0D01*
G02X1452913Y856514I-1298J0D01*
G01X1452823Y856497D01*
X1452015Y855098D01*
X1452045Y855011D01*
G02X1452118Y854584I-1225J-429D01*
G02X1449522I-1298J0D01*
G02X1450580Y855859I1297J0D01*
G01X1450670Y855876D01*
G37*
G36*
G01X1458070D02*
X1458877Y857274D01*
X1458846Y857361D01*
G02X1458774Y857789I1225J426D01*
G02X1461368I1297J0D01*
G02X1460313Y856514I-1298J0D01*
G01X1460223Y856497D01*
X1459415Y855098D01*
X1459445Y855011D01*
G02X1459518Y854584I-1225J-429D01*
G02X1456922I-1298J0D01*
G02X1457980Y855859I1297J0D01*
G01X1458070Y855876D01*
G37*
G36*
G01X1465470D02*
X1466277Y857274D01*
X1466246Y857361D01*
G02X1466174Y857789I1225J426D01*
G02X1468768I1297J0D01*
G02X1467713Y856514I-1298J0D01*
G01X1467623Y856497D01*
X1466815Y855098D01*
X1466845Y855011D01*
G02X1466918Y854584I-1225J-429D01*
G02X1464322I-1298J0D01*
G02X1465380Y855859I1297J0D01*
G01X1465470Y855876D01*
G37*
G36*
G01X1472870D02*
X1473677Y857274D01*
X1473646Y857361D01*
G02X1473574Y857789I1225J426D01*
G02X1476168I1297J0D01*
G02X1475113Y856514I-1298J0D01*
G01X1475023Y856497D01*
X1474215Y855098D01*
X1474245Y855011D01*
G02X1474318Y854584I-1225J-429D01*
G02X1471722I-1298J0D01*
G02X1472780Y855859I1297J0D01*
G01X1472870Y855876D01*
G37*
G36*
G01X1440376Y858302D02*
X1439568Y859701D01*
X1439478Y859718D01*
G02X1438422Y860993I242J1275D01*
G02X1441018I1298J0D01*
G02X1440945Y860564I-1297J0D01*
G01X1440914Y860478D01*
X1441720Y859081D01*
X1441810Y859064D01*
G02X1442868Y857789I-239J-1275D01*
G02X1440274I-1297J0D01*
G02X1440345Y858215I1297J3D01*
G01X1440376Y858302D01*
G37*
G36*
G01X1447776D02*
X1446968Y859701D01*
X1446878Y859718D01*
G02X1445822Y860993I242J1275D01*
G02X1448418I1298J0D01*
G02X1448345Y860564I-1297J0D01*
G01X1448314Y860478D01*
X1449120Y859081D01*
X1449210Y859064D01*
G02X1450268Y857789I-239J-1275D01*
G02X1447674I-1297J0D01*
G02X1447745Y858215I1297J3D01*
G01X1447776Y858302D01*
G37*
G36*
G01X1455176D02*
X1454368Y859701D01*
X1454278Y859718D01*
G02X1453222Y860993I242J1275D01*
G02X1455818I1298J0D01*
G02X1455745Y860564I-1297J0D01*
G01X1455714Y860478D01*
X1456520Y859081D01*
X1456610Y859064D01*
G02X1457668Y857789I-239J-1275D01*
G02X1455074I-1297J0D01*
G02X1455145Y858215I1297J3D01*
G01X1455176Y858302D01*
G37*
G36*
G01X1462576D02*
X1461768Y859701D01*
X1461678Y859718D01*
G02X1460622Y860993I242J1275D01*
G02X1463218I1298J0D01*
G02X1463145Y860564I-1297J0D01*
G01X1463114Y860478D01*
X1463920Y859081D01*
X1464010Y859064D01*
G02X1465068Y857789I-239J-1275D01*
G02X1462474I-1297J0D01*
G02X1462545Y858215I1297J3D01*
G01X1462576Y858302D01*
G37*
G36*
G01X1469976D02*
X1469168Y859701D01*
X1469078Y859718D01*
G02X1468022Y860993I242J1275D01*
G02X1470618I1298J0D01*
G02X1470545Y860564I-1297J0D01*
G01X1470514Y860478D01*
X1471320Y859081D01*
X1471410Y859064D01*
G02X1472468Y857789I-239J-1275D01*
G02X1469874I-1297J0D01*
G02X1469945Y858215I1297J3D01*
G01X1469976Y858302D01*
G37*
G36*
G01X1435870Y868693D02*
X1436677Y870091D01*
X1436646Y870178D01*
G02X1436574Y870606I1225J426D01*
G02X1439168I1297J0D01*
G02X1438113Y869331I-1298J0D01*
G01X1438023Y869314D01*
X1437215Y867915D01*
X1437245Y867828D01*
G02X1437318Y867401I-1225J-429D01*
G02X1434722I-1298J0D01*
G02X1435780Y868676I1297J0D01*
G01X1435870Y868693D01*
G37*
G36*
G01X1443270D02*
X1444077Y870091D01*
X1444046Y870178D01*
G02X1443974Y870606I1225J426D01*
G02X1446568I1297J0D01*
G02X1445513Y869331I-1298J0D01*
G01X1445423Y869314D01*
X1444615Y867915D01*
X1444645Y867828D01*
G02X1444718Y867401I-1225J-429D01*
G02X1442122I-1298J0D01*
G02X1443180Y868676I1297J0D01*
G01X1443270Y868693D01*
G37*
G36*
G01X1450670D02*
X1451477Y870091D01*
X1451446Y870178D01*
G02X1451374Y870606I1225J426D01*
G02X1453968I1297J0D01*
G02X1452913Y869331I-1298J0D01*
G01X1452823Y869314D01*
X1452015Y867915D01*
X1452045Y867828D01*
G02X1452118Y867401I-1225J-429D01*
G02X1449522I-1298J0D01*
G02X1450580Y868676I1297J0D01*
G01X1450670Y868693D01*
G37*
G36*
G01X1458070D02*
X1458877Y870091D01*
X1458846Y870178D01*
G02X1458774Y870606I1225J426D01*
G02X1461368I1297J0D01*
G02X1460313Y869331I-1298J0D01*
G01X1460223Y869314D01*
X1459415Y867915D01*
X1459445Y867828D01*
G02X1459518Y867401I-1225J-429D01*
G02X1456922I-1298J0D01*
G02X1457980Y868676I1297J0D01*
G01X1458070Y868693D01*
G37*
G36*
G01X1465470D02*
X1466277Y870091D01*
X1466246Y870178D01*
G02X1466174Y870606I1225J426D01*
G02X1468768I1297J0D01*
G02X1467713Y869331I-1298J0D01*
G01X1467623Y869314D01*
X1466815Y867915D01*
X1466845Y867828D01*
G02X1466918Y867401I-1225J-429D01*
G02X1464322I-1298J0D01*
G02X1465380Y868676I1297J0D01*
G01X1465470Y868693D01*
G37*
G36*
G01X1472870D02*
X1473677Y870091D01*
X1473646Y870178D01*
G02X1473574Y870606I1225J426D01*
G02X1476168I1297J0D01*
G02X1475113Y869331I-1298J0D01*
G01X1475023Y869314D01*
X1474215Y867915D01*
X1474245Y867828D01*
G02X1474318Y867401I-1225J-429D01*
G02X1471722I-1298J0D01*
G02X1472780Y868676I1297J0D01*
G01X1472870Y868693D01*
G37*
G36*
G01X1440376Y871119D02*
X1439568Y872518D01*
X1439478Y872535D01*
G02X1438422Y873810I242J1275D01*
G02X1441018I1298J0D01*
G02X1440945Y873381I-1297J0D01*
G01X1440914Y873295D01*
X1441720Y871898D01*
X1441810Y871881D01*
G02X1442868Y870606I-239J-1275D01*
G02X1440274I-1297J0D01*
G02X1440345Y871032I1297J3D01*
G01X1440376Y871119D01*
G37*
G36*
G01X1455176D02*
X1454368Y872518D01*
X1454278Y872535D01*
G02X1453222Y873810I242J1275D01*
G02X1455818I1298J0D01*
G02X1455745Y873381I-1297J0D01*
G01X1455714Y873295D01*
X1456520Y871898D01*
X1456610Y871881D01*
G02X1457668Y870606I-239J-1275D01*
G02X1455074I-1297J0D01*
G02X1455145Y871032I1297J3D01*
G01X1455176Y871119D01*
G37*
G36*
G01X1462576D02*
X1461768Y872518D01*
X1461678Y872535D01*
G02X1460622Y873810I242J1275D01*
G02X1463218I1298J0D01*
G02X1463145Y873381I-1297J0D01*
G01X1463114Y873295D01*
X1463920Y871898D01*
X1464010Y871881D01*
G02X1465068Y870606I-239J-1275D01*
G02X1462474I-1297J0D01*
G02X1462545Y871032I1297J3D01*
G01X1462576Y871119D01*
G37*
G36*
G01X1469976D02*
X1469168Y872518D01*
X1469078Y872535D01*
G02X1468022Y873810I242J1275D01*
G02X1470618I1298J0D01*
G02X1470545Y873381I-1297J0D01*
G01X1470514Y873295D01*
X1471320Y871898D01*
X1471410Y871881D01*
G02X1472468Y870606I-239J-1275D01*
G02X1469874I-1297J0D01*
G02X1469945Y871032I1297J3D01*
G01X1469976Y871119D01*
G37*
G36*
G01X1434825Y880734D02*
X1434019Y882131D01*
X1433929Y882148D01*
G02X1432874Y883423I243J1275D01*
G02X1435468I1297J0D01*
G02X1435396Y882994I-1297J-3D01*
G01X1435365Y882908D01*
X1436171Y881511D01*
X1436261Y881494D01*
G02X1437318Y880219I-240J-1275D01*
G02X1434722I-1298J0D01*
G02X1434795Y880647I1298J-1D01*
G01X1434825Y880734D01*
G37*
G36*
G01X1442225D02*
X1441419Y882131D01*
X1441329Y882148D01*
G02X1440274Y883423I243J1275D01*
G02X1442868I1297J0D01*
G02X1442796Y882994I-1297J-3D01*
G01X1442765Y882908D01*
X1443571Y881511D01*
X1443661Y881494D01*
G02X1444718Y880219I-240J-1275D01*
G02X1442122I-1298J0D01*
G02X1442195Y880647I1298J-1D01*
G01X1442225Y880734D01*
G37*
G36*
G01X1449625D02*
X1448819Y882131D01*
X1448729Y882148D01*
G02X1447674Y883423I243J1275D01*
G02X1450268I1297J0D01*
G02X1450196Y882994I-1297J-3D01*
G01X1450165Y882908D01*
X1450971Y881511D01*
X1451061Y881494D01*
G02X1452118Y880219I-240J-1275D01*
G02X1449522I-1298J0D01*
G02X1449595Y880647I1298J-1D01*
G01X1449625Y880734D01*
G37*
G36*
G01X1457025D02*
X1456219Y882131D01*
X1456129Y882148D01*
G02X1455074Y883423I243J1275D01*
G02X1457668I1297J0D01*
G02X1457596Y882994I-1297J-3D01*
G01X1457565Y882908D01*
X1458371Y881511D01*
X1458461Y881494D01*
G02X1459518Y880219I-240J-1275D01*
G02X1456922I-1298J0D01*
G02X1456995Y880647I1298J-1D01*
G01X1457025Y880734D01*
G37*
G36*
G01X1464425D02*
X1463619Y882131D01*
X1463529Y882148D01*
G02X1462474Y883423I243J1275D01*
G02X1465068I1297J0D01*
G02X1464996Y882994I-1297J-3D01*
G01X1464965Y882908D01*
X1465771Y881511D01*
X1465861Y881494D01*
G02X1466918Y880219I-240J-1275D01*
G02X1464322I-1298J0D01*
G02X1464395Y880647I1298J-1D01*
G01X1464425Y880734D01*
G37*
G36*
G01X1471825D02*
X1471019Y882131D01*
X1470929Y882148D01*
G02X1469874Y883423I243J1275D01*
G02X1472468I1297J0D01*
G02X1472396Y882994I-1297J-3D01*
G01X1472365Y882908D01*
X1473171Y881511D01*
X1473261Y881494D01*
G02X1474318Y880219I-240J-1275D01*
G02X1471722I-1298J0D01*
G02X1471795Y880647I1298J-1D01*
G01X1471825Y880734D01*
G37*
G36*
G01X1437719Y884715D02*
X1438526Y886112D01*
X1438495Y886199D01*
G02X1438422Y886627I1225J429D01*
G02X1441018I1298J0D01*
G02X1439962Y885352I-1298J0D01*
G01X1439872Y885335D01*
X1439065Y883938D01*
X1439096Y883851D01*
G02X1439168Y883423I-1225J-426D01*
G02X1436574I-1297J0D01*
G02X1437629Y884698I1298J0D01*
G01X1437719Y884715D01*
G37*
G36*
G01X1445119D02*
X1445926Y886112D01*
X1445895Y886199D01*
G02X1445822Y886627I1225J429D01*
G02X1448418I1298J0D01*
G02X1447362Y885352I-1298J0D01*
G01X1447272Y885335D01*
X1446465Y883938D01*
X1446496Y883851D01*
G02X1446568Y883423I-1225J-426D01*
G02X1443974I-1297J0D01*
G02X1445029Y884698I1298J0D01*
G01X1445119Y884715D01*
G37*
G36*
G01X1452519D02*
X1453326Y886112D01*
X1453295Y886199D01*
G02X1453222Y886627I1225J429D01*
G02X1455818I1298J0D01*
G02X1454762Y885352I-1298J0D01*
G01X1454672Y885335D01*
X1453865Y883938D01*
X1453896Y883851D01*
G02X1453968Y883423I-1225J-426D01*
G02X1451374I-1297J0D01*
G02X1452429Y884698I1298J0D01*
G01X1452519Y884715D01*
G37*
G36*
G01X1459919D02*
X1460726Y886112D01*
X1460695Y886199D01*
G02X1460622Y886627I1225J429D01*
G02X1463218I1298J0D01*
G02X1462162Y885352I-1298J0D01*
G01X1462072Y885335D01*
X1461265Y883938D01*
X1461296Y883851D01*
G02X1461368Y883423I-1225J-426D01*
G02X1458774I-1297J0D01*
G02X1459829Y884698I1298J0D01*
G01X1459919Y884715D01*
G37*
G36*
G01X1467319D02*
X1468126Y886112D01*
X1468095Y886199D01*
G02X1468022Y886627I1225J429D01*
G02X1470618I1298J0D01*
G02X1469562Y885352I-1298J0D01*
G01X1469472Y885335D01*
X1468665Y883938D01*
X1468696Y883851D01*
G02X1468768Y883423I-1225J-426D01*
G02X1466174I-1297J0D01*
G02X1467229Y884698I1298J0D01*
G01X1467319Y884715D01*
G37*
G36*
G01X1494025Y880733D02*
X1493219Y882131D01*
X1493129Y882148D01*
G02X1492074Y883423I243J1275D01*
G02X1494668I1297J0D01*
G01Y883421D01*
G02X1494596Y882994I-1298J-1D01*
G01X1494566Y882908D01*
X1495372Y881511D01*
X1495462Y881494D01*
G02X1496518Y880219I-242J-1275D01*
G02X1493922I-1298J0D01*
G02X1493995Y880647I1299J-1D01*
G01X1494025Y880733D01*
G37*
G36*
G01X1505096Y886198D02*
G02X1505024Y886625I1226J426D01*
G01Y886627D01*
G02X1507618I1297J0D01*
G02X1506563Y885352I-1298J0D01*
G01X1506473Y885335D01*
X1505666Y883937D01*
X1505696Y883851D01*
G02X1505768Y883423I-1226J-426D01*
G02X1503174I-1297J0D01*
G02X1504230Y884698I1298J0D01*
G01X1504320Y884715D01*
X1505126Y886112D01*
X1505096Y886198D01*
G37*
G36*
G01X1499575Y871118D02*
X1498768Y872518D01*
X1498678Y872535D01*
G02X1497622Y873810I242J1275D01*
G02X1500218I1298J0D01*
G01Y873808D01*
G02X1500145Y873381I-1298J2D01*
G01X1500115Y873295D01*
X1500921Y871898D01*
X1501011Y871881D01*
G02X1502068Y870606I-240J-1275D01*
G02X1499474I-1297J0D01*
G01Y870607D01*
G02X1499545Y871032I1297J2D01*
G01X1499575Y871118D01*
G37*
G36*
G01X1506975D02*
X1506168Y872518D01*
X1506078Y872535D01*
G02X1505022Y873810I242J1275D01*
G02X1507618I1298J0D01*
G01Y873808D01*
G02X1507545Y873381I-1298J2D01*
G01X1507515Y873295D01*
X1508321Y871898D01*
X1508411Y871881D01*
G02X1509468Y870606I-240J-1275D01*
G02X1506874I-1297J0D01*
G01Y870607D01*
G02X1506945Y871032I1297J2D01*
G01X1506975Y871118D01*
G37*
G36*
G01X1501426Y880732D02*
X1500619Y882131D01*
X1500529Y882148D01*
G02X1499474Y883423I243J1275D01*
G02X1502068I1297J0D01*
G01Y883421D01*
G02X1501996Y882994I-1298J-1D01*
G01X1501966Y882908D01*
X1502772Y881511D01*
X1502862Y881494D01*
G02X1503918Y880219I-242J-1275D01*
G02X1501324I-1297J0D01*
G02X1501396Y880646I1297J1D01*
G01X1501426Y880732D01*
G37*
G36*
G01X1487670Y855876D02*
X1488477Y857274D01*
X1488446Y857361D01*
G02X1488374Y857789I1225J426D01*
G02X1490968I1297J0D01*
G02X1489913Y856514I-1298J0D01*
G01X1489823Y856497D01*
X1489015Y855098D01*
X1489045Y855011D01*
G02X1489118Y854584I-1225J-429D01*
G02X1486522I-1298J0D01*
G02X1487580Y855859I1297J0D01*
G01X1487670Y855876D01*
G37*
G36*
G01X1495070D02*
X1495877Y857274D01*
X1495846Y857361D01*
G02X1495774Y857789I1225J426D01*
G02X1498368I1297J0D01*
G02X1497313Y856514I-1298J0D01*
G01X1497223Y856497D01*
X1496415Y855098D01*
X1496445Y855011D01*
G02X1496518Y854584I-1225J-429D01*
G02X1493922I-1298J0D01*
G02X1494980Y855859I1297J0D01*
G01X1495070Y855876D01*
G37*
G36*
G01X1502470D02*
X1503277Y857274D01*
X1503246Y857361D01*
G02X1503174Y857789I1225J426D01*
G02X1505768I1297J0D01*
G02X1504713Y856514I-1298J0D01*
G01X1504623Y856497D01*
X1503815Y855098D01*
X1503845Y855011D01*
G02X1503918Y854584I-1225J-429D01*
G02X1501322I-1298J0D01*
G02X1502380Y855859I1297J0D01*
G01X1502470Y855876D01*
G37*
G36*
G01X1484776Y858302D02*
X1483968Y859701D01*
X1483878Y859718D01*
G02X1482822Y860993I242J1275D01*
G02X1485418I1298J0D01*
G02X1485345Y860564I-1297J0D01*
G01X1485314Y860478D01*
X1486120Y859081D01*
X1486210Y859064D01*
G02X1487268Y857789I-239J-1275D01*
G02X1484674I-1297J0D01*
G02X1484745Y858215I1297J3D01*
G01X1484776Y858302D01*
G37*
G36*
G01X1492176D02*
X1491368Y859701D01*
X1491278Y859718D01*
G02X1490222Y860993I242J1275D01*
G02X1492818I1298J0D01*
G02X1492745Y860564I-1297J0D01*
G01X1492714Y860478D01*
X1493520Y859081D01*
X1493610Y859064D01*
G02X1494668Y857789I-239J-1275D01*
G02X1492074I-1297J0D01*
G02X1492145Y858215I1297J3D01*
G01X1492176Y858302D01*
G37*
G36*
G01X1499576D02*
X1498768Y859701D01*
X1498678Y859718D01*
G02X1497622Y860993I242J1275D01*
G02X1500218I1298J0D01*
G02X1500145Y860564I-1297J0D01*
G01X1500114Y860478D01*
X1500920Y859081D01*
X1501010Y859064D01*
G02X1502068Y857789I-239J-1275D01*
G02X1499474I-1297J0D01*
G02X1499545Y858215I1297J3D01*
G01X1499576Y858302D01*
G37*
G36*
G01X1487670Y868693D02*
X1488477Y870091D01*
X1488446Y870178D01*
G02X1488374Y870606I1225J426D01*
G02X1490968I1297J0D01*
G02X1489913Y869331I-1298J0D01*
G01X1489823Y869314D01*
X1489015Y867915D01*
X1489045Y867828D01*
G02X1489118Y867401I-1225J-429D01*
G02X1486522I-1298J0D01*
G02X1487580Y868676I1297J0D01*
G01X1487670Y868693D01*
G37*
G36*
G01X1495070D02*
X1495877Y870091D01*
X1495846Y870178D01*
G02X1495774Y870606I1225J426D01*
G02X1498368I1297J0D01*
G02X1497313Y869331I-1298J0D01*
G01X1497223Y869314D01*
X1496415Y867915D01*
X1496445Y867828D01*
G02X1496518Y867401I-1225J-429D01*
G02X1493922I-1298J0D01*
G02X1494980Y868676I1297J0D01*
G01X1495070Y868693D01*
G37*
G36*
G01X1502470D02*
X1503277Y870091D01*
X1503246Y870178D01*
G02X1503174Y870606I1225J426D01*
G02X1505768I1297J0D01*
G02X1504713Y869331I-1298J0D01*
G01X1504623Y869314D01*
X1503816Y867916D01*
X1503846Y867829D01*
G02X1503918Y867401I-1225J-426D01*
G02X1501324I-1297J0D01*
G02X1502380Y868676I1298J0D01*
G01X1502470Y868693D01*
G37*
G36*
G01X1484776Y871119D02*
X1483968Y872518D01*
X1483878Y872535D01*
G02X1482822Y873810I242J1275D01*
G02X1485418I1298J0D01*
G02X1485345Y873381I-1297J0D01*
G01X1485314Y873295D01*
X1486120Y871898D01*
X1486210Y871881D01*
G02X1487268Y870606I-239J-1275D01*
G02X1484674I-1297J0D01*
G02X1484745Y871032I1297J3D01*
G01X1484776Y871119D01*
G37*
G36*
G01X1492176D02*
X1491368Y872518D01*
X1491278Y872535D01*
G02X1490222Y873810I242J1275D01*
G02X1492818I1298J0D01*
G02X1492745Y873381I-1297J0D01*
G01X1492714Y873295D01*
X1493520Y871898D01*
X1493610Y871881D01*
G02X1494668Y870606I-239J-1275D01*
G02X1492074I-1297J0D01*
G02X1492145Y871032I1297J3D01*
G01X1492176Y871119D01*
G37*
G36*
G01X1486625Y880734D02*
X1485819Y882131D01*
X1485729Y882148D01*
G02X1484674Y883423I243J1275D01*
G02X1487268I1297J0D01*
G02X1487196Y882994I-1297J-3D01*
G01X1487165Y882908D01*
X1487971Y881511D01*
X1488061Y881494D01*
G02X1489118Y880219I-240J-1275D01*
G02X1486522I-1298J0D01*
G02X1486595Y880647I1298J-1D01*
G01X1486625Y880734D01*
G37*
G36*
G01X1482119Y884715D02*
X1482926Y886112D01*
X1482895Y886199D01*
G02X1482822Y886627I1225J429D01*
G02X1485418I1298J0D01*
G02X1484362Y885352I-1298J0D01*
G01X1484272Y885335D01*
X1483465Y883938D01*
X1483496Y883851D01*
G02X1483568Y883423I-1225J-426D01*
G02X1480974I-1297J0D01*
G02X1482029Y884698I1298J0D01*
G01X1482119Y884715D01*
G37*
G36*
G01X1489519D02*
X1490326Y886112D01*
X1490295Y886199D01*
G02X1490222Y886627I1225J429D01*
G02X1492818I1298J0D01*
G02X1491762Y885352I-1298J0D01*
G01X1491672Y885335D01*
X1490865Y883938D01*
X1490896Y883851D01*
G02X1490968Y883423I-1225J-426D01*
G02X1488374I-1297J0D01*
G02X1489429Y884698I1298J0D01*
G01X1489519Y884715D01*
G37*
G36*
G01X1496919D02*
X1497726Y886112D01*
X1497695Y886199D01*
G02X1497622Y886627I1225J429D01*
G02X1500218I1298J0D01*
G02X1499162Y885352I-1298J0D01*
G01X1499072Y885335D01*
X1498265Y883938D01*
X1498296Y883851D01*
G02X1498368Y883423I-1225J-426D01*
G02X1495774I-1297J0D01*
G02X1496829Y884698I1298J0D01*
G01X1496919Y884715D01*
G37*
G36*
G01X1452952Y1122739D02*
X1453759Y1124136D01*
X1453728Y1124223D01*
G02X1453656Y1124651I1225J426D01*
G02X1456250I1297J0D01*
G02X1455195Y1123376I-1298J0D01*
G01X1455105Y1123359D01*
X1454298Y1121962D01*
X1454329Y1121875D01*
G02X1454402Y1121447I-1225J-429D01*
G02X1451806I-1298J0D01*
G02X1452862Y1122722I1298J0D01*
G01X1452952Y1122739D01*
G37*
G36*
G01X1460352D02*
X1461159Y1124136D01*
X1461128Y1124223D01*
G02X1461056Y1124651I1225J426D01*
G02X1463650I1297J0D01*
G02X1462595Y1123376I-1298J0D01*
G01X1462505Y1123359D01*
X1461698Y1121962D01*
X1461729Y1121875D01*
G02X1461802Y1121447I-1225J-429D01*
G02X1459206I-1298J0D01*
G02X1460262Y1122722I1298J0D01*
G01X1460352Y1122739D01*
G37*
G36*
G01X1467752D02*
X1468559Y1124136D01*
X1468528Y1124223D01*
G02X1468456Y1124651I1225J426D01*
G02X1471050I1297J0D01*
G02X1469995Y1123376I-1298J0D01*
G01X1469905Y1123359D01*
X1469098Y1121962D01*
X1469129Y1121875D01*
G02X1469202Y1121447I-1225J-429D01*
G02X1466606I-1298J0D01*
G02X1467662Y1122722I1298J0D01*
G01X1467752Y1122739D01*
G37*
G36*
G01X1475152D02*
X1475959Y1124136D01*
X1475928Y1124223D01*
G02X1475856Y1124651I1225J426D01*
G02X1478450I1297J0D01*
G02X1477395Y1123376I-1298J0D01*
G01X1477305Y1123359D01*
X1476498Y1121962D01*
X1476529Y1121875D01*
G02X1476602Y1121447I-1225J-429D01*
G02X1474006I-1298J0D01*
G02X1475062Y1122722I1298J0D01*
G01X1475152Y1122739D01*
G37*
G36*
G01X1482552D02*
X1483359Y1124136D01*
X1483328Y1124223D01*
G02X1483256Y1124651I1225J426D01*
G02X1485850I1297J0D01*
G02X1484795Y1123376I-1298J0D01*
G01X1484705Y1123359D01*
X1483898Y1121962D01*
X1483929Y1121875D01*
G02X1484002Y1121447I-1225J-429D01*
G02X1481406I-1298J0D01*
G02X1482462Y1122722I1298J0D01*
G01X1482552Y1122739D01*
G37*
G36*
G01X1489952D02*
X1490759Y1124136D01*
X1490728Y1124223D01*
G02X1490656Y1124651I1225J426D01*
G02X1493250I1297J0D01*
G02X1492195Y1123376I-1298J0D01*
G01X1492105Y1123359D01*
X1491298Y1121962D01*
X1491329Y1121875D01*
G02X1491402Y1121447I-1225J-429D01*
G02X1488806I-1298J0D01*
G02X1489862Y1122722I1298J0D01*
G01X1489952Y1122739D01*
G37*
G36*
G01X1497352D02*
X1498159Y1124136D01*
X1498128Y1124223D01*
G02X1498056Y1124651I1225J426D01*
G02X1500650I1297J0D01*
G02X1499595Y1123376I-1298J0D01*
G01X1499505Y1123359D01*
X1498698Y1121962D01*
X1498729Y1121875D01*
G02X1498802Y1121447I-1225J-429D01*
G02X1496206I-1298J0D01*
G02X1497262Y1122722I1298J0D01*
G01X1497352Y1122739D01*
G37*
G36*
G01X1457459Y1125166D02*
X1456652Y1126564D01*
X1456562Y1126581D01*
G02X1455506Y1127856I242J1275D01*
G02X1458102I1298J0D01*
G02X1458029Y1127427I-1297J0D01*
G01X1457998Y1127341D01*
X1458805Y1125943D01*
X1458895Y1125926D01*
G02X1459950Y1124651I-243J-1275D01*
G02X1457356I-1297J0D01*
G02X1457428Y1125080I1297J3D01*
G01X1457459Y1125166D01*
G37*
G36*
G01X1464859D02*
X1464052Y1126564D01*
X1463962Y1126581D01*
G02X1462906Y1127856I242J1275D01*
G02X1465502I1298J0D01*
G02X1465429Y1127427I-1297J0D01*
G01X1465398Y1127341D01*
X1466205Y1125943D01*
X1466295Y1125926D01*
G02X1467350Y1124651I-243J-1275D01*
G02X1464756I-1297J0D01*
G02X1464828Y1125080I1297J3D01*
G01X1464859Y1125166D01*
G37*
G36*
G01X1472259D02*
X1471452Y1126564D01*
X1471362Y1126581D01*
G02X1470306Y1127856I242J1275D01*
G02X1472902I1298J0D01*
G02X1472829Y1127427I-1297J0D01*
G01X1472798Y1127341D01*
X1473605Y1125943D01*
X1473695Y1125926D01*
G02X1474750Y1124651I-243J-1275D01*
G02X1472156I-1297J0D01*
G02X1472228Y1125080I1297J3D01*
G01X1472259Y1125166D01*
G37*
G36*
G01X1479659D02*
X1478852Y1126564D01*
X1478762Y1126581D01*
G02X1477706Y1127856I242J1275D01*
G02X1480302I1298J0D01*
G02X1480229Y1127427I-1297J0D01*
G01X1480198Y1127341D01*
X1481005Y1125943D01*
X1481095Y1125926D01*
G02X1482150Y1124651I-243J-1275D01*
G02X1479556I-1297J0D01*
G02X1479628Y1125080I1297J3D01*
G01X1479659Y1125166D01*
G37*
G36*
G01X1487059D02*
X1486252Y1126564D01*
X1486162Y1126581D01*
G02X1485106Y1127856I242J1275D01*
G02X1487702I1298J0D01*
G02X1487629Y1127427I-1297J0D01*
G01X1487598Y1127341D01*
X1488405Y1125943D01*
X1488495Y1125926D01*
G02X1489550Y1124651I-243J-1275D01*
G02X1486956I-1297J0D01*
G02X1487028Y1125080I1297J3D01*
G01X1487059Y1125166D01*
G37*
G36*
G01X1494459D02*
X1493652Y1126564D01*
X1493562Y1126581D01*
G02X1492506Y1127856I242J1275D01*
G02X1495102I1298J0D01*
G02X1495029Y1127427I-1297J0D01*
G01X1494998Y1127341D01*
X1495805Y1125943D01*
X1495895Y1125926D01*
G02X1496950Y1124651I-243J-1275D01*
G02X1494356I-1297J0D01*
G02X1494428Y1125080I1297J3D01*
G01X1494459Y1125166D01*
G37*
G36*
G01X1501859D02*
X1501052Y1126564D01*
X1500962Y1126581D01*
G02X1499906Y1127856I242J1275D01*
G02X1502502I1298J0D01*
G02X1502429Y1127427I-1297J0D01*
G01X1502398Y1127341D01*
X1503205Y1125943D01*
X1503295Y1125926D01*
G02X1504350Y1124651I-243J-1275D01*
G02X1501756I-1297J0D01*
G02X1501828Y1125080I1297J3D01*
G01X1501859Y1125166D01*
G37*
G54D101*
X1290005Y293768D03*
G54D89*
X93547Y692260D03*
X1455787Y1421784D03*
X1710550Y691327D03*
G54D93*
X174685Y637367D03*
X174393Y668511D03*
G54D96*
X1565236Y184783D03*
Y264035D03*
G54D97*
X1405118Y112008D03*
G54D76*
X1380522Y261936D03*
X1388754Y255503D03*
X1380638Y247394D03*
X1386630Y240351D03*
X1031950Y385471D03*
X968286Y482241D03*
X944032Y435931D03*
G54D100*
X1247638Y269488D03*
G54D98*
X306771Y991220D03*
X531240Y811122D03*
X525275Y1171319D03*
X356062D03*
X574566Y991220D03*
X1282913D03*
X1326240Y811122D03*
X1332204Y1171319D03*
X1501417D03*
X1507381Y811122D03*
X1550708Y991220D03*
G54D75*
X1386273Y270370D03*
X615573Y178034D03*
X628195Y174214D03*
X941059Y426211D03*
X1407029Y154432D03*
X1282645Y253971D03*
G54D94*
X537477Y1395413D03*
X322500Y1391830D03*
X1513618Y1395413D03*
X1298642Y1391830D03*
G54D95*
X704185Y277236D03*
X177413Y277208D03*
X1153555D03*
%LPC*%
G75*
G36*
G01X307246Y1374027D02*
X325476D01*
X326274Y1373229D01*
X326290Y1373189D01*
G03X326294Y1373179I466J181D01*
G01X326309Y1373142D01*
Y1367927D01*
X317918Y1359537D01*
G03X317772Y1359185I354J-353D01*
G01Y1351160D01*
G03X317918Y1350808I500J1D01*
G01X318590Y1350136D01*
G03X318942Y1349990I353J354D01*
G01X333342D01*
G03X333694Y1350136I-1J500D01*
G01X335419Y1351862D01*
X348596D01*
X352709Y1347749D01*
Y1340040D01*
X350243Y1337575D01*
G03X350097Y1337223I354J-353D01*
G01Y1327978D01*
G03X350243Y1327626I500J1D01*
G01X350541Y1327328D01*
G03X350893Y1327182I353J354D01*
G01X365363D01*
G03X365715Y1327328I-1J500D01*
G01X366181Y1327794D01*
G03X366327Y1328146I-354J353D01*
G01Y1335949D01*
X367024Y1336646D01*
X383374D01*
X385781Y1334239D01*
Y1326661D01*
X382282Y1323163D01*
G03X382136Y1322811I354J-353D01*
G01Y1314682D01*
G03X382282Y1314330I500J1D01*
G01X382783Y1313829D01*
G03X383135Y1313683I353J354D01*
G01X397105D01*
G03X397457Y1313829I-1J500D01*
G01X397964Y1314336D01*
G03X398110Y1314688I-354J353D01*
G01Y1320655D01*
G03X398399Y1321691I-1712J1036D01*
G03X398136Y1322682I-2002J-1D01*
G01X398110Y1322729D01*
Y1323553D01*
X398136Y1323600D01*
G03X398399Y1324591I-1739J992D01*
G03X398136Y1325582I-2002J-1D01*
G01X398110Y1325629D01*
Y1326453D01*
X398136Y1326500D01*
G03X398399Y1327491I-1739J992D01*
G03X398110Y1328527I-2001J0D01*
G01Y1333403D01*
X401481Y1336774D01*
X416025D01*
X417431Y1335368D01*
Y1326335D01*
X414405Y1323310D01*
G03X414259Y1322958I354J-353D01*
G01Y1314709D01*
G03X414405Y1314357I500J1D01*
G01X414940Y1313822D01*
G03X415292Y1313676I353J354D01*
G01X429425D01*
G03X429777Y1313822I-1J500D01*
G01X430504Y1314549D01*
G03X430650Y1314901I-354J353D01*
G01Y1328067D01*
G03X430504Y1328419I-500J-1D01*
G01X429655Y1329267D01*
Y1332822D01*
X433514Y1336681D01*
X447510D01*
X449010Y1335181D01*
Y1325616D01*
X446617Y1323224D01*
G03X446471Y1322872I354J-353D01*
G01Y1314616D01*
G03X446617Y1314264I500J1D01*
G01X447056Y1313825D01*
G03X447408Y1313679I353J354D01*
G01X461522D01*
G03X461874Y1313825I-1J500D01*
G01X462463Y1314414D01*
G03X462609Y1314766I-354J353D01*
G01Y1321264D01*
X462613Y1321284D01*
G03X462655Y1321691I-1960J408D01*
G03X462613Y1322098I-2002J-1D01*
G01X462609Y1322118D01*
Y1324164D01*
X462613Y1324184D01*
G03X462655Y1324591I-1960J408D01*
G03X462613Y1324998I-2002J-1D01*
G01X462609Y1325018D01*
Y1327064D01*
X462613Y1327084D01*
G03X462655Y1327491I-1960J408D01*
G03X462613Y1327898I-2002J-1D01*
G01X462609Y1327918D01*
Y1333968D01*
X465957Y1337316D01*
X479556D01*
X481315Y1335557D01*
Y1326017D01*
X478672Y1323375D01*
G03X478526Y1323023I354J-353D01*
G01Y1314616D01*
G03X478672Y1314264I500J1D01*
G01X479115Y1313821D01*
G03X479467Y1313675I353J354D01*
G01X493674D01*
G03X494026Y1313821I-1J500D01*
G01X494652Y1314447D01*
G03X494798Y1314799I-354J353D01*
G01Y1322050D01*
X494805Y1322077D01*
G03X494880Y1322618I-1927J543D01*
G03X494805Y1323159I-2002J-2D01*
G01X494798Y1323186D01*
Y1324950D01*
X494805Y1324977D01*
G03X494880Y1325518I-1927J543D01*
G03X494805Y1326059I-2002J-2D01*
G01X494798Y1326086D01*
Y1327850D01*
X494805Y1327877D01*
G03X494880Y1328418I-1927J543D01*
G03X494805Y1328959I-2002J-2D01*
G01X494798Y1328986D01*
Y1348099D01*
X497440Y1350741D01*
X510830D01*
X513564Y1348007D01*
Y1341917D01*
X510842Y1339196D01*
G03X510696Y1338844I354J-353D01*
G01Y1327861D01*
G03X510842Y1327509I500J1D01*
G01X511114Y1327237D01*
G03X511466Y1327091I353J354D01*
G01X525796D01*
G03X526148Y1327237I-1J500D01*
G01X527231Y1328320D01*
G03X527377Y1328672I-354J353D01*
G01Y1370120D01*
X529046Y1371789D01*
X544276D01*
X545066Y1370999D01*
Y1362358D01*
X542971Y1360264D01*
G03X542825Y1359912I354J-353D01*
G01Y1350571D01*
X542375Y1350121D01*
X537011D01*
G03X536304Y1349828I0J-999D01*
G01X533590Y1347114D01*
G03X533297Y1346407I706J-707D01*
G01Y1345963D01*
X533288Y1345934D01*
G03X533230Y1345539I1309J-394D01*
G03X533288Y1345144I1367J-1D01*
G01X533297Y1345115D01*
Y1342856D01*
X533288Y1342827D01*
G03X533230Y1342432I1309J-394D01*
G03X533288Y1342037I1367J-1D01*
G01X533297Y1342008D01*
Y1322918D01*
X528506Y1318127D01*
X503305D01*
G03X502598Y1317834I0J-999D01*
G01X500320Y1315556D01*
G03X500027Y1314849I706J-707D01*
G01Y1306116D01*
X498778Y1304867D01*
X492360D01*
X492346Y1304869D01*
G03X492155Y1304882I-190J-1389D01*
G03X491964Y1304869I-1J-1402D01*
G01X491950Y1304867D01*
X489760D01*
X489746Y1304869D01*
G03X489555Y1304882I-190J-1389D01*
G03X489364Y1304869I-1J-1402D01*
G01X489350Y1304867D01*
X462013D01*
G03X459841I-1086J-888D01*
G01X459413D01*
G03X457241I-1086J-888D01*
G01X428104D01*
X428090Y1304869D01*
G03X427899Y1304882I-190J-1389D01*
G03X427708Y1304869I-1J-1402D01*
G01X427694Y1304867D01*
X425504D01*
X425490Y1304869D01*
G03X425299Y1304882I-190J-1389D01*
G03X425108Y1304869I-1J-1402D01*
G01X425094Y1304867D01*
X395976D01*
X395962Y1304869D01*
G03X395771Y1304882I-190J-1389D01*
G03X395580Y1304869I-1J-1402D01*
G01X395566Y1304867D01*
X393376D01*
X393362Y1304869D01*
G03X393171Y1304882I-190J-1389D01*
G03X392980Y1304869I-1J-1402D01*
G01X392966Y1304867D01*
X367530D01*
X362137Y1310260D01*
G02X362114Y1310801I283J283D01*
G03X362445Y1311706I-1072J905D01*
G03X362014Y1312717I-1401J0D01*
G02Y1313295I277J289D01*
G03X362445Y1314306I-970J1011D01*
G03X361259Y1315691I-1402J0D01*
G02X361090Y1315877I31J198D01*
G03X360799Y1316527I-998J-57D01*
G01X359434Y1317892D01*
G03X358727Y1318185I-707J-706D01*
G01X338017D01*
X330159Y1326043D01*
X330210Y1326167D01*
G03X330317Y1326704I-1294J537D01*
G03X329823Y1327773I-1402J1D01*
G01X329752Y1327833D01*
Y1328175D01*
X329823Y1328235D01*
G03X330317Y1329304I-908J1068D01*
G03X329823Y1330373I-1402J1D01*
G01X329752Y1330433D01*
Y1330775D01*
X329823Y1330835D01*
G03X330317Y1331904I-908J1068D01*
G03X329823Y1332973I-1402J1D01*
G01X329752Y1333033D01*
Y1333375D01*
X329823Y1333435D01*
G03X330317Y1334504I-908J1068D01*
G03X329823Y1335573I-1402J1D01*
G01X329752Y1335633D01*
Y1335975D01*
X329823Y1336035D01*
G03X330317Y1337104I-908J1068D01*
G03X329751Y1338230I-1403J0D01*
G03X329459Y1338991I-998J54D01*
G01X327965Y1340485D01*
G03X327258Y1340778I-707J-706D01*
G01X304406D01*
X301260Y1343924D01*
Y1368041D01*
X307246Y1374027D01*
G37*
G36*
G01X456144Y1384372D02*
X472356D01*
X478755Y1377973D01*
G03X479462Y1377680I707J706D01*
G01X549610D01*
X562781Y1364509D01*
Y1350728D01*
X562174Y1350121D01*
X544231D01*
X543826Y1350525D01*
Y1359703D01*
X546068Y1361943D01*
Y1371414D01*
X544691Y1372790D01*
X528631D01*
X526376Y1370535D01*
Y1336027D01*
X526375Y1336025D01*
Y1335982D01*
Y1335939D01*
X526376Y1335937D01*
Y1328881D01*
X525587Y1328092D01*
X511698D01*
Y1338635D01*
X514566Y1341502D01*
Y1348422D01*
X513109Y1349878D01*
X513096Y1349933D01*
G03X511614Y1351415I-1947J-465D01*
G01X511559Y1351428D01*
X511245Y1351742D01*
X497025D01*
X493796Y1348514D01*
Y1315008D01*
X493465Y1314676D01*
X479676D01*
X479528Y1314825D01*
Y1322814D01*
X482316Y1325602D01*
Y1335972D01*
X479971Y1338318D01*
X465542D01*
X461608Y1334383D01*
Y1314975D01*
X461313Y1314680D01*
X447617D01*
X447472Y1314825D01*
Y1322663D01*
X450012Y1325201D01*
Y1335596D01*
X448677Y1336930D01*
X448665Y1336951D01*
G03X447967Y1337649I-1721J-1023D01*
G01X447946Y1337661D01*
X447925Y1337682D01*
X447909D01*
X447866Y1337705D01*
G03X446944Y1337930I-922J-1777D01*
G03X445980Y1337682I1J-2002D01*
G01X435940D01*
G03X434983Y1337926I-958J-1758D01*
G03X434068Y1337705I-1J-2002D01*
G01X434025Y1337682D01*
X433099D01*
X428654Y1333237D01*
Y1328852D01*
X429648Y1327858D01*
Y1315110D01*
X429216Y1314678D01*
X415501D01*
X415260Y1314918D01*
Y1322749D01*
X418432Y1325920D01*
Y1335783D01*
X417991Y1336225D01*
X417976Y1336265D01*
G03X416796Y1337445I-1877J-697D01*
G01X416756Y1337460D01*
X416440Y1337776D01*
X403981D01*
X403943Y1337793D01*
G03X403130Y1337965I-812J-1830D01*
G03X402317Y1337793I-1J-2002D01*
G01X402279Y1337776D01*
X401066D01*
X397108Y1333818D01*
Y1314897D01*
X396896Y1314684D01*
X383344D01*
X383138Y1314891D01*
Y1322602D01*
X386782Y1326246D01*
Y1334654D01*
X383789Y1337648D01*
X371807D01*
G03X370874Y1337878I-932J-1772D01*
G03X369941Y1337648I-1J-2002D01*
G01X366609D01*
X365326Y1336364D01*
Y1328355D01*
X365154Y1328184D01*
X351102D01*
X351098Y1328187D01*
Y1337014D01*
X353710Y1339625D01*
Y1348164D01*
X352429Y1349445D01*
X352416Y1349500D01*
G03X350940Y1350976I-1946J-470D01*
G01X350885Y1350989D01*
X349011Y1352864D01*
X335004D01*
X333133Y1350992D01*
X319151D01*
X318774Y1351369D01*
Y1358976D01*
X327310Y1367512D01*
Y1373217D01*
X328121Y1374027D01*
X337925D01*
G03X338632Y1374320I0J999D01*
G01X347862Y1383550D01*
X376941D01*
X378661Y1381830D01*
X378643Y1381728D01*
G03X378623Y1381490I1382J-236D01*
G03X380025Y1380088I1402J0D01*
G03X380263Y1380108I2J1402D01*
G01X380365Y1380126D01*
X384025Y1376466D01*
G03X384732Y1376173I707J706D01*
G01X447531D01*
G03X448238Y1376466I0J999D01*
G01X456144Y1384372D01*
G37*
G36*
G01X1283387Y1374026D02*
X1301617D01*
X1302415Y1373228D01*
X1302431Y1373188D01*
G03X1302435Y1373178I466J181D01*
G01X1302450Y1373141D01*
Y1367926D01*
X1294059Y1359536D01*
G03X1293913Y1359184I354J-353D01*
G01Y1351159D01*
G03X1294059Y1350807I500J1D01*
G01X1294731Y1350135D01*
G03X1295083Y1349989I353J354D01*
G01X1309483D01*
G03X1309835Y1350135I-1J500D01*
G01X1311560Y1351861D01*
X1324737D01*
X1328850Y1347748D01*
Y1340039D01*
X1326384Y1337574D01*
G03X1326238Y1337222I354J-353D01*
G01Y1327977D01*
G03X1326384Y1327625I500J1D01*
G01X1326682Y1327327D01*
G03X1327034Y1327181I353J354D01*
G01X1341004D01*
G03X1341356Y1327327I-1J500D01*
G01X1341822Y1327793D01*
G03X1341968Y1328145I-354J353D01*
G01Y1333888D01*
G03Y1335818I-1753J965D01*
G01Y1335948D01*
X1342665Y1336645D01*
X1359515D01*
X1361922Y1334238D01*
Y1326660D01*
X1358423Y1323162D01*
G03X1358277Y1322810I354J-353D01*
G01Y1314681D01*
G03X1358423Y1314329I500J1D01*
G01X1358924Y1313828D01*
G03X1359276Y1313682I353J354D01*
G01X1373246D01*
G03X1373598Y1313828I-1J500D01*
G01X1374105Y1314335D01*
G03X1374251Y1314687I-354J353D01*
G01Y1320655D01*
G03X1374540Y1321691I-1712J1036D01*
G03X1374277Y1322682I-2002J-1D01*
G01X1374251Y1322729D01*
Y1323553D01*
X1374277Y1323600D01*
G03X1374540Y1324591I-1739J992D01*
G03X1374277Y1325582I-2002J-1D01*
G01X1374251Y1325629D01*
Y1326453D01*
X1374277Y1326500D01*
G03X1374540Y1327491I-1739J992D01*
G03X1374251Y1328527I-2001J0D01*
G01Y1333402D01*
X1377622Y1336773D01*
X1392166D01*
X1393572Y1335367D01*
Y1326334D01*
X1390546Y1323309D01*
G03X1390400Y1322957I354J-353D01*
G01Y1314708D01*
G03X1390546Y1314356I500J1D01*
G01X1391081Y1313821D01*
G03X1391433Y1313675I353J354D01*
G01X1405566D01*
G03X1405918Y1313821I-1J500D01*
G01X1406645Y1314548D01*
G03X1406791Y1314900I-354J353D01*
G01Y1328066D01*
G03X1406645Y1328418I-500J-1D01*
G01X1405796Y1329266D01*
Y1332821D01*
X1409655Y1336680D01*
X1423651D01*
X1425151Y1335180D01*
Y1325615D01*
X1422758Y1323223D01*
G03X1422612Y1322871I354J-353D01*
G01Y1314615D01*
G03X1422758Y1314263I500J1D01*
G01X1423197Y1313824D01*
G03X1423549Y1313678I353J354D01*
G01X1437663D01*
G03X1438015Y1313824I-1J500D01*
G01X1438604Y1314413D01*
G03X1438750Y1314765I-354J353D01*
G01Y1321264D01*
X1438754Y1321284D01*
G03X1438796Y1321691I-1960J408D01*
G03X1438754Y1322098I-2002J-1D01*
G01X1438750Y1322118D01*
Y1324164D01*
X1438754Y1324184D01*
G03X1438796Y1324591I-1960J408D01*
G03X1438754Y1324998I-2002J-1D01*
G01X1438750Y1325018D01*
Y1327064D01*
X1438754Y1327084D01*
G03X1438796Y1327491I-1960J408D01*
G03X1438754Y1327898I-2002J-1D01*
G01X1438750Y1327918D01*
Y1333967D01*
X1442098Y1337315D01*
X1455697D01*
X1457456Y1335556D01*
Y1326016D01*
X1454813Y1323374D01*
G03X1454667Y1323022I354J-353D01*
G01Y1314615D01*
G03X1454813Y1314263I500J1D01*
G01X1455256Y1313820D01*
G03X1455608Y1313674I353J354D01*
G01X1469815D01*
G03X1470167Y1313820I-1J500D01*
G01X1470793Y1314446D01*
G03X1470939Y1314798I-354J353D01*
G01Y1322050D01*
X1470946Y1322077D01*
G03X1471021Y1322618I-1927J543D01*
G03X1470946Y1323159I-2002J-2D01*
G01X1470939Y1323186D01*
Y1324950D01*
X1470946Y1324977D01*
G03X1471021Y1325518I-1927J543D01*
G03X1470946Y1326059I-2002J-2D01*
G01X1470939Y1326086D01*
Y1327850D01*
X1470946Y1327877D01*
G03X1471021Y1328418I-1927J543D01*
G03X1470946Y1328959I-2002J-2D01*
G01X1470939Y1328986D01*
Y1348098D01*
X1473581Y1350740D01*
X1486971D01*
X1489705Y1348006D01*
Y1341916D01*
X1486983Y1339195D01*
G03X1486837Y1338843I354J-353D01*
G01Y1327860D01*
G03X1486983Y1327508I500J1D01*
G01X1487255Y1327236D01*
G03X1487607Y1327090I353J354D01*
G01X1501937D01*
G03X1502289Y1327236I-1J500D01*
G01X1503372Y1328319D01*
G03X1503518Y1328671I-354J353D01*
G01Y1370119D01*
X1505187Y1371788D01*
X1520417D01*
X1521207Y1370998D01*
Y1362357D01*
X1519112Y1360263D01*
G03X1518966Y1359911I354J-353D01*
G01Y1350570D01*
X1518516Y1350120D01*
X1513152D01*
G03X1512445Y1349827I0J-999D01*
G01X1509731Y1347113D01*
G03X1509438Y1346406I706J-707D01*
G01Y1345963D01*
X1509429Y1345934D01*
G03X1509371Y1345539I1309J-394D01*
G03X1509429Y1345144I1367J-1D01*
G01X1509438Y1345115D01*
Y1342856D01*
X1509429Y1342827D01*
G03X1509371Y1342432I1309J-394D01*
G03X1509429Y1342037I1367J-1D01*
G01X1509438Y1342008D01*
Y1322917D01*
X1504647Y1318126D01*
X1479446D01*
G03X1478739Y1317833I0J-999D01*
G01X1476461Y1315555D01*
G03X1476168Y1314848I706J-707D01*
G01Y1306115D01*
X1474919Y1304866D01*
X1468508D01*
X1468494Y1304868D01*
G03X1468296Y1304882I-198J-1388D01*
G03X1468098Y1304868I0J-1402D01*
G01X1468084Y1304866D01*
X1465908D01*
X1465894Y1304868D01*
G03X1465696Y1304882I-198J-1388D01*
G03X1465498Y1304868I0J-1402D01*
G01X1465484Y1304866D01*
X1438411D01*
G03X1437182Y1305593I-1229J-675D01*
G03X1436171Y1305162I0J-1401D01*
G02X1435593I-289J277D01*
G03X1434582Y1305593I-1011J-970D01*
G03X1433353Y1304866I0J-1402D01*
G01X1404252D01*
X1404238Y1304868D01*
G03X1404040Y1304882I-198J-1388D01*
G03X1403842Y1304868I0J-1402D01*
G01X1403828Y1304866D01*
X1401652D01*
X1401638Y1304868D01*
G03X1401440Y1304882I-198J-1388D01*
G03X1401242Y1304868I0J-1402D01*
G01X1401228Y1304866D01*
X1372124D01*
X1372110Y1304868D01*
G03X1371912Y1304882I-198J-1388D01*
G03X1371714Y1304868I0J-1402D01*
G01X1371700Y1304866D01*
X1369524D01*
X1369510Y1304868D01*
G03X1369312Y1304882I-198J-1388D01*
G03X1369114Y1304868I0J-1402D01*
G01X1369100Y1304866D01*
X1343671D01*
X1338277Y1310260D01*
G02X1338255Y1310801I283J282D01*
G03X1338586Y1311706I-1072J905D01*
G03X1338155Y1312717I-1401J0D01*
G02Y1313295I277J289D01*
G03X1338586Y1314306I-970J1011D01*
G03X1337400Y1315691I-1402J0D01*
G02X1337231Y1315877I31J198D01*
G03X1336940Y1316526I-998J-58D01*
G01X1335575Y1317891D01*
G03X1334868Y1318184I-707J-706D01*
G01X1314158D01*
X1306299Y1326043D01*
X1306351Y1326166D01*
G03X1306458Y1326704I-1295J537D01*
G03X1305964Y1327773I-1402J1D01*
G01X1305893Y1327833D01*
Y1328175D01*
X1305964Y1328235D01*
G03X1306458Y1329304I-908J1068D01*
G03X1305964Y1330373I-1402J1D01*
G01X1305893Y1330433D01*
Y1330775D01*
X1305964Y1330835D01*
G03X1306458Y1331904I-908J1068D01*
G03X1305964Y1332973I-1402J1D01*
G01X1305893Y1333033D01*
Y1333375D01*
X1305964Y1333435D01*
G03X1306458Y1334504I-908J1068D01*
G03X1305964Y1335573I-1402J1D01*
G01X1305893Y1335633D01*
Y1335975D01*
X1305964Y1336035D01*
G03X1306458Y1337104I-908J1068D01*
G03X1305892Y1338230I-1403J0D01*
G03X1305600Y1338990I-998J53D01*
G01X1304106Y1340484D01*
G03X1303399Y1340777I-707J-706D01*
G01X1281303D01*
G03X1280135Y1341404I-1168J-774D01*
G03X1280024Y1341400I-5J-1402D01*
G01X1279932Y1341392D01*
X1277401Y1343923D01*
Y1361472D01*
X1277518Y1361526D01*
G03Y1364256I-627J1365D01*
G01X1277401Y1364310D01*
Y1368040D01*
X1283387Y1374026D01*
G37*
G36*
G01X1431874Y1384632D02*
X1448216D01*
X1454905Y1377943D01*
G03X1455612Y1377650I707J706D01*
G01X1525780D01*
X1537406Y1366024D01*
X1537358Y1365902D01*
G03X1537255Y1365355I1399J-547D01*
G03X1538726Y1363853I1502J0D01*
G02X1538922Y1363653I-4J-200D01*
G01Y1350727D01*
X1538315Y1350120D01*
X1520372D01*
X1519968Y1350524D01*
Y1359702D01*
X1522208Y1361942D01*
Y1371413D01*
X1520832Y1372790D01*
X1504772D01*
X1502516Y1370534D01*
Y1336025D01*
Y1335982D01*
Y1328880D01*
X1501728Y1328092D01*
X1487838D01*
Y1338634D01*
X1490706Y1341501D01*
Y1348421D01*
X1489308Y1349819D01*
X1489294Y1349865D01*
G03X1487993Y1351166I-1908J-607D01*
G01X1487947Y1351180D01*
X1487386Y1351742D01*
X1473166D01*
X1469938Y1348513D01*
Y1315007D01*
X1469606Y1314676D01*
X1455817D01*
X1455668Y1314824D01*
Y1322813D01*
X1458458Y1325601D01*
Y1335971D01*
X1456112Y1338316D01*
X1441683D01*
X1437748Y1334382D01*
Y1314974D01*
X1437454Y1314680D01*
X1423758D01*
X1423614Y1314824D01*
Y1322662D01*
X1426152Y1325200D01*
Y1335595D01*
X1425501Y1336247D01*
X1425486Y1336281D01*
G03X1424469Y1337298I-1830J-813D01*
G01X1424435Y1337313D01*
X1424066Y1337682D01*
X1412083D01*
G03X1411124Y1337926I-958J-1758D01*
G03X1410207Y1337704I-1J-2002D01*
G01X1410164Y1337682D01*
X1409240D01*
X1404794Y1333236D01*
Y1328851D01*
X1405790Y1327857D01*
Y1315109D01*
X1405357Y1314676D01*
X1391642D01*
X1391402Y1314917D01*
Y1322748D01*
X1394574Y1325919D01*
Y1335782D01*
X1393922Y1336433D01*
X1393907Y1336467D01*
G03X1392885Y1337489I-1831J-809D01*
G01X1392851Y1337504D01*
X1392581Y1337774D01*
X1380124D01*
X1380086Y1337792D01*
G03X1379271Y1337965I-814J-1829D01*
G03X1378456Y1337792I-1J-2002D01*
G01X1378418Y1337774D01*
X1377207D01*
X1373250Y1333817D01*
Y1314896D01*
X1373037Y1314684D01*
X1359485D01*
X1359278Y1314890D01*
Y1322601D01*
X1362924Y1326245D01*
Y1334653D01*
X1359930Y1337646D01*
X1347950D01*
G03X1347015Y1337878I-935J-1770D01*
G03X1346080Y1337646I0J-2002D01*
G01X1342250D01*
X1340966Y1336363D01*
Y1328354D01*
X1340795Y1328182D01*
X1327243D01*
X1327240Y1328186D01*
Y1337013D01*
X1329852Y1339624D01*
Y1348163D01*
X1329186Y1348829D01*
X1329193Y1348920D01*
G03X1329198Y1349068I-1997J142D01*
G03X1327196Y1351070I-2002J0D01*
G03X1327048Y1351065I-6J-2002D01*
G01X1326957Y1351058D01*
X1325152Y1352862D01*
X1311145D01*
X1309274Y1350990D01*
X1295292D01*
X1294914Y1351368D01*
Y1352413D01*
X1294915Y1352418D01*
G03X1294918Y1352531I-1999J110D01*
G03X1294915Y1352644I-2002J3D01*
G01X1294914Y1352649D01*
Y1358013D01*
X1294915Y1358018D01*
G03X1294918Y1358131I-1999J110D01*
G03X1294915Y1358244I-2002J3D01*
G01X1294914Y1358249D01*
Y1358975D01*
X1303452Y1367511D01*
Y1373216D01*
X1304262Y1374026D01*
X1314066D01*
G03X1314773Y1374319I0J999D01*
G01X1324003Y1383549D01*
X1353082D01*
X1360166Y1376465D01*
G03X1360873Y1376172I707J706D01*
G01X1423000D01*
G03X1423707Y1376465I0J999D01*
G01X1431874Y1384632D01*
G37*
%LPD*%
G75*
G54D20*
X40120Y1287664D03*
X69820D03*
X99520D03*
X129220Y1000853D03*
Y1287664D03*
X158920Y1000853D03*
Y1287664D03*
X188620Y1000853D03*
Y1287664D03*
X218320Y1000853D03*
Y1287664D03*
X248020Y744554D03*
Y1000853D03*
Y1287664D03*
X633320Y744554D03*
Y1000853D03*
Y1287664D03*
X663020Y744554D03*
Y1000853D03*
Y1287664D03*
X692720Y744554D03*
Y1000853D03*
Y1287664D03*
X722420Y744554D03*
Y1287664D03*
X752120Y744554D03*
Y1287664D03*
X781820Y744554D03*
Y1287664D03*
X811520Y744554D03*
Y1287664D03*
X841220Y744554D03*
Y1287664D03*
X1016262Y744554D03*
Y1287664D03*
X1045962Y744554D03*
Y1287664D03*
X1075662Y744554D03*
Y1287664D03*
X1105362Y744554D03*
Y1287664D03*
X1135062Y744554D03*
Y1000853D03*
Y1287664D03*
X1164762Y744554D03*
Y1000853D03*
Y1287664D03*
X1194462Y744554D03*
Y1000853D03*
Y1287664D03*
X1224162Y744554D03*
Y1000853D03*
Y1287664D03*
X1609462Y744554D03*
Y1000853D03*
Y1287664D03*
X1639162Y1000853D03*
Y1287664D03*
X1668862Y1000853D03*
Y1287664D03*
X1698562D03*
X1728262D03*
X1757962Y744554D03*
Y1000853D03*
Y1287664D03*
X1787662Y744554D03*
Y1000853D03*
Y1287664D03*
X1817362Y744554D03*
Y1000853D03*
Y1287664D03*
G54D11*
X3010Y63308D03*
Y123308D03*
Y163308D03*
Y183308D03*
Y203308D03*
Y223308D03*
Y243308D03*
Y263308D03*
Y283308D03*
X14092Y287115D03*
X3010Y303308D03*
X10884Y321693D03*
Y341693D03*
Y361693D03*
Y381693D03*
Y401693D03*
Y421693D03*
Y441693D03*
Y461693D03*
Y481693D03*
Y501693D03*
Y521693D03*
Y661693D03*
Y681693D03*
Y701693D03*
Y721693D03*
Y741693D03*
Y781693D03*
Y801693D03*
Y821693D03*
Y841693D03*
Y861693D03*
Y881693D03*
Y901693D03*
Y921693D03*
Y941693D03*
Y961693D03*
Y981693D03*
Y1001693D03*
Y1021693D03*
Y1041693D03*
Y1061693D03*
Y1081693D03*
Y1101693D03*
Y1121693D03*
Y1141693D03*
Y1161693D03*
Y1181693D03*
Y1201693D03*
Y1221693D03*
Y1241693D03*
Y1401693D03*
Y1421693D03*
Y1441693D03*
Y1461693D03*
Y1481693D03*
Y1501693D03*
Y1521693D03*
Y1541693D03*
Y1561693D03*
Y1581693D03*
X17371Y49388D03*
X26054Y195148D03*
X16925Y203366D03*
X17061Y196368D03*
X25752Y203274D03*
X24720Y216362D03*
X24754Y220220D03*
X24720Y232362D03*
Y224362D03*
X24814Y236472D03*
X24720Y240362D03*
X22223Y388057D03*
X29509Y398132D03*
X29962Y401000D03*
X16420Y420662D03*
X26615Y670036D03*
X26500Y672862D03*
Y675862D03*
X24700Y765600D03*
X27300Y764200D03*
X27520Y1245162D03*
X20188Y1599396D03*
X28601Y1617541D03*
Y1637541D03*
Y1657541D03*
Y1677541D03*
X37371Y49388D03*
X33500Y200862D03*
X33670Y192862D03*
Y208362D03*
X30795Y213358D03*
X35600Y227380D03*
X33670Y232362D03*
X42500Y224409D03*
X30795Y227366D03*
X33670Y240362D03*
X41492Y290637D03*
X40000Y298707D03*
X36000Y295952D03*
X40000Y293392D03*
X36255Y304972D03*
X33105D03*
X42809Y360862D03*
X35740Y363337D03*
X39410Y384582D03*
X39226Y395346D03*
X33020Y382822D03*
X39320Y392269D03*
X40940Y387302D03*
X43020Y382942D03*
X41933Y395652D03*
X36524Y398013D03*
X45182Y426310D03*
X45960Y428806D03*
X30680Y438142D03*
X45034Y449106D03*
X38220Y589862D03*
Y592862D03*
Y595862D03*
X33020Y595232D03*
X32720Y598402D03*
X34790Y666595D03*
X31390D03*
X38470Y688122D03*
Y683122D03*
Y680622D03*
Y685622D03*
Y693122D03*
Y690622D03*
Y695622D03*
X34899Y711400D03*
X45700Y724100D03*
X45800Y726874D03*
X43841Y1248688D03*
X44833Y1659909D03*
Y1656759D03*
X48269Y1672771D03*
X54593Y19183D03*
X58379Y69340D03*
X60379Y66844D03*
Y71836D03*
X60692Y87118D03*
X54920Y185039D03*
Y177165D03*
X62020Y295952D03*
X62731Y305426D03*
X46834Y360862D03*
X55190D03*
X59322Y360702D03*
X51114Y360862D03*
X61340Y384362D03*
X61250Y396142D03*
X49250Y396332D03*
X49400Y384392D03*
X47618Y413113D03*
X62833Y410047D03*
X53406Y402862D03*
X47619Y421155D03*
X62808Y418425D03*
X53825Y421746D03*
X50138Y426310D03*
X60393D03*
X49360Y428806D03*
X61171D03*
X47619Y418655D03*
X47618Y415613D03*
X54762Y444993D03*
X53800Y435451D03*
X49990Y449106D03*
X48400Y586000D03*
X57595Y603476D03*
X59500Y738700D03*
X55177Y1322328D03*
X56777Y1314165D03*
X55277Y1326068D03*
X56799Y1520094D03*
Y1524094D03*
Y1528094D03*
Y1532094D03*
Y1536094D03*
Y1544094D03*
Y1548094D03*
Y1552094D03*
Y1540094D03*
Y1556094D03*
Y1560094D03*
X54333Y1604359D03*
X59833D03*
X54333Y1613359D03*
X50333D03*
X46994Y1663165D03*
X54478Y1663669D03*
X54535Y1658447D03*
X50900Y1677775D03*
X57833Y1671809D03*
X53333Y1671862D03*
X65000Y1681900D03*
X58325Y1679275D03*
X69058Y3010D03*
X79047Y23978D03*
X74091D03*
X72091Y25974D03*
X73020Y37106D03*
Y28406D03*
X78269Y26474D03*
X74869D03*
X65937Y28403D03*
X73020Y48720D03*
Y40020D03*
X65937Y48720D03*
X67335Y69340D03*
X65335Y66844D03*
Y71836D03*
X65648Y87118D03*
X71379Y72844D03*
Y77836D03*
X76335Y72844D03*
Y77836D03*
X78335Y75340D03*
X69379D03*
X77165Y278798D03*
Y295798D03*
Y286262D03*
X65881Y305426D03*
X77165Y303262D03*
X63429Y360702D03*
X67681D03*
X77220Y379022D03*
Y381522D03*
X68020Y395222D03*
X71772Y421746D03*
X65349Y426310D03*
X75516Y420319D03*
Y424319D03*
X64571Y428806D03*
X75516Y436519D03*
X75490Y432519D03*
X68365Y443677D03*
X64150Y434972D03*
X63540Y438802D03*
X72610Y441262D03*
Y444762D03*
X77000Y485362D03*
X74550Y487812D03*
X80300Y641862D03*
X80241Y659011D03*
X80123Y664031D03*
X80135Y667933D03*
X74559Y667814D03*
X78080Y701832D03*
X63930Y739300D03*
X73759Y754726D03*
X68315Y765664D03*
X73759Y759246D03*
X65600Y1318588D03*
X65240Y1326068D03*
X75564Y1509952D03*
X78120Y1512936D03*
X76369Y1507456D03*
X78120Y1521336D03*
X76680Y1530482D03*
X72774Y1549669D03*
Y1546519D03*
X75922Y1564874D03*
Y1556474D03*
Y1558974D03*
Y1562374D03*
X73429Y1570008D03*
X78415D03*
X77618Y1572504D03*
X74218D03*
X66906Y1598324D03*
X77040Y1601102D03*
X66906Y1603280D03*
X65120Y1609909D03*
X65520Y1615972D03*
X74100Y1613300D03*
X77833Y1678902D03*
X73833Y1674252D03*
X69833Y1678582D03*
X73832Y1689362D03*
X77833Y1689162D03*
X89058Y3010D03*
X81196Y17042D03*
Y22034D03*
X86152Y17042D03*
Y22034D03*
X95369Y17042D03*
Y22034D03*
X79196Y19538D03*
X88152D03*
X93369D03*
X85374D03*
X81974D03*
X88264Y23978D03*
X93220D03*
X86264Y25974D03*
X95220D03*
X81047D03*
X94279Y37106D03*
Y28406D03*
X87193Y37106D03*
Y28406D03*
X80106Y37106D03*
Y28406D03*
X92442Y26474D03*
X89042D03*
X94279Y48720D03*
Y40020D03*
X87193Y48720D03*
Y40020D03*
X80106Y48720D03*
Y40020D03*
X80379Y69340D03*
X89335D03*
X82379Y66844D03*
Y71836D03*
X87335Y66844D03*
Y71836D03*
X91379Y75340D03*
X93379Y72844D03*
Y77836D03*
X86490Y200787D03*
Y208661D03*
X85960Y224409D03*
X85788Y240157D03*
X90700Y282762D03*
X87620Y285321D03*
X87845Y278798D03*
Y295798D03*
X90700Y300262D03*
X87820Y302821D03*
X87654Y376026D03*
X87520Y386502D03*
Y395865D03*
Y391391D03*
Y382219D03*
X85826Y424319D03*
Y420319D03*
Y428319D03*
X84410Y438519D03*
X83320Y445212D03*
X82661Y449604D03*
X94439Y450081D03*
X81505Y447377D03*
X79400Y482862D03*
X94811Y510173D03*
X91027Y643276D03*
X89859Y628246D03*
X86459D03*
X82961Y657111D03*
X95725Y654540D03*
X95860Y659622D03*
X83165Y652564D03*
X91078Y649584D03*
X83208Y646436D03*
X83250Y665428D03*
X84470Y668702D03*
X86433Y688160D03*
X81285Y689804D03*
X84035Y697604D03*
X93547Y692260D03*
X83004Y705141D03*
X97295Y699786D03*
X85095Y722164D03*
X95849Y716358D03*
X91610Y721414D03*
X82357Y737803D03*
X84623Y741249D03*
X81966Y759246D03*
X85877Y759275D03*
X88520Y1484482D03*
X92071Y1492888D03*
X88520Y1491482D03*
Y1487982D03*
Y1494982D03*
X80649Y1509944D03*
X84274Y1517619D03*
X93544Y1510099D03*
X88459Y1510107D03*
X90998Y1513037D03*
X89264Y1507611D03*
X92664D03*
X79769Y1507456D03*
X90998Y1521437D03*
X81038Y1536899D03*
X91538Y1539399D03*
X87500Y1567069D03*
X91500D03*
X84048Y1578008D03*
X90713Y1581852D03*
Y1585852D03*
Y1589852D03*
Y1593867D03*
Y1597867D03*
X81008Y1589872D03*
X90788Y1611821D03*
Y1605867D03*
Y1615821D03*
Y1601867D03*
X81900Y1613300D03*
X85800D03*
X90788Y1623821D03*
X84700Y1627000D03*
X90698Y1630362D03*
X90788Y1619821D03*
X90698Y1638362D03*
Y1634362D03*
Y1642362D03*
X90407Y1656672D03*
X88333Y1661334D03*
X81833Y1674526D03*
X86245Y1690362D03*
X81833Y1689162D03*
X94220Y1686622D03*
X86245Y1694362D03*
X96420Y1693803D03*
X86030Y1683092D03*
X92895Y1737108D03*
X109058Y3010D03*
X100325Y17042D03*
Y22034D03*
X109542Y17042D03*
Y22034D03*
X102325Y19538D03*
X107542D03*
X99547D03*
X110320D03*
X96147D03*
X102437Y23978D03*
X107393D03*
X100437Y25974D03*
X109393D03*
X108453Y37106D03*
Y28406D03*
X101366Y37106D03*
Y28406D03*
X106615Y26474D03*
X103215D03*
X108453Y48720D03*
Y40020D03*
X101366Y48720D03*
Y40020D03*
X102379Y69340D03*
X111335D03*
X104379Y66844D03*
Y71836D03*
X109335Y66844D03*
Y71836D03*
X98335Y72844D03*
Y77836D03*
X100335Y75340D03*
X113490Y216596D03*
X113400Y232128D03*
X107200Y393562D03*
X107301Y388071D03*
X104220Y400862D03*
X101720D03*
X101317Y431727D03*
X113597Y488434D03*
X102060Y493578D03*
X107419Y487807D03*
X102152Y509374D03*
X102334Y500628D03*
X102359Y497374D03*
X112480Y507792D03*
X110689Y498271D03*
X110464Y505374D03*
X102152Y513374D03*
X111087Y520052D03*
X101983Y518100D03*
X99880Y526300D03*
X110060Y515279D03*
X99773Y515606D03*
X105587Y520727D03*
X106110Y633732D03*
X107489Y630917D03*
X110374Y630879D03*
X102269Y634466D03*
X107045Y661917D03*
X99021Y663732D03*
X103397Y667272D03*
X102120Y688650D03*
X102060Y692100D03*
X102420Y697262D03*
X96626Y736187D03*
X110527Y758869D03*
X112270Y1518907D03*
X99274Y1526019D03*
Y1529169D03*
X96570Y1546187D03*
X99716Y1567878D03*
X99750Y1559478D03*
Y1565378D03*
Y1561978D03*
X96251Y1577532D03*
X107451Y1574704D03*
X100451D03*
X103902Y1584337D03*
X102251Y1576504D03*
X105651D03*
X104318Y1592304D03*
Y1589352D03*
X100620Y1596367D03*
X104318Y1603690D03*
X110200Y1605200D03*
X101500Y1604400D03*
X100020Y1615821D03*
X98738Y1605867D03*
X104318Y1622380D03*
X104400Y1632385D03*
X104430Y1628012D03*
X104318Y1641075D03*
Y1637862D03*
X99600Y1668332D03*
X99645Y1663217D03*
X99980Y1685362D03*
Y1696052D03*
Y1687921D03*
Y1698921D03*
X114498Y17042D03*
Y22034D03*
X123716Y17042D03*
Y22034D03*
X116498Y19538D03*
X121716D03*
X113720D03*
X127894D03*
X124494D03*
X121567Y23978D03*
X116611D03*
X114611Y25974D03*
X123567D03*
X122626Y37106D03*
Y28406D03*
X115539Y37106D03*
Y28406D03*
X120789Y26474D03*
X117389D03*
X122626Y48720D03*
Y40020D03*
X115539Y48720D03*
Y40020D03*
X124379Y69340D03*
X126379Y66844D03*
Y71836D03*
X115379Y72844D03*
Y77836D03*
X120335Y72844D03*
Y77836D03*
X122335Y75340D03*
X113379D03*
X115850Y186362D03*
X122000Y207362D03*
X116920Y207462D03*
X114087Y285495D03*
X118920Y278875D03*
X114087Y302854D03*
X119220Y306236D03*
X119920Y379362D03*
X125007Y392071D03*
Y388071D03*
Y384071D03*
Y396071D03*
X119457Y392071D03*
Y388071D03*
X114507Y404571D03*
X117597Y488434D03*
X127206Y480216D03*
X125070Y486736D03*
X125013Y491829D03*
X124124Y495883D03*
X116171Y485041D03*
X126225Y504368D03*
X120225D03*
Y510368D03*
X112483Y510637D03*
X116411Y497707D03*
X126225Y516368D03*
X120225D03*
X118652Y528860D03*
X129762Y531942D03*
X115793Y528188D03*
X112393D03*
X123257Y547506D03*
X119087D03*
X115060D03*
X111920Y632922D03*
X114540Y633032D03*
X117750Y633232D03*
X120440Y633347D03*
X121400Y638062D03*
X125890Y644163D03*
X122329Y654660D03*
X122280Y651934D03*
X124431Y649570D03*
X122575Y671930D03*
X118019Y661371D03*
X124737Y735726D03*
X118737D03*
X121737D03*
Y738726D03*
X118737D03*
X124737D03*
X123220Y1324662D03*
X120220D03*
X120267Y1327697D03*
X127366Y1535855D03*
X112749Y1524594D03*
Y1532594D03*
Y1528594D03*
X127366Y1541874D03*
Y1547935D03*
X112749Y1540594D03*
Y1544594D03*
Y1548594D03*
Y1536594D03*
Y1552594D03*
Y1564594D03*
Y1560594D03*
Y1556594D03*
X117707Y1553759D03*
X116798Y1586288D03*
Y1598572D03*
X125033Y1589352D03*
X116798D03*
X123230Y1597350D03*
X116798Y1617262D03*
X119500Y1622380D03*
X116798Y1635303D03*
X117220Y1680287D03*
X127195Y1670362D03*
X124795Y1681846D03*
X128195Y1674362D03*
X117795Y1698862D03*
X127195Y1688362D03*
Y1692362D03*
X114645Y1698862D03*
X117220Y1683437D03*
X127195Y1696362D03*
Y1708362D03*
Y1700362D03*
Y1704362D03*
X117255Y1730422D03*
X125082Y1727092D03*
X123394Y1723472D03*
X117426Y1726622D03*
X125720Y1719262D03*
X112895Y1737108D03*
X129058Y3010D03*
X128672Y17042D03*
Y22034D03*
X130672Y19538D03*
X129713Y37106D03*
Y28406D03*
Y48720D03*
Y40020D03*
X133335Y69340D03*
X131335Y66844D03*
Y71836D03*
X137379Y72844D03*
Y77836D03*
X142335Y72844D03*
Y77836D03*
X135379Y75340D03*
X136301Y179095D03*
X141520Y181462D03*
X139720Y179162D03*
X143470Y184012D03*
X143340Y204622D03*
X133590Y212382D03*
X140974Y396885D03*
X135220Y397071D03*
X140974Y401885D03*
Y399385D03*
X132490Y420062D03*
X138042Y480238D03*
X132833D03*
X142166Y490835D03*
X136982Y497090D03*
X131737Y496295D03*
X135006Y487753D03*
X131295Y487822D03*
X132225Y504368D03*
Y510368D03*
X141325Y503806D03*
X141462Y507600D03*
X141329Y510487D03*
X141220Y498810D03*
X138878Y512550D03*
X138408Y507366D03*
X132401Y516368D03*
X139153Y516453D03*
X133160Y532002D03*
X132600Y537072D03*
Y540472D03*
X133467Y634531D03*
X131740Y640103D03*
X131600Y646861D03*
X131330Y665740D03*
X142960Y690807D03*
X140460D03*
X142754Y698811D03*
X140254D03*
X142778Y706835D03*
X140278D03*
X140326Y721660D03*
X142826D03*
X141470Y1359100D03*
X140142Y1392545D03*
Y1396275D03*
X144263Y1412275D03*
X129670Y1563160D03*
X140104Y1560136D03*
X129627Y1556360D03*
X129586Y1553759D03*
X129813Y1604367D03*
X130533Y1622321D03*
X129533Y1637862D03*
X137420Y1708362D03*
X144520Y1717562D03*
X138492Y1717592D03*
X139080Y1731398D03*
X141642Y1717592D03*
X134557Y1722778D03*
X137852Y1726572D03*
X132895Y1737108D03*
X149058Y3010D03*
X159582Y17042D03*
Y22034D03*
X157582Y19538D03*
X160360D03*
X152477Y23978D03*
X157433D03*
X150477Y25974D03*
X159433D03*
X158492Y37106D03*
Y28406D03*
X151405Y37106D03*
Y28406D03*
X156655Y26474D03*
X153255D03*
X147924Y28258D03*
X158492Y48720D03*
Y40020D03*
X151405Y48720D03*
Y40020D03*
X148784Y48720D03*
X146379Y69340D03*
X155335D03*
X148379Y66844D03*
Y71836D03*
X153335Y66844D03*
Y71836D03*
X158583Y75340D03*
X144335D03*
X147901Y188852D03*
X145720Y186462D03*
Y202862D03*
Y206362D03*
X156670Y344542D03*
X159170D03*
X154220Y375682D03*
X158110Y376172D03*
X160090Y391170D03*
Y397470D03*
X149371Y423383D03*
Y419383D03*
Y427383D03*
Y439383D03*
Y431383D03*
Y435383D03*
Y443383D03*
X152826Y439397D03*
Y434362D03*
X159125Y448664D03*
X156306Y449045D03*
X153360Y449112D03*
X152171Y490615D03*
X150113Y488487D03*
X161267Y503143D03*
X149472Y502810D03*
X149486Y498810D03*
X160000Y510052D03*
X152470Y495383D03*
X151378Y526924D03*
X149518Y522810D03*
X150800Y512021D03*
X153737Y514893D03*
X149504Y519881D03*
X154647Y521783D03*
X150877Y757969D03*
X154477Y1360797D03*
X159898Y1360790D03*
X148663Y1378607D03*
X151163D03*
Y1383807D03*
Y1381207D03*
X158318Y1384286D03*
X155718D03*
X158318Y1387393D03*
X155718D03*
X148663Y1386407D03*
X151163D03*
X148663Y1383807D03*
Y1381207D03*
X160201Y1399732D03*
X157731D03*
Y1394132D03*
X160201D03*
X147307Y1404745D03*
X149568Y1395145D03*
Y1397695D03*
X152684Y1403451D03*
X152806Y1414175D03*
X159858Y1409361D03*
X155858Y1406669D03*
Y1409390D03*
X144748Y1514878D03*
X149728D03*
X146390Y1504240D03*
X145538Y1517374D03*
X148938D03*
X153600Y1505600D03*
X154581Y1520981D03*
X158570D03*
X153271Y1540961D03*
X153138Y1549032D03*
X147067Y1545985D03*
X150502Y1572021D03*
X145522D03*
X159107Y1571364D03*
X157441Y1581932D03*
X146312Y1569525D03*
X149712D03*
X152026Y1614138D03*
X158335Y1614452D03*
X155180Y1619872D03*
X156070Y1695702D03*
X144854Y1702389D03*
X154803Y1708532D03*
X145745Y1712362D03*
X161310Y1708022D03*
X148145Y1701862D03*
X155145Y1713517D03*
X155100Y1723262D03*
X152895Y1737108D03*
X169058Y3010D03*
X164538Y17042D03*
Y22034D03*
X173755Y17042D03*
Y22034D03*
X166538Y19538D03*
X171755D03*
X163760D03*
X174533D03*
X166650Y23978D03*
X171606D03*
X164650Y25974D03*
X173606D03*
X172665Y37106D03*
Y28406D03*
X165579Y37106D03*
Y28406D03*
X170828Y26474D03*
X167428D03*
X172665Y48720D03*
Y40020D03*
X165579Y48720D03*
Y40020D03*
X169583Y69340D03*
X171583Y66844D03*
Y71836D03*
X176539Y66844D03*
Y71836D03*
X165539Y72844D03*
X160583D03*
Y77836D03*
X165539D03*
X167539Y75340D03*
X174327Y230928D03*
X164830Y344542D03*
X161670D03*
X173275Y393497D03*
X171180Y401885D03*
X163900Y409362D03*
X164000Y415362D03*
X163926Y425383D03*
X164000Y420362D03*
X172507Y417205D03*
X163926Y430883D03*
Y443319D03*
Y439397D03*
Y435383D03*
X175640Y453779D03*
X178546Y453806D03*
X172632Y454095D03*
X163132Y493299D03*
X165176Y500782D03*
X162750Y512502D03*
X166986Y575918D03*
X176651Y596883D03*
Y594163D03*
X173878Y597027D03*
Y594307D03*
X176651Y599603D03*
X173878Y599747D03*
X161126Y721660D03*
X161078Y706835D03*
X163626Y721660D03*
X163578Y706835D03*
X162398Y1360790D03*
X164898D03*
X172807Y1360797D03*
X160918Y1384286D03*
X163518D03*
Y1387393D03*
X160918D03*
X169318Y1384286D03*
X166118D03*
X172262Y1384302D03*
Y1387409D03*
X174932Y1378797D03*
Y1381397D03*
X163718Y1390500D03*
X161118D03*
X162631Y1399732D03*
Y1394132D03*
X172231Y1390532D03*
X176358Y1403669D03*
X176258Y1400669D03*
X173892Y1402749D03*
Y1405649D03*
X170922Y1399255D03*
X166262D03*
X173252Y1400005D03*
X168592D03*
X162693Y1411529D03*
X164000Y1408862D03*
X162257Y1406594D03*
X171262Y1443390D03*
X173727Y1452134D03*
Y1448734D03*
X170570Y1509250D03*
X164710Y1518014D03*
X168110D03*
X168900Y1520510D03*
X163920D03*
X161321Y1540858D03*
X161374Y1549073D03*
X166476Y1572464D03*
X171456D03*
X173331Y1579399D03*
X167266Y1569968D03*
X170666D03*
X172099Y1588141D03*
X166529Y1707678D03*
X164920Y1712017D03*
X163060Y1717017D03*
X166661Y1721211D03*
X178226Y1726517D03*
X172962Y1721234D03*
X169777Y1726517D03*
X178142Y1720652D03*
X172895Y1737108D03*
X166761Y1732967D03*
X189058Y3010D03*
X178711Y17042D03*
Y22034D03*
X180711Y19538D03*
X177933D03*
X179752Y37106D03*
Y28406D03*
X186120Y24162D03*
X188620D03*
X179752Y48720D03*
Y40020D03*
X191583Y69340D03*
X178539D03*
X182583Y72844D03*
Y77836D03*
X187539Y72844D03*
Y77836D03*
X189539Y75340D03*
X180583D03*
X186457Y393071D03*
Y385071D03*
Y389071D03*
X190880Y383012D03*
Y387162D03*
Y391082D03*
X178375Y396571D03*
X186457Y405071D03*
X192220Y408662D03*
Y412162D03*
X184490Y402203D03*
X181845Y401071D03*
X177871Y421383D03*
Y425383D03*
X191305Y430216D03*
X187371Y425383D03*
Y430883D03*
X177871D03*
Y443383D03*
X187371D03*
X180740Y437562D03*
X184550Y435712D03*
X187371Y440742D03*
X194440Y433895D03*
Y439565D03*
X188221Y454048D03*
X184147Y447078D03*
X187371Y447172D03*
X177871D03*
X181994Y453932D03*
X180640Y447172D03*
X185211Y453942D03*
X185191Y502439D03*
X187490Y568752D03*
X181651Y596883D03*
X179151D03*
X186796Y594195D03*
Y596915D03*
X184151Y596883D03*
X179151Y594163D03*
X181651D03*
X184151D03*
X181651Y599603D03*
X179151D03*
X186796Y599635D03*
X184151Y599603D03*
X186720Y737862D03*
X180720D03*
X183720D03*
Y734862D03*
X180720D03*
X186720D03*
X185835Y757057D03*
X188978Y756855D03*
X191602Y756839D03*
X184215Y1361072D03*
X181403Y1361115D03*
X192620Y1360797D03*
X188233Y1387027D03*
Y1379227D03*
Y1381827D03*
Y1384427D03*
X183283Y1387987D03*
X185633Y1387027D03*
X180672Y1387987D03*
X185633Y1379227D03*
X180672Y1380187D03*
X183283D03*
X177532Y1378797D03*
X185633Y1384427D03*
Y1381827D03*
X180672Y1382787D03*
Y1385387D03*
X183283Y1382787D03*
Y1385387D03*
X177421Y1383997D03*
X177532Y1381397D03*
X182653Y1404535D03*
X187711Y1395170D03*
Y1397670D03*
X190827Y1403451D03*
X180977Y1396173D03*
X178458Y1399269D03*
Y1402169D03*
Y1405069D03*
X192767Y1413725D03*
X185643Y1413945D03*
X188211Y1406691D03*
X186165Y1422589D03*
X183135Y1419784D03*
X180510Y1420258D03*
X177510D03*
X186135Y1419784D03*
X183165Y1422589D03*
X177510Y1423278D03*
X180510D03*
X183075Y1430424D03*
Y1425424D03*
Y1427924D03*
X186075Y1430424D03*
Y1425424D03*
Y1427924D03*
X183075Y1432924D03*
X186075D03*
X185895Y1535462D03*
Y1539723D03*
Y1544029D03*
Y1548487D03*
Y1552875D03*
X192600Y1557360D03*
X185895Y1557875D03*
X189600Y1566300D03*
X187400Y1568132D03*
X176793Y1585173D03*
X192529Y1728947D03*
X183822Y1720517D03*
X187542Y1729092D03*
X193293Y1722197D03*
X188794Y1725092D03*
X192895Y1737108D03*
X209058Y3010D03*
X203716Y17042D03*
Y22034D03*
X208672Y17042D03*
Y22034D03*
X201716Y19538D03*
X207894D03*
X204494D03*
X201567Y23978D03*
X196611D03*
X194611Y25974D03*
X203567D03*
X208784D03*
X202626Y28406D03*
Y37106D03*
X195539Y28406D03*
Y37106D03*
X200789Y26474D03*
X197389D03*
X202626Y40020D03*
Y48720D03*
X195539Y40020D03*
Y48720D03*
X200539Y69340D03*
X193583Y66844D03*
Y71836D03*
X198539Y66844D03*
Y71836D03*
X204717Y72844D03*
Y77836D03*
X202717Y75340D03*
X195050Y412055D03*
X199047Y428626D03*
X199139Y422882D03*
X204699Y423242D03*
Y428742D03*
X195050Y417465D03*
X196215Y447565D03*
X197650Y455712D03*
X208200Y493510D03*
X202338Y568746D03*
X201392Y574271D03*
X198336D03*
X204610Y571097D03*
X199164Y582481D03*
X200654Y578271D03*
X201622Y581009D03*
X208056Y591665D03*
X208806Y589335D03*
X208056Y587005D03*
X208806Y584675D03*
X202262Y592305D03*
X205162D03*
X194059Y604901D03*
X202338Y602746D03*
X201392Y608271D03*
X198336D03*
X203892Y594471D03*
X202492Y596571D03*
X208292D03*
X206892Y594371D03*
X205392Y596571D03*
X204610Y605097D03*
X199164Y616481D03*
X200654Y612271D03*
X201622Y615009D03*
X208806Y618675D03*
X208056Y621005D03*
X208806Y623335D03*
X202338Y636746D03*
X208056Y625665D03*
X203892Y628471D03*
X202492Y630571D03*
X202262Y626305D03*
X208292Y630571D03*
X206892Y628371D03*
X205162Y626305D03*
X205392Y630571D03*
X204610Y639097D03*
X201392Y642271D03*
X199164Y650481D03*
X200654Y646271D03*
X201622Y649009D03*
X198336Y642271D03*
X208056Y655005D03*
X208806Y657335D03*
Y652675D03*
X207620Y671262D03*
X198420Y672662D03*
X198495Y669487D03*
X208056Y659665D03*
X205392Y664571D03*
X205162Y660305D03*
X206892Y662371D03*
X202262Y660305D03*
X202492Y664571D03*
X203892Y662471D03*
X208292Y664571D03*
X196049Y678195D03*
X194196Y687061D03*
X200018Y677492D03*
X193332Y678195D03*
X207129Y690027D03*
X203199Y690006D03*
X197086Y686326D03*
X203179Y693626D03*
X207140Y693636D03*
X195735Y696469D03*
X198235Y698969D03*
Y696469D03*
X200735Y698969D03*
Y696469D03*
X207140Y738462D03*
X205220Y736562D03*
X201220Y736662D03*
X203660Y731802D03*
X195602Y756839D03*
X203602Y756855D03*
X203441Y1360790D03*
X198041D03*
X200941D03*
X201661Y1384286D03*
X193861D03*
X196461D03*
X199061D03*
X201661Y1387393D03*
X193861D03*
X196461D03*
X199061D03*
X204261Y1384286D03*
X207461D03*
X201861Y1390500D03*
X199261D03*
X195874Y1399732D03*
X198344D03*
X200774D03*
X195874Y1394132D03*
X198344D03*
X200774D03*
X206735Y1400005D03*
X209065Y1399255D03*
X204405D03*
X201071Y1412173D03*
X198001Y1409361D03*
X193941Y1407029D03*
X200797Y1409605D03*
X200492Y1406686D03*
X193941Y1409750D03*
X195966Y1542863D03*
X207229Y1631181D03*
X203120Y1624782D03*
X208115Y1624217D03*
X193410Y1711606D03*
X205582Y1700867D03*
X195590Y1714517D03*
X196010Y1709017D03*
X208295Y1703362D03*
X196443Y1722197D03*
X199050Y1726431D03*
X204600Y1733022D03*
X217889Y17042D03*
Y22034D03*
X222845Y17042D03*
Y22034D03*
X210672Y19538D03*
X215889D03*
X224845D03*
X222067D03*
X218667D03*
X215740Y23978D03*
X210784D03*
X217740Y25974D03*
X223886Y28406D03*
Y37106D03*
X216799Y28406D03*
Y37106D03*
X209713Y28406D03*
Y37106D03*
X214962Y26474D03*
X211562D03*
X223886Y40020D03*
Y48720D03*
X216799Y40020D03*
Y48720D03*
X209713Y40020D03*
Y48720D03*
X215717Y66844D03*
Y71836D03*
X220673Y66844D03*
Y71836D03*
X213717Y69340D03*
X222673D03*
X209673Y72844D03*
Y77836D03*
X211673Y75340D03*
X224717D03*
X223330Y426467D03*
X220843Y430004D03*
X209530Y426192D03*
X217770Y428262D03*
X224210Y431501D03*
X224305Y422977D03*
X219995Y426267D03*
X220874Y442079D03*
X224210Y436619D03*
X218140Y440735D03*
X218010Y432735D03*
X223664Y443125D03*
X220000Y448735D03*
X209579Y457222D03*
Y462235D03*
X212891Y566632D03*
X210391Y567981D03*
X212891Y601981D03*
X210391D03*
Y635981D03*
X212891D03*
X210320Y671262D03*
X224900Y713293D03*
X209720Y731862D03*
X220033Y756844D03*
X211602Y756855D03*
X216842Y756865D03*
X215824Y1361199D03*
X211350Y1360797D03*
X218960Y1388312D03*
X210405Y1384302D03*
Y1387409D03*
X213075Y1381558D03*
X217133Y1384055D03*
X214425Y1384058D03*
X215675Y1381558D03*
X218175D03*
X213075Y1378958D03*
X215675D03*
X218175D03*
X219752Y1405499D03*
Y1401999D03*
Y1398599D03*
X210374Y1390532D03*
X211395Y1400005D03*
X214201Y1404169D03*
X212035Y1402899D03*
X214101Y1401169D03*
X216554Y1399264D03*
Y1402164D03*
Y1405064D03*
X212035Y1405799D03*
X224137Y1414345D03*
X224077Y1416975D03*
X224350Y1432032D03*
X219587Y1435402D03*
X217469Y1454725D03*
X219587Y1443402D03*
Y1439402D03*
X220869Y1454725D03*
X209820Y1631142D03*
X210593Y1714017D03*
X212120Y1703062D03*
X214120Y1713462D03*
X212684Y1720307D03*
X212895Y1737108D03*
X229058Y3010D03*
X233339Y17662D03*
X235701Y21582D03*
X241310Y20322D03*
X238063Y37162D03*
X230972Y28406D03*
Y37106D03*
X229135Y26474D03*
X225735D03*
X238063Y26232D03*
X235701Y39570D03*
X230972Y48720D03*
Y40020D03*
X229131Y50646D03*
X225731D03*
X239820Y54362D03*
X239720Y71862D03*
X226717Y72844D03*
Y77836D03*
X231673Y72844D03*
Y77836D03*
X233673Y75340D03*
X239010Y78542D03*
X238297Y129703D03*
X242215Y151788D03*
X233800Y162692D03*
X237539Y174266D03*
X234902Y174047D03*
X226800Y359464D03*
X228550Y420412D03*
X230359Y461683D03*
X240993Y570490D03*
Y604490D03*
Y596820D03*
Y594220D03*
Y638490D03*
Y630820D03*
Y628220D03*
X227430Y719772D03*
X238940Y716652D03*
X230864Y1254295D03*
X249058Y3010D03*
X243490Y23002D03*
X246510Y20362D03*
X253000Y28362D03*
X256500D03*
X249500D03*
X242220Y39362D03*
X246220D03*
X250220D03*
X254050Y39422D03*
X246360Y26852D03*
X248820Y48962D03*
X252320D03*
X255820D03*
X257520Y51562D03*
X254020D03*
X250520D03*
X247720Y71862D03*
X244300Y59762D03*
X249885Y69623D03*
X245220Y67862D03*
X247720Y75862D03*
X251797Y100843D03*
X244822Y115543D03*
Y111543D03*
X253910Y115722D03*
X253878Y111771D03*
X252195Y144320D03*
X249735Y152694D03*
X259933Y141122D03*
X242255Y162512D03*
X257256Y156727D03*
X245490Y159702D03*
X252000Y395400D03*
X255810Y405582D03*
X252500Y415862D03*
X257434Y415896D03*
X258066Y426735D03*
X259845Y461117D03*
X257750Y450842D03*
X249300Y510362D03*
X253800Y515362D03*
X249860Y518222D03*
X254713Y518465D03*
X245700Y513262D03*
X250100Y521783D03*
X246400Y563162D03*
X242460Y716652D03*
X253057Y755345D03*
X245487Y755435D03*
X259510Y757822D03*
X251187Y1255025D03*
X252895Y1737108D03*
X269058Y3010D03*
X260000Y28362D03*
X263280Y35312D03*
X272600Y27182D03*
X263240Y38122D03*
X266990Y41832D03*
X275120Y28562D03*
X271600Y40162D03*
X275900Y48872D03*
X259320Y48962D03*
X261020Y51562D03*
X263520D03*
X261820Y48962D03*
X264740Y49182D03*
X266497Y69536D03*
Y72036D03*
X264720Y56362D03*
Y60362D03*
Y64362D03*
X266597Y77526D03*
Y80026D03*
X263320Y87662D03*
X261420Y100662D03*
X264920D03*
X268420D03*
X262920Y97962D03*
X266420D03*
X269920D03*
X273620Y96662D03*
X272361Y120243D03*
X270364Y118415D03*
X263550Y120922D03*
X269191Y121092D03*
X275797Y120245D03*
X261387Y133783D03*
X258257D03*
X265910Y125492D03*
X266975Y140107D03*
X260600Y151062D03*
X272800Y140162D03*
X264578Y151203D03*
Y155203D03*
Y159203D03*
X260100Y159562D03*
X260700Y218662D03*
X268940Y217982D03*
X263580Y218627D03*
X270745Y207562D03*
X265343Y244460D03*
X270240Y245332D03*
X258746Y407842D03*
X260807Y424403D03*
X263430Y422235D03*
X272029Y443735D03*
X262963D03*
X272500Y447735D03*
X263040Y448752D03*
X272500Y452862D03*
X269600Y715792D03*
X274247Y727165D03*
X268331Y738029D03*
X273046Y735662D03*
X270100Y727262D03*
X264000Y726262D03*
X266700Y730962D03*
X270322Y740207D03*
X274270Y746602D03*
X271570Y746422D03*
X265997Y747535D03*
X272208Y768516D03*
X271057Y765525D03*
Y762425D03*
X272895Y1737108D03*
X289058Y3010D03*
X287000Y20862D03*
X285900Y23962D03*
X286071Y28406D03*
X278984D03*
X284233Y26474D03*
X280833D03*
X290799Y28362D03*
X287952Y39984D03*
X286071Y48720D03*
X286500Y52462D03*
X278984Y48720D03*
X284230Y50646D03*
X280830D03*
X289400Y54222D03*
X287800Y60062D03*
X279277Y99183D03*
X289557Y121803D03*
X275797Y129592D03*
X283953Y152503D03*
X280687Y140746D03*
X287000Y139862D03*
X283053Y139728D03*
X276825Y140462D03*
X288520Y157062D03*
X290685Y165447D03*
X282640Y214102D03*
X279740Y205962D03*
X276890Y249022D03*
X289920Y248652D03*
X286920D03*
X282420D03*
X284482Y569548D03*
X286582Y630757D03*
X287819Y691097D03*
X284287Y716015D03*
X277046Y725709D03*
Y735442D03*
X284358Y732562D03*
X287820Y727962D03*
X278520Y738072D03*
X283350Y728483D03*
X289137Y735275D03*
X279507Y727025D03*
X285046Y737964D03*
X281046Y737938D03*
X275210Y738102D03*
X290077Y739735D03*
X287607Y754962D03*
X277046Y746702D03*
X281046D03*
X285046D03*
X289047Y760245D03*
X291520Y12762D03*
X291660Y21642D03*
X299500Y22862D03*
X295520Y12762D03*
X302610Y26362D03*
X292060Y24472D03*
X295520Y26362D03*
X300248Y28362D03*
X304927Y24654D03*
X304972Y28362D03*
X302720Y38182D03*
X298720Y40017D03*
X306720Y39982D03*
X292590Y53982D03*
X293161Y50522D03*
X306570Y50222D03*
X290720Y40017D03*
X294720D03*
X295524Y52092D03*
X301310Y52482D03*
X298550Y51602D03*
X303715Y50857D03*
X292942Y67513D03*
X305747Y64013D03*
Y61113D03*
X305247Y71567D03*
X293447Y78573D03*
X293452Y82483D03*
Y85983D03*
X303047Y79373D03*
X299947Y79273D03*
X301600Y82457D03*
X302310Y75673D03*
X295357Y88903D03*
X299657Y92503D03*
X307820Y95724D03*
X301751Y127466D03*
Y124466D03*
Y121466D03*
X305025Y144202D03*
X299628Y149203D03*
X302891Y141811D03*
X296800Y139762D03*
X299628Y158703D03*
X294553Y153819D03*
X306000Y165662D03*
X295685Y165447D03*
X296478Y158703D03*
X306730Y173842D03*
X298587Y508074D03*
X300520Y552262D03*
X306087Y569718D03*
X307987Y577658D03*
X293805Y569397D03*
Y565997D03*
X298000Y587890D03*
X308417Y585158D03*
X308447Y592255D03*
X306144Y602225D03*
X305612Y622530D03*
Y625030D03*
X294658Y637809D03*
X305612Y627530D03*
X296405Y630732D03*
Y634132D03*
X295962Y679374D03*
X294679Y688446D03*
Y685046D03*
X291600Y705162D03*
X298273Y715400D03*
X297087Y721249D03*
X304602Y727968D03*
X293027Y755985D03*
X290680Y745312D03*
X299427Y768265D03*
X303831Y1318566D03*
X303723Y1353316D03*
Y1355853D03*
X304051Y1365453D03*
X306667Y1361597D03*
X302805Y1379941D03*
Y1376541D03*
X296170Y1622852D03*
X292895Y1737108D03*
X309058Y3010D03*
X318651Y22921D03*
X310400Y50362D03*
X314657Y71803D03*
Y68903D03*
X323040Y73122D03*
X320057Y85803D03*
X323117Y81168D03*
Y76938D03*
X322875Y84318D03*
X316364Y89212D03*
X310459Y75892D03*
X320430Y78002D03*
X320057Y88803D03*
X311758Y124469D03*
Y121469D03*
Y127469D03*
X324733Y148598D03*
X308175Y144202D03*
X320825Y159062D03*
X308500Y165662D03*
X311200Y165562D03*
X309230Y173842D03*
X309756Y177449D03*
Y181449D03*
X310970Y195362D03*
X308790Y197622D03*
X320270Y200462D03*
X319370Y214492D03*
X316370D03*
X319370Y217492D03*
X316370D03*
X323314Y210645D03*
X306910Y228162D03*
X309910D03*
X306910Y225162D03*
X309910D03*
X322658Y229254D03*
X319718Y223750D03*
X313995Y237724D03*
X320940Y238372D03*
X316444Y559125D03*
X317860Y572322D03*
X319520Y577658D03*
X314200Y585282D03*
X316080Y578262D03*
X312007Y588675D03*
X319520Y582658D03*
X316127Y592785D03*
X318560Y587632D03*
X320691Y602448D03*
X311820Y598762D03*
X321276Y599298D03*
X317386Y623207D03*
X308605Y629525D03*
Y627025D03*
X319557Y736225D03*
X317967Y746985D03*
Y771875D03*
X316397Y776125D03*
X321119Y1313108D03*
X317119D03*
X313119D03*
X313841Y1365553D03*
X309841Y1364815D03*
X318051Y1367043D03*
X316579Y1364585D03*
X309841Y1367871D03*
X329535Y49388D03*
X336240Y150738D03*
X332500D03*
X326216Y138787D03*
X335285Y210609D03*
X332285D03*
X335575Y214170D03*
X328588Y209677D03*
X325755Y230719D03*
X338985Y229509D03*
X325855Y227619D03*
X328939Y229139D03*
X335385Y235309D03*
X335412Y222176D03*
X325055Y237219D03*
X328965Y237214D03*
X332465D03*
X341295Y290239D03*
X330417Y380482D03*
X330674Y368261D03*
Y365702D03*
X328167Y379073D03*
X336370Y406302D03*
X336270Y402992D03*
X329050Y607402D03*
X331760Y705882D03*
X331339Y709313D03*
X328120Y710862D03*
X335677Y715215D03*
X327107Y732665D03*
X335467Y725335D03*
X338097Y736235D03*
X335126Y728323D03*
X327096Y736005D03*
X336446Y746486D03*
X338667Y772452D03*
X341527Y778362D03*
X325119Y1313108D03*
X328915Y1337104D03*
Y1331904D03*
Y1329304D03*
Y1334504D03*
Y1326704D03*
X335679Y1330518D03*
X334973Y1333353D03*
X338795Y1338799D03*
X336179Y1342753D03*
X332895Y1737108D03*
X349535Y49388D03*
X343040Y122522D03*
X340440Y120552D03*
X343450Y131167D03*
X344776Y148462D03*
X342700Y139662D03*
X355189Y144267D03*
X351100Y150412D03*
X348100Y185162D03*
X345869Y192716D03*
X345600Y188162D03*
X356295Y219362D03*
X353145Y228362D03*
X354145Y290591D03*
X345164Y314234D03*
X343411Y363143D03*
X345411Y364702D03*
X343411Y375364D03*
X345411Y376923D03*
X343354Y387988D03*
Y391643D03*
X343720Y400628D03*
X347340Y407462D03*
X348880Y703442D03*
X354100Y720743D03*
X349187Y715485D03*
X352879Y728657D03*
X348037Y728735D03*
X348730Y735098D03*
Y731698D03*
X344446Y739434D03*
X348000Y755362D03*
X339769Y1299868D03*
X342769D03*
X345969Y1342755D03*
X341969Y1342017D03*
X350179Y1344245D03*
X348707Y1341787D03*
X341969Y1345073D03*
X352895Y1737108D03*
X366775Y127662D03*
X363625D03*
X361800Y122522D03*
X366060Y133912D03*
X366675Y158702D03*
X356250Y216342D03*
X358209Y208169D03*
X361190Y210762D03*
X357303Y213159D03*
X371551Y224862D03*
X357764Y314234D03*
X357660Y318850D03*
X364014Y366391D03*
X363750Y369362D03*
X371370Y373622D03*
X364014Y378649D03*
Y382304D03*
X364179Y394596D03*
Y392037D03*
X371066Y400628D03*
X370200Y409582D03*
X373720Y431362D03*
X369690Y431812D03*
X365970Y444662D03*
X365720Y440562D03*
X365771Y449480D03*
X359669Y686744D03*
X359639Y690114D03*
X360470Y705965D03*
X363101Y697348D03*
Y693948D03*
X360990Y726862D03*
X359930Y732985D03*
X358902Y736225D03*
X355946Y728800D03*
X359790Y729835D03*
X358902Y739755D03*
Y743035D03*
Y754945D03*
Y746405D03*
X360927Y757665D03*
X358902Y773352D03*
X361043Y1306506D03*
X361769Y1300008D03*
X363643Y1306506D03*
X364769Y1300008D03*
X367939Y1303319D03*
X361043Y1314306D03*
Y1309106D03*
Y1311706D03*
X367694Y1317092D03*
X367807Y1319592D03*
X368391Y1328161D03*
X370923Y1325373D03*
X367948Y1531529D03*
X371850Y1534062D03*
X368600Y1543200D03*
X367140Y1645390D03*
X366700Y1649000D03*
X370500Y1654362D03*
X370635Y1675820D03*
X369300Y1680400D03*
Y1682900D03*
X383140Y119822D03*
X380930Y122022D03*
X375330Y121182D03*
X374981Y131433D03*
X383160Y124322D03*
X383060Y128491D03*
X372530Y122972D03*
X373200Y126052D03*
X379295Y131002D03*
X376245Y212862D03*
Y217362D03*
Y221362D03*
Y225362D03*
X386120Y220322D03*
X385720Y323761D03*
Y320902D03*
X376500Y362736D03*
Y366391D03*
Y378649D03*
X376770Y387272D03*
X377136Y390307D03*
X390220Y392062D03*
X383060Y403542D03*
X385520Y429262D03*
X373190Y438342D03*
X384510Y438662D03*
X379220Y436362D03*
X376220D03*
X382220D03*
X385730Y460922D03*
X389920Y461362D03*
X382860Y471122D03*
X379220Y470962D03*
X387500Y495362D03*
X389020Y522862D03*
X371970Y683892D03*
X381010Y734732D03*
X383239Y1286578D03*
X378069Y1286568D03*
X375069D03*
X386239Y1286578D03*
X378097Y1329329D03*
X374097Y1328591D03*
X382307Y1330819D03*
X380835Y1328361D03*
X374097Y1331647D03*
X380025Y1381490D03*
X383127Y1395610D03*
X381060Y1433622D03*
X382489Y1428478D03*
X385667Y1433425D03*
X386827Y1429525D03*
X377830Y1534342D03*
X374900Y1534102D03*
X381120D03*
X377720Y1539862D03*
X374720D03*
X374800Y1546400D03*
X385100Y1539700D03*
X381800Y1539600D03*
X381000Y1546500D03*
X384000D03*
X378000Y1546400D03*
X387152Y1582659D03*
X387930Y1585155D03*
X384600Y1595100D03*
X382220Y1591870D03*
X374690Y1631700D03*
X374391Y1648476D03*
X385123Y1639732D03*
X378547D03*
X375550Y1662052D03*
X380170Y1660002D03*
X372640Y1662112D03*
X380077Y1654049D03*
X381068Y1674824D03*
X386824Y1682866D03*
X387760Y1671092D03*
X372009Y1682584D03*
X375430Y1676462D03*
X373320Y1688202D03*
X376610Y1688252D03*
X372895Y1737108D03*
X393830Y62062D03*
X399800Y59662D03*
X403800D03*
X396380Y62742D03*
X402100Y62632D03*
X399240Y62722D03*
X404910Y62562D03*
X388735Y117322D03*
X395980Y148272D03*
X390830Y155833D03*
X388965Y215067D03*
Y209949D03*
X388720Y218362D03*
X394720Y206362D03*
X402700Y234167D03*
X396294Y281585D03*
X398720Y318643D03*
Y321202D03*
X398661Y323761D03*
X403675Y363081D03*
X390876Y365640D03*
X391195Y368199D03*
X391101Y380939D03*
X403581Y375880D03*
X390843Y378439D03*
X403875Y365640D03*
X404120Y378439D03*
X390730Y394852D03*
X403570Y388874D03*
X404291Y391433D03*
X403700Y402422D03*
X390892Y406863D03*
X391149Y404304D03*
X403720Y405552D03*
X403260Y439352D03*
X391150Y445302D03*
X388720Y430862D03*
X403220Y436362D03*
X395520Y448362D03*
X396570Y472602D03*
X400080Y472652D03*
X402500Y495362D03*
X391360Y495712D03*
X402780Y499372D03*
X394860Y518812D03*
X394500Y522862D03*
X400589Y575236D03*
X403200Y572622D03*
X396139Y1286708D03*
X399139D03*
X395771Y1303480D03*
X393171D03*
X395771Y1300880D03*
X393171D03*
X395771Y1295680D03*
X393171D03*
X395771Y1298280D03*
X393171D03*
X400067Y1303319D03*
Y1300719D03*
Y1295519D03*
Y1298119D03*
X399935Y1317092D03*
Y1319592D03*
X400073Y1327653D03*
X403051Y1325373D03*
X400888Y1395508D03*
X400926Y1402207D03*
X391249Y1401048D03*
X392947Y1397827D03*
X390934Y1404085D03*
X401079Y1399208D03*
X400924Y1408227D03*
X400926Y1404707D03*
X400919Y1411231D03*
X392517Y1419015D03*
X400991Y1417264D03*
X390934Y1407605D03*
X390914Y1412991D03*
X391370Y1424782D03*
X403125Y1425008D03*
X390687Y1431713D03*
X390777Y1435152D03*
X394067Y1435323D03*
X401244Y1440773D03*
X396822Y1439340D03*
X396946Y1537632D03*
X396921Y1549810D03*
X396768Y1541810D03*
X404920Y1539362D03*
X396946Y1560810D03*
Y1556810D03*
X392108Y1582659D03*
X391330Y1585155D03*
X404030Y1595390D03*
Y1591990D03*
X401812Y1616456D03*
X394360Y1616380D03*
X388220Y1631404D03*
X394910Y1632364D03*
X392550Y1618650D03*
X397406Y1633142D03*
X402590Y1618952D03*
X394910Y1637320D03*
X401740Y1648082D03*
X404240D03*
X404320Y1645452D03*
X401820D03*
X391563Y1640244D03*
X397406Y1636542D03*
X397400Y1641000D03*
X402246Y1671745D03*
X390180Y1668212D03*
X396824Y1673662D03*
X409535Y49388D03*
X412930Y62572D03*
X407970Y59612D03*
X407790Y62652D03*
X415800Y62665D03*
Y67465D03*
X419901Y117491D03*
X413459Y129061D03*
X411434Y163662D03*
X407490Y216912D03*
X420865Y215067D03*
X410996Y218834D03*
X412820Y231922D03*
X420752Y239562D03*
X405478Y236726D03*
X410090Y241932D03*
X420710Y242482D03*
X405139Y239908D03*
X419920Y338162D03*
X419012Y368762D03*
X418704Y379201D03*
X416762Y367353D03*
X418602Y394722D03*
X419023Y381760D03*
X418540Y392163D03*
X418982Y407847D03*
X416514Y407028D03*
X417010Y439352D03*
X412720Y439362D03*
X417880Y461942D03*
X418520Y473562D03*
X415130Y480202D03*
X410532Y1153341D03*
X407948Y1153370D03*
Y1161570D03*
X410532Y1161541D03*
X407948Y1169597D03*
X410532D03*
X410225Y1329329D03*
X406225Y1328591D03*
X414435Y1330819D03*
X412963Y1328361D03*
X406225Y1331647D03*
X418320Y1383862D03*
X422320D03*
X414333Y1385292D03*
X410933Y1384648D03*
X412465Y1393878D03*
X419974Y1405289D03*
X414909Y1395658D03*
X408915Y1402606D03*
X411150Y1408163D03*
X419974Y1412789D03*
X420474Y1420289D03*
X410912Y1418177D03*
X408968Y1410427D03*
X411162Y1414126D03*
X407125Y1424978D03*
X416926Y1426471D03*
X412416Y1431645D03*
X419861Y1429718D03*
X419302Y1434700D03*
X422708Y1437560D03*
X410074Y1424993D03*
X416999Y1441908D03*
X413599D03*
X404475Y1552452D03*
X407625Y1552572D03*
X419820Y1555862D03*
X409140Y1566892D03*
X405000Y1566670D03*
X419002Y1600306D03*
X406526Y1591212D03*
Y1596168D03*
X412600Y1601000D03*
X406768Y1616456D03*
X408700Y1603500D03*
Y1614300D03*
X408600Y1607400D03*
X419780Y1602802D03*
X411910Y1629170D03*
Y1624214D03*
X414406Y1624992D03*
Y1628392D03*
X405990Y1618952D03*
X416020Y1620862D03*
X412456Y1649838D03*
X417960Y1650072D03*
X410700Y1658460D03*
Y1655310D03*
X410232Y1670244D03*
X409857Y1682767D03*
X421320Y1671699D03*
X410249Y1673082D03*
X429535Y49388D03*
X430655Y58677D03*
X427120Y59862D03*
X428500Y65016D03*
Y70016D03*
X429050Y117491D03*
X435340Y125346D03*
X430980Y132672D03*
X435340Y122196D03*
X428889Y121515D03*
X428883Y131015D03*
X429780Y149373D03*
Y153477D03*
Y157466D03*
Y161466D03*
X433695Y214862D03*
Y209862D03*
X429395Y232562D03*
X426295Y227862D03*
X422210Y221452D03*
X429395Y236562D03*
Y240562D03*
X426490Y244262D03*
X425720Y319492D03*
X425249Y338061D03*
X432380Y346522D03*
X422420Y338162D03*
X432006Y363644D03*
X431503Y376642D03*
X431781Y379201D03*
X434006Y365203D03*
X431596Y389604D03*
X433596Y391163D03*
X431920Y405288D03*
X431462Y402729D03*
X424980Y439462D03*
X428720Y439362D03*
X437720Y435362D03*
X431570Y435512D03*
X437520Y476337D03*
X431220Y496362D03*
X427790Y500862D03*
X427880Y506442D03*
X431220Y507143D03*
Y512623D03*
Y501643D03*
X428510Y515842D03*
X434343Y515233D03*
Y526233D03*
Y520733D03*
X431220Y518133D03*
Y523362D03*
X434620Y535762D03*
X434343Y542733D03*
X434320Y540153D03*
X434343Y547769D03*
Y552769D03*
X436822Y1161570D03*
Y1153370D03*
X431722D03*
Y1161570D03*
X434272Y1153370D03*
Y1161570D03*
X436822Y1170070D03*
X431722D03*
X434272D03*
X430999Y1286758D03*
X423229D03*
X426229D03*
X433999D03*
X432195Y1303319D03*
X425299Y1303480D03*
X427899D03*
X425299Y1295680D03*
X427899D03*
X432195Y1295519D03*
Y1298119D03*
X427899Y1298280D03*
X425299D03*
X432195Y1300719D03*
X427899Y1300880D03*
X425299D03*
X432063Y1317092D03*
Y1319592D03*
X432628Y1327845D03*
X435179Y1325373D03*
X426320Y1383862D03*
X430320D03*
X439030Y1383692D03*
X436780Y1387387D03*
X436467Y1391687D03*
X427474Y1405289D03*
X434974D03*
X438458Y1402169D03*
X434974Y1412789D03*
X427474Y1420289D03*
X434974D03*
X438645Y1426890D03*
X437299Y1436774D03*
X433539Y1430613D03*
X425030Y1434292D03*
X433897Y1434670D03*
X427546Y1443411D03*
X433954Y1439029D03*
X424146Y1443411D03*
X436920Y1541562D03*
X422566Y1550046D03*
X435396Y1551810D03*
X424820Y1552605D03*
X431620Y1541362D03*
X432996Y1558322D03*
X434430Y1567562D03*
X424570Y1579466D03*
X433350Y1579509D03*
X423958Y1600306D03*
X428099Y1586282D03*
X435240Y1609200D03*
X433383Y1602629D03*
X428941Y1606441D03*
X424800Y1616600D03*
X432200Y1607060D03*
X423180Y1602802D03*
X432500Y1613822D03*
X436840Y1632682D03*
X436880Y1622442D03*
X430015Y1626608D03*
X433670Y1639562D03*
X426728Y1636495D03*
X432895Y1737108D03*
X449535Y49388D03*
X451418Y78782D03*
X446640Y104552D03*
X450380Y104647D03*
X443678Y145710D03*
X446746Y152662D03*
X453028Y154864D03*
X452500Y213362D03*
Y222362D03*
X452071Y254862D03*
X442265Y290939D03*
X445964Y314234D03*
X439120Y314562D03*
X442220Y323362D03*
X448220Y323582D03*
Y319862D03*
X446000Y339362D03*
X450400Y338812D03*
X455000Y340362D03*
X445944Y359053D03*
X450500Y358862D03*
X446730Y382432D03*
X443770Y371042D03*
X451062Y397262D03*
X447490Y409052D03*
X443300Y410962D03*
X447750Y414112D03*
X453020Y414262D03*
X443744Y429553D03*
X451421D03*
X449420Y424162D03*
X443744Y452462D03*
X442520Y476337D03*
X437520Y484837D03*
X447520D03*
X442520D03*
X451520D03*
X453680Y515072D03*
X442853Y542519D03*
X451320Y533562D03*
X442853Y547519D03*
X442353Y1329329D03*
X438353Y1328591D03*
X446563Y1330819D03*
X445091Y1328361D03*
X438353Y1331647D03*
X443842Y1389106D03*
X448020Y1391862D03*
X443424Y1397869D03*
X439391Y1398266D03*
X441369Y1394260D03*
X451048Y1404914D03*
X447110Y1403812D03*
X448114Y1396812D03*
X445339Y1415731D03*
X446230Y1407722D03*
X445230Y1411719D03*
X445723Y1419730D03*
X443850Y1423404D03*
X451080Y1433740D03*
X440164Y1433982D03*
X445294Y1430415D03*
X443715Y1436052D03*
X446258Y1441606D03*
X449778D03*
X448079Y1562177D03*
X443910Y1555602D03*
X452520Y1564862D03*
X440019Y1576809D03*
X442128Y1574879D03*
X450020Y1570412D03*
X448328Y1582476D03*
X446020Y1570412D03*
X452020Y1580412D03*
X448740Y1574862D03*
X441308Y1602654D03*
X444458D03*
X437383Y1602629D03*
X454661Y1609235D03*
X442974Y1615615D03*
X448181Y1614401D03*
X443800Y1610712D03*
X447100Y1622562D03*
X447020Y1632632D03*
X451910Y1643282D03*
X437562Y1649770D03*
X442518D03*
X449940Y1647412D03*
X447090Y1647472D03*
X444940Y1641842D03*
X438340Y1652266D03*
X441740D03*
X452895Y1737108D03*
X469535Y49388D03*
X454568Y78782D03*
X462620Y120948D03*
X462320Y115948D03*
X466992Y145888D03*
X461900Y215244D03*
X466300Y217803D03*
X461900Y222921D03*
X466300Y225480D03*
X458264Y254862D03*
X465236Y293823D03*
X461736Y301098D03*
Y306098D03*
X467736Y312938D03*
X460300Y303662D03*
X463198Y311587D03*
X468490Y340572D03*
X465000Y340362D03*
X453621Y359053D03*
X469830Y366158D03*
X456660Y359172D03*
X460800Y358962D03*
X467211Y371902D03*
X459220Y393762D03*
X463500Y383562D03*
X462720Y404762D03*
X455720D03*
X458600Y414262D03*
X465421Y424928D03*
X466520Y475812D03*
X456520Y476337D03*
X461520D03*
X456520Y484837D03*
X461520D03*
X460323Y510183D03*
X455326Y520389D03*
X453727Y518036D03*
X457456Y522516D03*
X470880Y572692D03*
X467130Y600122D03*
X457196Y1161570D03*
X459696D03*
X462196D03*
X459696Y1153370D03*
X457196D03*
X462196D03*
X459696Y1170070D03*
X462196D03*
X457196D03*
X460049Y1286978D03*
X463049D03*
X469019Y1286718D03*
X458327Y1303980D03*
X460927D03*
X458327Y1301380D03*
X460927D03*
X464427Y1300180D03*
Y1302780D03*
X458327Y1296180D03*
X460927D03*
X464427D03*
X458327Y1298780D03*
X460927D03*
X464191Y1317092D03*
Y1319592D03*
Y1327793D03*
X467307Y1325373D03*
X465749Y1401238D03*
X459550Y1401348D03*
X465947Y1398355D03*
X459321Y1393009D03*
Y1396409D03*
X455576Y1409125D03*
Y1417125D03*
X455602Y1412334D03*
X455576Y1420625D03*
X468880Y1418400D03*
X455576Y1427632D03*
Y1424125D03*
X454450Y1433580D03*
X463140Y1451562D03*
X463207Y1547543D03*
X453595Y1551470D03*
X459520Y1546962D03*
X466905Y1567847D03*
X456961Y1559697D03*
X467400Y1556700D03*
X456020Y1580412D03*
X464020D03*
X462079Y1572177D03*
X460020Y1580412D03*
X457220Y1584020D03*
X466520Y1574862D03*
X454661Y1596755D03*
X464160Y1587122D03*
X457220Y1603562D03*
X460200Y1589900D03*
X459779Y1609235D03*
X456510Y1614472D03*
X469488Y1607362D03*
X458414Y1624994D03*
Y1629950D03*
X460910Y1629172D03*
Y1625772D03*
X455681Y1622492D03*
X458978Y1634481D03*
X463344Y1637622D03*
X469580Y1640272D03*
X468040Y1654807D03*
Y1651657D03*
X466460Y1672332D03*
X466180Y1678392D03*
X478240Y55935D03*
Y66575D03*
Y61129D03*
X481880Y147069D03*
X484396Y161364D03*
X476220Y158772D03*
X475500Y212685D03*
X486800Y259162D03*
X478500Y258862D03*
X472800Y299462D03*
X474736Y302098D03*
X484800Y307362D03*
X476740Y309272D03*
X479740Y300202D03*
X479736Y303598D03*
Y308598D03*
X486720Y360862D03*
X482720D03*
X475508Y359266D03*
X476585Y370727D03*
X482920Y398060D03*
X472720Y391362D03*
X485020Y414162D03*
X480393Y429412D03*
X471920Y416687D03*
X479379Y452445D03*
X474169Y476196D03*
X479169D03*
Y484696D03*
X474169D03*
X484169D03*
X474044Y503725D03*
X473870Y506622D03*
X474220Y572782D03*
X471940Y597532D03*
X478510Y602942D03*
X472960Y602152D03*
X482780Y607012D03*
X483030Y1153370D03*
Y1161570D03*
Y1170070D03*
X474509Y1286848D03*
X481509D03*
X477509D03*
X484509D03*
X474481Y1329329D03*
X470481Y1328591D03*
X478691Y1330819D03*
X477219Y1328361D03*
X470481Y1331647D03*
X483560Y1401712D03*
X475285Y1395402D03*
X474983Y1400385D03*
X485141Y1405430D03*
X485236Y1417844D03*
X481997Y1409955D03*
X470987Y1409965D03*
X484921Y1413246D03*
X470890Y1435838D03*
X482741Y1438698D03*
X478308Y1439986D03*
X482742Y1441312D03*
X478449Y1448158D03*
X482633Y1449091D03*
Y1446091D03*
X470111Y1548269D03*
X483348Y1548062D03*
X475110Y1548112D03*
X477968Y1548122D03*
X480848Y1548120D03*
X486210Y1547960D03*
X482400Y1558320D03*
X472220Y1626732D03*
X472210Y1618626D03*
X485150Y1624942D03*
X472210Y1622735D03*
X477905Y1663242D03*
Y1659242D03*
X475150Y1654302D03*
X477835Y1673462D03*
X477905Y1667242D03*
X477835Y1677462D03*
Y1685462D03*
X472895Y1737108D03*
X489535Y49347D03*
X488748Y72264D03*
X497002Y88167D03*
X499580Y78442D03*
X489730Y76132D03*
X498330Y96112D03*
X501540Y105152D03*
X498630Y140492D03*
X498700Y212685D03*
Y220362D03*
X503100Y215244D03*
Y222921D03*
X489980Y250512D03*
X496028Y258590D03*
X498636Y293123D03*
X489091Y293787D03*
X495136Y300398D03*
Y305398D03*
X501136Y312238D03*
X486861Y309398D03*
X492074Y300306D03*
X495036Y310398D03*
X486710Y313582D03*
X492150Y336810D03*
X498720Y360862D03*
X490720D03*
Y368862D03*
X497568Y397632D03*
X489520Y411862D03*
X494020Y414262D03*
X492970Y409252D03*
X502070Y424787D03*
X488070Y429412D03*
X493169Y476196D03*
X498169D03*
Y484696D03*
X493169D03*
X488169D03*
X494193Y550447D03*
X486500Y556212D03*
X491043Y550447D03*
X490759Y1291978D03*
X489555Y1303480D03*
X492155D03*
Y1300880D03*
X489555D03*
X495309Y1300058D03*
X498309D03*
X496319Y1330493D03*
Y1333043D03*
X499435Y1338799D03*
X496319Y1341264D03*
X499818Y1385027D03*
X499859Y1393027D03*
X490307Y1421499D03*
X491156Y1438713D03*
X499541Y1438698D03*
X491142Y1441312D03*
X499542D03*
X491089Y1446091D03*
Y1449091D03*
X499489D03*
Y1446091D03*
X487340Y1641352D03*
X489230Y1643592D03*
X492895Y1737108D03*
X517914Y42257D03*
X517902Y49194D03*
X510815D03*
X517902Y69508D03*
X510815D03*
X503100Y78402D03*
X510030Y78412D03*
X504980Y101752D03*
X516236Y92948D03*
X513586Y92799D03*
X510600Y92782D03*
X517290Y104252D03*
X513700Y117862D03*
X510900Y111962D03*
X503290Y140492D03*
X507360D03*
X515690Y147852D03*
X519010Y147912D03*
X518186Y139821D03*
X514850Y168443D03*
X519236Y202404D03*
X518670Y219192D03*
X512500Y209862D03*
X504075Y231262D03*
X512500Y223362D03*
X508500Y232862D03*
X508000Y237862D03*
X508502Y298813D03*
X505900Y311562D03*
X508500Y303362D03*
X508136Y309398D03*
X510740Y332592D03*
X507160Y332452D03*
X510720Y360862D03*
X514720D03*
X502720D03*
X506720Y368862D03*
X509720Y390362D03*
X513720D03*
X513173Y408740D03*
X505720Y398362D03*
X502260Y397742D03*
X511320Y437962D03*
X513444Y457522D03*
Y473281D03*
X503169Y475671D03*
X514425Y489112D03*
Y495112D03*
X509493Y539819D03*
X516970Y592942D03*
X513025Y615742D03*
X504135Y615612D03*
X517989Y1300108D03*
X514989D03*
X506609Y1342755D03*
X502609Y1342017D03*
X510819Y1344245D03*
X509347Y1341787D03*
X502609Y1345073D03*
X505055Y1387601D03*
Y1382301D03*
X505018Y1385027D03*
X502418D03*
X505055Y1396001D03*
Y1398601D03*
Y1390201D03*
X508881Y1404880D03*
X506181D03*
X505059Y1393027D03*
X502459D03*
X503559Y1405025D03*
X508775Y1409889D03*
X508828Y1407385D03*
X508802Y1412420D03*
X506075Y1409889D03*
X506128Y1407385D03*
X503572Y1407539D03*
Y1415039D03*
Y1412539D03*
X506102Y1412420D03*
X503572Y1410039D03*
X509246Y1420002D03*
X508001Y1438669D03*
X505777Y1425579D03*
X507942Y1441312D03*
X507964Y1448979D03*
Y1445979D03*
X512895Y1737108D03*
X518606Y23797D03*
X529720Y30792D03*
X525000Y42257D03*
X524988Y49194D03*
X529720Y43054D03*
X534720Y42922D03*
X532075Y69508D03*
Y57894D03*
X524988Y69508D03*
X533915Y59822D03*
X523978Y59074D03*
X529078Y59282D03*
X527520Y69633D03*
X528590Y72922D03*
X529239Y99997D03*
Y92911D03*
X528400Y104225D03*
X518450Y101602D03*
X527310Y98147D03*
Y94747D03*
X528400Y114275D03*
X527823Y131802D03*
X527160Y129243D03*
X527823Y149802D03*
X527278Y164726D03*
X523220Y170362D03*
X534765Y161067D03*
X526920Y161362D03*
X529480Y183921D03*
X529507Y202448D03*
X522337Y202404D03*
X536127Y247652D03*
X531298Y284280D03*
X532533Y299500D03*
X529533D03*
X536420Y309422D03*
X523660Y323222D03*
X526980Y322582D03*
X521820Y336762D03*
X531720Y360862D03*
X527720D03*
X535220Y383552D03*
X523670Y368892D03*
X525720Y390362D03*
X529720D03*
X528145Y408705D03*
X521720Y398362D03*
X526941Y447802D03*
X532650Y442376D03*
X518735Y452442D03*
X532650Y450330D03*
Y454270D03*
X533410Y475932D03*
X525820Y473662D03*
X531258Y505473D03*
X526852Y511331D03*
X527042Y505830D03*
X521561Y511469D03*
X524220Y505862D03*
Y500362D03*
Y511362D03*
X526853Y516817D03*
X521561Y516969D03*
Y522469D03*
X536000Y520362D03*
X524220Y516862D03*
X524720Y525293D03*
Y519743D03*
X521561Y527969D03*
Y539819D03*
X524920D03*
X524820Y545319D03*
X521561Y550819D03*
X523699Y571545D03*
X526280Y569122D03*
X528500Y566722D03*
X523890Y592387D03*
X520710Y592552D03*
X531472Y579750D03*
X534597Y1345539D03*
Y1342432D03*
X528447Y1353316D03*
Y1355816D03*
X528929Y1364212D03*
X531563Y1361597D03*
X532895Y1737108D03*
X548609Y32500D03*
X539720Y30792D03*
X534720D03*
X542050Y47452D03*
X539720Y42862D03*
X550971Y42902D03*
X544720Y42892D03*
X548609Y48082D03*
X546248Y69508D03*
X539161D03*
Y57894D03*
X537315Y59822D03*
X541002Y71436D03*
X544402D03*
X546234Y77443D03*
X548070Y79372D03*
X542620Y103352D03*
X542460Y99172D03*
X549610Y120682D03*
X537360Y120522D03*
X539475Y118772D03*
X550545Y147302D03*
X543083Y146338D03*
X540460Y200392D03*
X542798Y202646D03*
X544390Y236512D03*
X550390Y231742D03*
X548390Y236512D03*
X546390Y231742D03*
X542050Y231722D03*
X539830Y274912D03*
X537720Y278212D03*
X535630Y306602D03*
X547420Y306862D03*
X544920D03*
X549220Y339687D03*
X535720Y360862D03*
X546758Y360502D03*
X550024Y369123D03*
Y401023D03*
X547810Y414472D03*
X549670Y419892D03*
X543035Y441005D03*
X542870Y438320D03*
X548464Y456534D03*
X548780Y475932D03*
X538120Y463137D03*
X548550Y480382D03*
X546210Y519642D03*
X535290Y572932D03*
X541820Y575130D03*
X541722Y568054D03*
X543450Y590262D03*
X537730Y577440D03*
X547020Y590332D03*
X550320Y583362D03*
X536626Y590500D03*
X537560Y598102D03*
X544813Y1322668D03*
X542213D03*
X538293D03*
X535693D03*
X548197Y1342432D03*
X539997Y1348646D03*
X542397Y1345539D03*
X542597Y1348646D03*
X537197Y1342432D03*
X539797D03*
X542397D03*
X544997D03*
X537197Y1345539D03*
X539797D03*
X538737Y1365553D03*
X534737Y1364815D03*
X542947Y1367043D03*
X541475Y1364585D03*
X534737Y1367871D03*
X562780Y32842D03*
X563482Y40826D03*
X554720Y32862D03*
X565184Y47982D03*
X564430Y45132D03*
X558058Y46352D03*
X554983Y45312D03*
X553650Y48842D03*
X560421Y69508D03*
X553335D03*
X553320Y77443D03*
X551470Y79372D03*
X567865Y92656D03*
X559000Y102862D03*
X561000Y98862D03*
X564988Y118670D03*
X555545Y134340D03*
X566500Y125097D03*
X551231Y122671D03*
X565500Y145252D03*
X564890Y142173D03*
X555220Y167937D03*
X555545Y156462D03*
X553657Y193862D03*
X554872Y196635D03*
X559400Y201162D03*
X557248Y198909D03*
X564600Y202662D03*
X552489Y212022D03*
X553402Y231292D03*
X564944Y252173D03*
X552089Y257202D03*
X562461Y272161D03*
X561324Y301149D03*
X553536Y307527D03*
X555520Y309827D03*
X563790Y331846D03*
X561290D03*
X558790D03*
X557701Y369123D03*
X569080Y414002D03*
X559300Y422732D03*
X562200Y419412D03*
X559300Y414112D03*
X559730Y434772D03*
X558220Y459362D03*
X563281Y543113D03*
X563700Y538477D03*
X560640Y540613D03*
X566140Y554972D03*
Y551472D03*
X559927Y548457D03*
X556820Y570462D03*
X557430Y583572D03*
X558933Y1323658D03*
X563634Y1334315D03*
X561034D03*
X558933Y1326258D03*
X556563Y1337918D03*
X553963D03*
X558933Y1328938D03*
X556563Y1335318D03*
Y1332718D03*
X558933Y1331538D03*
X553963Y1335318D03*
Y1332718D03*
X555313Y1340418D03*
X551141Y1345555D03*
X551041Y1348651D03*
X551141Y1342448D03*
X555372Y1343037D03*
X561070Y1346174D03*
X565849Y1346968D03*
X566510Y1352217D03*
X555057Y1449395D03*
X552895Y1737108D03*
X572500Y32862D03*
X568500D03*
X578620Y45112D03*
X581500Y41862D03*
X573190Y42912D03*
X567507Y45869D03*
X575330Y47672D03*
X570208Y47982D03*
X579930Y72052D03*
X577300Y66682D03*
X577880Y75442D03*
X570150Y102862D03*
X579080Y119402D03*
X567673Y130542D03*
X573360Y140532D03*
X581175Y164717D03*
X569965Y161232D03*
X569470Y171702D03*
X581120Y155062D03*
X568245Y167112D03*
X579481Y202378D03*
Y194378D03*
Y210378D03*
X568149Y217916D03*
X580712Y215877D03*
X578450Y218562D03*
X581645Y233362D03*
X569668Y229812D03*
X578711Y230109D03*
X579245Y221362D03*
X567730Y225362D03*
X578390D03*
X567730Y221362D03*
X581755Y236978D03*
X578509Y265132D03*
X577676Y300268D03*
X569880Y300992D03*
X580400Y302402D03*
X577480Y303822D03*
X570440Y331930D03*
X567630Y331958D03*
X574800Y322462D03*
X571830Y348772D03*
X582436Y361032D03*
X572360Y351962D03*
X570200Y372229D03*
X571720Y381862D03*
X575050Y383602D03*
X577720Y381862D03*
X574491Y376549D03*
X580370Y383670D03*
X581090Y426970D03*
X571930Y421232D03*
X571110Y442656D03*
X569490Y437600D03*
X571110Y446706D03*
X570760Y451710D03*
X567320Y454962D03*
Y459962D03*
Y457462D03*
X577220Y449462D03*
X578920Y466462D03*
X583220Y493212D03*
X571990Y501046D03*
X584173Y498422D03*
X568520Y504162D03*
Y506662D03*
X577470Y505592D03*
X578925Y516846D03*
X571700Y552200D03*
X571627Y548124D03*
X569050Y578292D03*
X572057Y577242D03*
X573849Y1346968D03*
X569849D03*
X571555Y1352487D03*
X570645Y1361358D03*
X576220Y1423862D03*
X571620Y1424492D03*
X572895Y1737108D03*
X584950Y54842D03*
X596840Y45152D03*
X593925Y49193D03*
X586260Y52222D03*
X599800Y43152D03*
X597955Y48047D03*
X593369Y45682D03*
X586600Y60602D03*
X590680Y83591D03*
X592307Y94262D03*
X597287D03*
X594720Y97220D03*
X591395Y132142D03*
X598410Y124102D03*
X598390Y126802D03*
X595220Y140922D03*
X588000D03*
X592710Y156342D03*
X593248Y159480D03*
X598295Y171862D03*
X589690Y161732D03*
X596581Y184849D03*
X590337Y177604D03*
X596795Y179287D03*
X590281Y180698D03*
X599720Y184887D03*
X593220D03*
X598760Y203712D03*
X593966Y229965D03*
X584795Y233362D03*
X591310Y219582D03*
X592220Y249362D03*
X595415Y246515D03*
X592039Y252202D03*
X588577Y285862D03*
X590350Y294402D03*
X593763Y293999D03*
X588850Y291622D03*
X586820Y314662D03*
X599620Y314762D03*
X595520Y314862D03*
X583820Y314662D03*
X597820Y317062D03*
X592920Y326362D03*
X590820Y330962D03*
X590720Y327862D03*
Y324582D03*
X590470Y319192D03*
X593120Y342782D03*
X583685Y363271D03*
X586185D03*
X586070Y352302D03*
X591720Y430787D03*
X591839Y426112D03*
X595380Y416660D03*
X599220Y444362D03*
X595520Y439762D03*
X597220Y458688D03*
X599080Y448062D03*
X584100Y477952D03*
X592520Y467662D03*
X590210Y484132D03*
X593545Y488212D03*
X598661Y486922D03*
X587100Y493842D03*
X592400Y479162D03*
X591070Y504900D03*
X594090Y505107D03*
X587100Y496342D03*
X589260Y519421D03*
X594240Y511953D03*
X591425Y522337D03*
X591500Y516862D03*
X593675Y534702D03*
X596880Y534812D03*
X589989Y745475D03*
X592340Y744624D03*
X598693Y742072D03*
X607890Y34389D03*
X611810Y34400D03*
X615420Y42342D03*
X605060Y42402D03*
X615185Y49193D03*
X612822Y43232D03*
X606880Y44682D03*
X614400Y46012D03*
X603063Y48023D03*
X615185Y69508D03*
X603374D03*
X606020Y84562D03*
X615220Y76862D03*
X615170Y73812D03*
X601220Y73862D03*
Y76862D03*
X601050Y100008D03*
X603720Y98362D03*
X608620Y94162D03*
X617585Y97257D03*
X613020Y94162D03*
X617409D03*
X603880Y93902D03*
X600220Y96862D03*
X610104Y119342D03*
X614384D03*
X602306Y143077D03*
X612670Y142872D03*
X606040Y153432D03*
X606190Y144002D03*
X602580Y151052D03*
X603019Y146399D03*
X602430Y153862D03*
X612520Y154812D03*
X606260Y161652D03*
X615572Y173942D03*
X615573Y181984D03*
Y179484D03*
X615572Y176442D03*
X614531Y200378D03*
X611030Y188372D03*
X603340Y208142D03*
X614531Y209878D03*
X609456Y204994D03*
X611381Y209878D03*
X606719Y254966D03*
X611310Y266272D03*
X614200Y265792D03*
X605350Y293092D03*
X605870Y298172D03*
X605560Y303372D03*
X607590Y314732D03*
X609844Y330407D03*
X614130Y328762D03*
X605305Y331162D03*
X615180Y336812D03*
X608830Y374302D03*
X605898Y372984D03*
X605830Y402782D03*
X609690Y402812D03*
X604779Y423862D03*
X605220Y416362D03*
X610720Y436362D03*
X600800Y430900D03*
X614220Y436362D03*
X610720Y442862D03*
X614220D03*
X600351Y461862D03*
X614220Y452862D03*
X602910Y461862D03*
X610720Y457862D03*
X614220D03*
X610720Y452862D03*
X604360Y452120D03*
X614220Y467862D03*
Y472862D03*
Y477862D03*
X610820Y472862D03*
X605469Y467562D03*
X610720Y462862D03*
X614220D03*
X603779Y486922D03*
X601220D03*
X600645Y504362D03*
X606200Y510862D03*
Y514862D03*
X609520Y515162D03*
X611870Y512560D03*
X606220Y517762D03*
X614086Y537624D03*
X607328Y537481D03*
X610797Y537528D03*
X614000Y550800D03*
X607720Y550862D03*
X610720D03*
X613220Y654662D03*
X603317Y738415D03*
X603276Y741375D03*
X614660Y739553D03*
X600460Y744912D03*
X613047Y741492D03*
X602027Y761445D03*
X602768Y758385D03*
X612895Y1737108D03*
X616675Y31777D03*
X624633Y49193D03*
X629820Y42562D03*
Y45062D03*
X619562Y49193D03*
X624140Y46672D03*
X622271Y44782D03*
X629000Y67362D03*
X628590Y58622D03*
X622271Y57952D03*
X631546Y85024D03*
X623300Y95762D03*
X620540Y100112D03*
X632300Y104472D03*
X618460Y119342D03*
X626699Y119182D03*
X630951D03*
X624610Y142842D03*
X624520Y154622D03*
X631300Y167872D03*
X631290Y153702D03*
X615970Y161522D03*
X628195Y178414D03*
X628194Y170372D03*
X628195Y175914D03*
X628194Y172872D03*
X630818Y191248D03*
X625862D03*
X620030Y188782D03*
X628730Y216472D03*
X631730D03*
X627645Y236862D03*
X628730Y220472D03*
Y224472D03*
X631730Y220472D03*
Y224472D03*
X622730Y230362D03*
X629564Y256277D03*
X621740Y265952D03*
X618470Y265732D03*
X623150Y273172D03*
X633150Y301457D03*
X627950Y298897D03*
X625800Y311912D03*
X627600Y309134D03*
X632143Y306575D03*
X630220Y314362D03*
X628294Y317007D03*
X619474Y331162D03*
X623580Y336429D03*
X619100Y374638D03*
X621720Y373362D03*
X622490Y402162D03*
X628500Y402362D03*
X624220Y411362D03*
X629220D03*
X623220Y426362D03*
X625500Y421362D03*
X629220D03*
Y426362D03*
X629248Y436972D03*
X625620Y447862D03*
X625900Y431050D03*
X625620Y442862D03*
X629220D03*
X622220D03*
X617220Y436362D03*
X622220Y452862D03*
Y447862D03*
X626400Y462812D03*
X625620Y457862D03*
X622220D03*
X629220Y452862D03*
X625620D03*
X629220Y447862D03*
X626390Y467882D03*
X626210Y478002D03*
X626310Y472902D03*
X629220Y472862D03*
Y477862D03*
Y467862D03*
X622220Y462862D03*
X622520Y467862D03*
X629220Y487310D03*
Y482862D03*
X622860Y487310D03*
X626720Y482880D03*
X623670Y507862D03*
X629480Y508862D03*
X633000Y508700D03*
X629920Y516652D03*
X623000Y546900D03*
X629220Y643462D03*
X626720D03*
X617252Y739354D03*
X626207Y747585D03*
X623497Y748235D03*
X626017Y745083D03*
X620870Y762072D03*
X617940Y763552D03*
X630417Y757135D03*
X618114Y1258470D03*
X628970Y1670880D03*
X637220Y31462D03*
X646440Y43632D03*
X632463Y43302D03*
X643880Y42142D03*
X647447Y46322D03*
X641200Y46762D03*
X645150Y69508D03*
X645350Y60612D03*
X638500Y57362D03*
X635000D03*
X637000Y68142D03*
X634500Y73422D03*
X645330Y77132D03*
Y72972D03*
X640220Y85542D03*
X634690D03*
X647220Y96929D03*
X639901Y103462D03*
X632640Y107532D03*
X637500Y110362D03*
X640000Y108542D03*
X639970Y113892D03*
X640130Y166362D03*
X642480Y184862D03*
X643170Y171362D03*
X649870Y181942D03*
X645263Y235689D03*
X640295Y234237D03*
X645876Y296231D03*
X633138Y296766D03*
X643800Y298297D03*
X645528Y308623D03*
X645807Y304291D03*
X643800Y302247D03*
X645990Y314482D03*
X643800Y310962D03*
X633350Y314362D03*
X647200Y354300D03*
X647100Y357372D03*
X636075Y389862D03*
X649075Y389937D03*
X632620Y389862D03*
X645925Y389937D03*
X638700Y400962D03*
X647700Y399162D03*
X643500Y400962D03*
X643940Y411482D03*
X637220Y411362D03*
X644220Y426362D03*
X640720Y418862D03*
X644220Y421362D03*
X637220Y416362D03*
Y426362D03*
X637195Y421362D03*
X647420Y434162D03*
X640720Y431362D03*
X644220D03*
X638250Y439250D03*
X637220Y431362D03*
X643736Y457214D03*
X640820Y457902D03*
X637220Y452862D03*
X640720D03*
X640920Y447862D03*
X644220D03*
X637195Y457862D03*
X637220Y467862D03*
Y472862D03*
Y477862D03*
X644245Y472862D03*
X644220Y467862D03*
X641235Y477377D03*
X640798Y472934D03*
X637220Y462862D03*
X640820Y467862D03*
X644245Y482862D03*
X640620Y483422D03*
X649218Y504277D03*
X642580Y508172D03*
X645220Y504362D03*
X636960Y516002D03*
X637020Y522362D03*
X642630Y517870D03*
X640130D03*
X633147Y758595D03*
X641057Y1648659D03*
X647725Y1643719D03*
X643725Y1643467D03*
X645407Y1660425D03*
X648225Y1658482D03*
X642725Y1658562D03*
X635410Y1664220D03*
X637540Y1669480D03*
X636702Y1677610D03*
X641386Y1687283D03*
X645725Y1691182D03*
X640725Y1691452D03*
X650725Y1690682D03*
X639745Y1714362D03*
X646225Y1708169D03*
X642225Y1708457D03*
X648220Y1716912D03*
X636160Y1710662D03*
X648290Y1720052D03*
X639745Y1726362D03*
Y1722362D03*
Y1718362D03*
X648220Y1722921D03*
X632895Y1737108D03*
X651943Y33535D03*
X661534Y41748D03*
X661550Y45133D03*
X654464D03*
X661681Y49193D03*
X654595D03*
X663543Y43328D03*
X656950Y59012D03*
X651680Y73812D03*
X656500Y69662D03*
X661587D03*
X661600Y75562D03*
X657165Y79131D03*
X656426Y75431D03*
X652153Y98105D03*
X652680Y89712D03*
X651579Y102703D03*
X659000Y89262D03*
X652320Y123362D03*
X651980Y133822D03*
X662498Y124960D03*
X650790Y144982D03*
Y149871D03*
Y140699D03*
X662880Y149912D03*
Y146912D03*
X651730Y177212D03*
X662560Y214152D03*
X662780Y210362D03*
Y205362D03*
Y207862D03*
X659880Y210762D03*
Y205762D03*
Y208262D03*
X650705Y270947D03*
X662891Y357442D03*
X662680Y354362D03*
X651520Y378662D03*
X660690Y408162D03*
X660720Y404362D03*
X652000Y402362D03*
X653100Y407862D03*
X655820Y452662D03*
X655800Y461432D03*
X652195Y457862D03*
X655820Y467662D03*
X663000Y489500D03*
X663014Y493860D03*
X655220Y486862D03*
X661865Y505334D03*
X653800Y498740D03*
X663720Y523806D03*
X656877Y514716D03*
X661743Y521166D03*
X665990Y517131D03*
X661220Y526862D03*
X650794Y515039D03*
X657734Y528255D03*
X652577Y1000775D03*
X662282Y1386432D03*
X653690Y1392362D03*
X653761Y1396300D03*
X663187Y1395170D03*
Y1397720D03*
X666303Y1403476D03*
X663687Y1407279D03*
X654540Y1427605D03*
Y1424205D03*
X661100Y1451012D03*
X662660Y1548120D03*
X663410Y1553982D03*
X664590Y1631620D03*
X655307Y1647436D03*
X663097Y1642667D03*
X651725Y1643397D03*
X656725Y1657619D03*
Y1660769D03*
X663118Y1655557D03*
X663043Y1651557D03*
X663145Y1672862D03*
Y1668862D03*
X656973Y1698727D03*
X652712Y1686275D03*
X653420Y1698662D03*
X663645Y1722862D03*
X652895Y1737108D03*
X680200Y39062D03*
X677560Y40572D03*
X672250Y40812D03*
X675854Y49193D03*
X672005Y44119D03*
X669004Y41698D03*
X668800Y45262D03*
X668768Y49193D03*
X666943Y43328D03*
X682290Y46822D03*
X670612Y47264D03*
X674012D03*
X666406Y69508D03*
X675225Y58108D03*
X674035Y74522D03*
X678050Y58157D03*
X673750Y77692D03*
X673987Y87662D03*
X677820Y89462D03*
X680578Y75992D03*
X674540Y80652D03*
X670800Y85932D03*
X667940Y80142D03*
X671320Y91192D03*
X677790Y104880D03*
X673720Y110362D03*
X674145Y113487D03*
X677978Y119668D03*
Y115668D03*
X675560Y117120D03*
X668300Y132400D03*
X665650Y147692D03*
X673690Y200672D03*
X673300Y211332D03*
X667020Y225762D03*
X673713Y237725D03*
X674731Y359924D03*
X680600Y375462D03*
X683100Y369550D03*
X673220Y388362D03*
X677295Y404362D03*
X677195Y408262D03*
X670720Y399862D03*
X668695Y408362D03*
Y404262D03*
X665870Y433942D03*
X675220Y508862D03*
X680220Y495887D03*
X670220Y503837D03*
X675220D03*
X680220D03*
Y508862D03*
X675220Y521862D03*
Y516852D03*
X670720Y521862D03*
Y516862D03*
X680220Y530362D03*
X673340Y530922D03*
X671607Y742835D03*
X673617Y744735D03*
X669700Y746626D03*
X677887Y742121D03*
X669778Y759929D03*
X664987Y1348896D03*
X667487D03*
X664987Y1346396D03*
X667487D03*
X670037D03*
Y1348896D03*
X673517Y1360815D03*
X676017D03*
X668096Y1360822D03*
X678517Y1360815D03*
X677137Y1384311D03*
X674537D03*
X671937D03*
X669337D03*
X677137Y1387418D03*
X674537D03*
X671937D03*
X669337D03*
X664782Y1383832D03*
Y1381232D03*
Y1378632D03*
Y1386432D03*
X679737Y1384311D03*
X677337Y1390525D03*
X674737D03*
X676250Y1399757D03*
X673820D03*
X671350D03*
X676250Y1394157D03*
X673820D03*
X671350D03*
X679881Y1399280D03*
X666425Y1414200D03*
X676312Y1411554D03*
X673477Y1409386D03*
X669477Y1406694D03*
X677619Y1408887D03*
X675876Y1406619D03*
X669477Y1409415D03*
X667926Y1547018D03*
X682160Y1548040D03*
X665410Y1548180D03*
X679192Y1564252D03*
X679207Y1560482D03*
X678877Y1566798D03*
X678621Y1571072D03*
X678610Y1582154D03*
X666560Y1581000D03*
X678515Y1573910D03*
X678619Y1579070D03*
X666600Y1584900D03*
X678900Y1595400D03*
X678771Y1585945D03*
X666700Y1595500D03*
X678900Y1589800D03*
X666700Y1591900D03*
X678900Y1592600D03*
X666700Y1588500D03*
X679640Y1617520D03*
Y1614000D03*
X679270Y1604040D03*
X675710Y1620320D03*
X673420Y1650057D03*
X671290Y1646320D03*
X668695Y1662235D03*
X671610Y1673792D03*
X671620Y1668303D03*
X677940Y1670110D03*
X678490Y1695660D03*
X674195Y1712362D03*
X675120Y1716242D03*
X674195Y1728362D03*
X672270Y1721612D03*
X672895Y1737108D03*
X687120Y39632D03*
X692289Y40633D03*
X689940Y38952D03*
X696838Y45112D03*
X686854Y43701D03*
X692380Y43532D03*
X696800Y42108D03*
X696838Y47940D03*
X683440Y42832D03*
X687344Y46940D03*
X692389Y46439D03*
X694751Y70212D03*
X690027Y70142D03*
X685780Y70022D03*
X682941Y69982D03*
X699475D03*
X685968Y58157D03*
X694400D03*
X681980D03*
X690510Y59132D03*
X696700Y72462D03*
X692389Y72692D03*
X687664Y73202D03*
X687050Y79212D03*
X685230Y76952D03*
X683820Y79192D03*
X682890Y72642D03*
X696370Y78512D03*
X696727Y81552D03*
Y84052D03*
X695720Y102162D03*
X694220Y104862D03*
X684953Y104968D03*
X688019Y109845D03*
X687030Y113090D03*
X687034Y115896D03*
X694390Y133682D03*
X697615Y123697D03*
X684520Y152482D03*
X688520D03*
X692520D03*
X687238Y171071D03*
X686760Y222912D03*
X685600Y375462D03*
X690600D03*
X695600D03*
X683500Y381200D03*
X688220Y388362D03*
X685210Y388852D03*
X694920Y388797D03*
X687500Y399402D03*
X692330Y388751D03*
X685220Y391652D03*
X692402Y391250D03*
X697220Y404362D03*
X697120Y408262D03*
X685270Y408362D03*
Y404262D03*
X692400Y404682D03*
X694720Y491962D03*
X690720D03*
X685220Y495887D03*
X690580Y482992D03*
X694510Y482942D03*
X686120Y481862D03*
X695220Y495887D03*
X690220D03*
X695220Y508862D03*
X685220D03*
X690220Y506362D03*
X685220Y503837D03*
X690220Y508882D03*
X690330Y503530D03*
X695257Y503847D03*
X695220Y516852D03*
X690220D03*
X685220D03*
X690220Y519662D03*
X695220D03*
X689720Y530862D03*
X695220Y530662D03*
X684357Y742345D03*
X683457Y745175D03*
X692784Y1298845D03*
X696810Y1300162D03*
X692280Y1302532D03*
X689605Y1348896D03*
X687105D03*
X689605Y1346396D03*
X687105D03*
X684555D03*
Y1348896D03*
X686426Y1360822D03*
X695022Y1361990D03*
X696462Y1386122D03*
X682937Y1384311D03*
X685881Y1384327D03*
Y1387434D03*
X691351Y1380922D03*
X688751D03*
X691240Y1383522D03*
X693851D03*
Y1378322D03*
Y1380922D03*
X691351Y1378322D03*
X688751D03*
X693851Y1386122D03*
X696462Y1378322D03*
Y1383522D03*
Y1380922D03*
X696272Y1404560D03*
X685850Y1390557D03*
X684541Y1399280D03*
X682211Y1400030D03*
X686871D03*
X691777Y1405594D03*
Y1399794D03*
X689577Y1401194D03*
X687511Y1402924D03*
X691777Y1402694D03*
X689677Y1404194D03*
X687511Y1405824D03*
X694596Y1396198D03*
X694129Y1420283D03*
X696754Y1419809D03*
X691129Y1420283D03*
X685015Y1438475D03*
X696940Y1437955D03*
X694129Y1423303D03*
X691129D03*
X696694Y1427949D03*
Y1425449D03*
Y1430449D03*
X696784Y1422614D03*
X683930Y1552562D03*
Y1555062D03*
Y1557562D03*
X692100Y1567190D03*
X689875Y1577913D03*
X692026Y1580490D03*
X697197Y1640667D03*
X697122Y1636667D03*
X689200Y1648843D03*
X686220Y1640667D03*
X697595Y1666862D03*
X687045Y1673362D03*
X701838Y45112D03*
X706370Y46782D03*
X701838Y42202D03*
Y47940D03*
X703900Y72112D03*
X701400D03*
X700610Y57782D03*
X713000Y69662D03*
X697720Y58162D03*
X710200Y69662D03*
X706867Y58197D03*
X703100Y58157D03*
X700741Y83050D03*
X712500Y79862D03*
X710486Y77695D03*
X700500Y74862D03*
X698710Y86035D03*
X705390Y85792D03*
X703000Y84862D03*
X712433Y103308D03*
X706720Y100462D03*
X699220Y102162D03*
X702720D03*
X701220Y104862D03*
X697720D03*
X712290Y106722D03*
X706673Y122762D03*
X703520Y122540D03*
X704880Y133643D03*
X712340Y128093D03*
X700600Y125309D03*
X707008Y125804D03*
X705800Y167788D03*
X701926Y166535D03*
X705800Y171188D03*
X701926Y178346D03*
Y184252D03*
Y172441D03*
X704770Y182999D03*
Y179599D03*
X701926Y190157D03*
Y196063D03*
Y201968D03*
X704770Y194810D03*
Y191410D03*
X701926Y207874D03*
Y213779D03*
X704770Y218432D03*
Y206621D03*
Y215032D03*
Y203221D03*
X701926Y219685D03*
X709000Y354000D03*
X715600Y363900D03*
X705700Y361400D03*
X700600Y375462D03*
X705600D03*
X709400Y378200D03*
X713220Y378362D03*
X711200Y396500D03*
X707220Y399362D03*
X709160Y386730D03*
X713220Y388362D03*
X707400Y396200D03*
X705195Y408362D03*
Y404262D03*
X705780Y411022D03*
X712770Y406822D03*
X705720Y488862D03*
X703220Y490362D03*
X705720Y484862D03*
X705220Y508862D03*
X711220Y508882D03*
X710720Y521362D03*
X705220D03*
X701757Y521324D03*
X711220Y516852D03*
X705220D03*
Y530362D03*
X698600Y530700D03*
X710940Y591172D03*
X698602Y580536D03*
X705240Y594020D03*
X702740D03*
X712060Y638542D03*
X708680Y638812D03*
X708310Y646032D03*
X704320Y645262D03*
X701917Y742865D03*
X704000Y740862D03*
X700500Y745862D03*
X703545Y745907D03*
X703755Y1290545D03*
X711720Y1286162D03*
X707720Y1290162D03*
X705720Y1286662D03*
X708795Y1303701D03*
X704795Y1294559D03*
X707320Y1301162D03*
X703087Y1346396D03*
X705587D03*
X703087Y1348896D03*
X705587D03*
X708137D03*
Y1346396D03*
X698094Y1361947D03*
X706239Y1360822D03*
X712060Y1360815D03*
X699062Y1380922D03*
Y1383522D03*
Y1378322D03*
X707480Y1384311D03*
X710080D03*
X707480Y1387418D03*
X710080D03*
X701662Y1380922D03*
Y1383522D03*
Y1378322D03*
X699062Y1386122D03*
X701662D03*
X712680Y1384311D03*
Y1387418D03*
X709493Y1399757D03*
Y1394157D03*
X712880Y1390525D03*
X711963Y1399757D03*
Y1394157D03*
X701330Y1395195D03*
Y1397695D03*
X704446Y1403476D03*
X699262Y1413970D03*
X704568Y1414119D03*
X701830Y1407326D03*
X711620Y1409386D03*
X707620Y1406694D03*
Y1409660D03*
X699754Y1419809D03*
X706680Y1437535D03*
X701730Y1437855D03*
X711440Y1436905D03*
X699694Y1427949D03*
Y1425449D03*
Y1430449D03*
X699784Y1422614D03*
X712222Y1570703D03*
X702112Y1583683D03*
Y1571683D03*
Y1575683D03*
Y1579683D03*
X711102Y1575683D03*
X714162Y1574333D03*
X713052Y1579683D03*
X712582Y1584843D03*
X702112Y1587683D03*
Y1591683D03*
X713102Y1601307D03*
X715775Y1599024D03*
X714380Y1589960D03*
X702112Y1595683D03*
X712512Y1596338D03*
X711350Y1590720D03*
X711780Y1614590D03*
X704370Y1604580D03*
X706103Y1617107D03*
X708857Y1613462D03*
X709111Y1618842D03*
X710570Y1629890D03*
X708830Y1623115D03*
X705516Y1620296D03*
X710540Y1636070D03*
X708999Y1646762D03*
X703719Y1646768D03*
X697595Y1662862D03*
X700460Y1660918D03*
X709678Y1658485D03*
X697730Y1677460D03*
X704759Y1677001D03*
X724620Y40062D03*
X722580Y49182D03*
X728980Y39872D03*
X728720Y43562D03*
X719820Y45862D03*
X717320Y44062D03*
X729293Y58062D03*
X724644Y58362D03*
X719949Y58862D03*
X715990Y69662D03*
X725740Y69580D03*
X721990Y69762D03*
X718900Y69662D03*
X727700Y60562D03*
X728591Y71960D03*
X722415Y77862D03*
X718425Y77882D03*
X728090Y75132D03*
X719100Y85262D03*
X728028Y101968D03*
X728023Y98058D03*
X728028Y105468D03*
X729933Y108388D03*
X724133Y141288D03*
X715940Y157362D03*
X718213Y159241D03*
X720633Y160788D03*
X719194Y172909D03*
X714202D03*
X719194Y177865D03*
X714202D03*
X719194Y184909D03*
X714202D03*
X716698Y185687D03*
Y173687D03*
Y177087D03*
X719194Y189865D03*
X714202D03*
X719194Y196409D03*
X714202D03*
X719194Y201365D03*
X714202D03*
X716698Y197187D03*
Y200587D03*
Y189087D03*
X719194Y208243D03*
X714202D03*
X719194Y213199D03*
X714202D03*
X716698Y209021D03*
Y212421D03*
X717020Y220862D03*
X719720Y220142D03*
X727720Y356362D03*
X722500Y365500D03*
X724897Y353887D03*
X721989Y351234D03*
X727000Y365500D03*
X731400D03*
X725220Y380787D03*
X715600Y375462D03*
X722500Y374100D03*
X727000D03*
X731400Y375000D03*
X718220Y388362D03*
X718720Y381892D03*
X728220Y388362D03*
X715220Y404362D03*
X715120Y408262D03*
X723195Y408362D03*
Y404262D03*
X725220Y399862D03*
X713820Y488762D03*
Y484662D03*
X723220Y508882D03*
X717220D03*
X729220D03*
X723120Y525362D03*
X728220Y521362D03*
X717220D03*
X722720D03*
X717296Y525407D03*
X723220Y516852D03*
X729220D03*
X717220D03*
X729212Y531700D03*
X729200Y588952D03*
X729328Y583076D03*
X729295Y586113D03*
X725207Y579371D03*
X722707D03*
X715860Y585540D03*
X714320Y597462D03*
X723450Y597072D03*
X720240Y598292D03*
X715420Y639162D03*
X719190Y646642D03*
X717720Y643262D03*
X715220D03*
X723340Y642922D03*
X714087Y745865D03*
X720697Y765862D03*
X723460Y1245632D03*
X713836Y1283689D03*
X714720Y1286162D03*
X725604Y1346396D03*
X728104D03*
X725604Y1348896D03*
X728104D03*
X723054D03*
Y1346396D03*
X724969Y1360822D03*
X714560Y1360815D03*
X717060D03*
X729443Y1361224D03*
X726694Y1381583D03*
Y1378983D03*
X715280Y1384311D03*
X717880D03*
X715280Y1387418D03*
X721080Y1384311D03*
X724024Y1384327D03*
Y1387434D03*
X728044Y1384083D03*
X729294Y1381583D03*
Y1378983D03*
X715480Y1390525D03*
X723993Y1390557D03*
X714393Y1399757D03*
Y1394157D03*
X725654Y1405824D03*
Y1402924D03*
X727720Y1401194D03*
X727820Y1404194D03*
X718024Y1399280D03*
X722684D03*
X720354Y1400030D03*
X725014D03*
X714455Y1411554D03*
X715762Y1408887D03*
X714019Y1406619D03*
X717300Y1547370D03*
X715792Y1567461D03*
X720370Y1566910D03*
X723520Y1561604D03*
X724712Y1566820D03*
X716612Y1584635D03*
X717152Y1570093D03*
X728977Y1574453D03*
X717402Y1574433D03*
X724465Y1580092D03*
X722465Y1582092D03*
X726465D03*
X723942Y1574123D03*
X718230Y1600372D03*
X724465Y1590950D03*
X722465Y1588950D03*
X726465D03*
X729052Y1602518D03*
X726092Y1598483D03*
X720987Y1599568D03*
X725378Y1614503D03*
X719770Y1614590D03*
X715780D03*
X723542Y1612702D03*
X721488Y1610945D03*
X725910Y1611900D03*
X716688Y1610055D03*
X719168Y1612016D03*
X722040Y1623970D03*
X713791Y1629816D03*
X718195Y1647300D03*
X714203Y1642926D03*
X729150Y1641690D03*
X726810Y1652430D03*
X714071Y1663842D03*
X722630Y1655740D03*
X724500Y1680400D03*
X718758Y1673800D03*
X745900Y40362D03*
X733314Y40862D03*
X740100Y41162D03*
X744987Y49062D03*
X742840Y39832D03*
X736790D03*
X746100Y46262D03*
X736620Y45262D03*
X745130Y69508D03*
X738043D03*
X730957D03*
X731330Y60712D03*
X745474Y57932D03*
X733642Y58062D03*
X741377Y57932D03*
X737595D03*
X732793Y71436D03*
X736193D03*
X742620Y71762D03*
X735880Y60662D03*
X730820Y84062D03*
X740819Y82362D03*
X737623Y98858D03*
X734523Y98758D03*
X736720Y101662D03*
X745035Y94632D03*
X735770Y94988D03*
X739823Y91052D03*
X735733Y111988D03*
X741308Y108742D03*
X738600Y136600D03*
X736060Y145532D03*
X740220Y145362D03*
X732720Y231362D03*
X734220Y238362D03*
X745685Y265322D03*
Y269322D03*
X744247Y312598D03*
X741800Y363200D03*
X742090Y356082D03*
X735600Y351400D03*
X735800Y365500D03*
X732700Y351500D03*
X740200Y375100D03*
X736220Y380787D03*
X742720Y380262D03*
X735800Y375000D03*
X733220Y388362D03*
X738220D03*
X742160Y396452D03*
X738220Y383862D03*
X743720Y404362D03*
X743820Y408262D03*
X735220Y410842D03*
X735745Y408362D03*
Y404262D03*
X733720Y399862D03*
X743980Y443482D03*
X740740Y473822D03*
X741420Y494162D03*
X747600Y506592D03*
X735220Y508862D03*
X745220Y503842D03*
X730070Y506212D03*
X744630Y506529D03*
X735220Y503842D03*
X735430Y516862D03*
X745220Y522362D03*
Y516852D03*
X730220Y523362D03*
X740840Y521982D03*
X735173Y521362D03*
X745220Y530362D03*
X736480Y531722D03*
X738980D03*
X733922Y531712D03*
X733117Y580071D03*
Y582571D03*
X733134Y585672D03*
X736710Y603842D03*
Y607242D03*
X739206Y608020D03*
Y603064D03*
X735620Y613862D03*
X730690Y655532D03*
X744538Y746524D03*
X737609Y744282D03*
X730889Y746834D03*
X740820Y741762D03*
X737784Y1360017D03*
X730752Y1384080D03*
X731794Y1381583D03*
Y1378983D03*
X732238Y1388343D03*
X738810Y1396665D03*
X741540Y1396585D03*
X739170Y1405655D03*
X741670Y1405675D03*
X729920Y1405594D03*
X732226Y1396212D03*
X729920Y1399794D03*
Y1402694D03*
X738170Y1414185D03*
X740760Y1414165D03*
X735300Y1648760D03*
X737080Y1655820D03*
X735080Y1662980D03*
X740840Y1655590D03*
X732705Y1669450D03*
X732895Y1737108D03*
X758606Y23797D03*
X747487Y49062D03*
X754620Y51602D03*
X758620D03*
X752720Y59002D03*
X749477Y57932D03*
X755700Y59942D03*
Y62442D03*
X758200Y59942D03*
Y62442D03*
X760700Y59942D03*
Y62442D03*
X747487Y71429D03*
X754219Y75707D03*
X757693Y100653D03*
Y96423D03*
X750700Y106642D03*
X754800Y97082D03*
X750033Y92888D03*
Y89988D03*
X757340Y92562D03*
X754633Y108288D03*
Y105288D03*
X760390Y111810D03*
X762198Y129684D03*
Y126684D03*
X762172Y123898D03*
X751220Y137864D03*
X758110Y172636D03*
X747200Y251500D03*
X761720Y283262D03*
X748085Y278942D03*
X758360Y276122D03*
X754290Y286632D03*
X755200Y296062D03*
X758412Y298790D03*
X755305Y298847D03*
X748820Y284562D03*
X758390Y295450D03*
X748498Y309640D03*
X757936Y303908D03*
X747554Y384962D03*
X757430Y408212D03*
X760469Y442647D03*
X759940Y438232D03*
X750290Y462162D03*
X758420Y447662D03*
X757365Y459862D03*
X752500Y495762D03*
X757238Y483862D03*
X756642Y496522D03*
Y501744D03*
X751220Y522362D03*
Y516852D03*
X759790Y525522D03*
X755940Y516862D03*
X756650Y526072D03*
X761710Y517651D03*
X751220Y530362D03*
X757020Y530462D03*
X759820D03*
X754220D03*
X757720Y1375462D03*
Y1384062D03*
X757779Y1390645D03*
X758020Y1397862D03*
X758420Y1406862D03*
X757542Y1420684D03*
X758120Y1414762D03*
X755420Y1426262D03*
Y1422862D03*
X760112Y1579183D03*
X749612Y1579023D03*
X749652Y1586407D03*
X760152Y1583183D03*
X749612Y1583023D03*
X760112Y1592183D03*
Y1587183D03*
X749662Y1590733D03*
X749612Y1594683D03*
X758360Y1589661D03*
X761716Y1661194D03*
X751620Y1674312D03*
X759859Y1686090D03*
X759359Y1729520D03*
X752875Y1726670D03*
X752895Y1737108D03*
X765606Y44894D03*
X774059Y68912D03*
X769474Y75360D03*
X765858Y87340D03*
X762368Y84088D03*
X769284Y103895D03*
X767061Y99959D03*
X767045Y95960D03*
X767028Y91490D03*
X776730Y117479D03*
X773943Y114633D03*
X771131Y111788D03*
X769775Y107977D03*
X766769Y140138D03*
X773420Y143462D03*
X771774Y167518D03*
X772328Y153728D03*
X771426Y158026D03*
X764850Y249792D03*
X766320Y264892D03*
X763320D03*
X771630Y258102D03*
X777420Y277962D03*
X773220Y296262D03*
X769789Y296231D03*
X777467Y296315D03*
X769860Y302462D03*
X772866Y311558D03*
X771377Y314139D03*
X777283Y320892D03*
X771490Y354942D03*
X768490D03*
X777420Y354962D03*
X774490Y354942D03*
X765000Y354862D03*
X771960Y375162D03*
X767960Y369662D03*
X776100Y375100D03*
X776000Y369662D03*
X764000D03*
X766195Y393212D03*
X773245Y398212D03*
X766195Y403212D03*
X773245D03*
Y408212D03*
X768910Y403260D03*
X771050Y416940D03*
X766195Y418212D03*
X768701Y418662D03*
X774982Y446908D03*
X772365Y454862D03*
X768720Y459862D03*
X765315Y454862D03*
Y459862D03*
X772365D03*
X765360Y475412D03*
X765315Y464862D03*
X772364Y475062D03*
X772365Y469862D03*
X765315Y479862D03*
Y488862D03*
X776170Y493422D03*
X766510Y493452D03*
X765386Y483572D03*
X773530Y507062D03*
X765810Y506342D03*
X769745Y502600D03*
X775378Y502502D03*
X765521Y525364D03*
X769220Y530362D03*
X765720D03*
X772220D03*
X777020D03*
X772020Y746562D03*
X774384Y744088D03*
X762562Y746444D03*
X769921Y742095D03*
X767421D03*
X764921D03*
X769337Y760775D03*
X762617Y758885D03*
X768520Y1379962D03*
Y1384062D03*
Y1375462D03*
X768620Y1392762D03*
Y1397262D03*
X775375Y1403561D03*
X767820Y1410262D03*
Y1414762D03*
X763152Y1581893D03*
Y1577893D03*
Y1573793D03*
X773952Y1580493D03*
X768714Y1571203D03*
X769452Y1584393D03*
X770252Y1587268D03*
X763152Y1590893D03*
Y1594893D03*
X774052Y1590293D03*
X776922Y1590444D03*
X764920Y1695347D03*
X766880Y1689020D03*
X766603Y1721797D03*
X772208Y1731911D03*
X785095Y49388D03*
X785180Y120947D03*
X792680D03*
X790180D03*
X787680D03*
X783940Y118637D03*
X786440D03*
X788940D03*
X781440D03*
X782553Y150031D03*
Y152531D03*
X779893Y147521D03*
Y150021D03*
X785135Y281822D03*
Y267822D03*
X780820Y278262D03*
X785135Y274822D03*
X785200Y271400D03*
X780617Y296345D03*
X794057Y301569D03*
X794220Y296062D03*
X785220Y284762D03*
X792943Y312642D03*
X784415Y313734D03*
X779120Y306162D03*
X793896Y309026D03*
X793820Y304962D03*
X779120Y303410D03*
Y308755D03*
X794600Y360600D03*
X785000Y355000D03*
X779920Y354962D03*
X782420D03*
X790120Y354862D03*
X792620D03*
X787600Y354900D03*
X787925Y387900D03*
X795520Y393462D03*
X791075Y388000D03*
X781320Y398212D03*
X787720Y408362D03*
X781195Y413212D03*
Y423212D03*
X785560Y417902D03*
X781195Y418212D03*
X791590Y417050D03*
X791040Y422892D03*
X793660Y422842D03*
X785720Y427862D03*
X789230Y414942D03*
X780020Y438287D03*
X781410Y431822D03*
X784730Y432682D03*
X787320Y444862D03*
Y439862D03*
X791582Y435352D03*
X780315Y459862D03*
X787320Y454862D03*
Y449862D03*
Y459862D03*
X787360Y469862D03*
X780340Y468982D03*
Y474862D03*
X786220Y464862D03*
X780315D03*
X783340Y474802D03*
X782690Y488862D03*
X793220Y493362D03*
X781170Y493422D03*
X785800Y482762D03*
X793875Y483262D03*
X778670Y493422D03*
X783600Y502462D03*
X793673Y512862D03*
X783400Y511902D03*
X789720Y589862D03*
X785220Y581362D03*
X789720Y587362D03*
X792720Y589862D03*
X789720Y581862D03*
X791720Y593862D03*
X793720Y595862D03*
X783100Y593582D03*
X791969Y618384D03*
X794720Y617862D03*
X783507Y761875D03*
X794157Y761295D03*
X782515Y766702D03*
X791140Y761693D03*
X788225Y1388683D03*
X791260Y1388662D03*
X790380Y1432132D03*
X792208Y1731911D03*
X805095Y49388D03*
X797443Y271469D03*
X806300Y279662D03*
X809700Y273562D03*
X810920Y280062D03*
X798204Y279146D03*
X795190Y298572D03*
X797924Y298358D03*
X798620Y312773D03*
X803620Y302962D03*
X805870Y304812D03*
X799720Y300462D03*
X795920Y312662D03*
X803280Y354982D03*
X800646Y354921D03*
X809800Y360600D03*
X802200D03*
X806588Y351097D03*
X795220Y354862D03*
X806000Y360600D03*
X805910Y355012D03*
X797900Y354800D03*
X799800Y368700D03*
X810781Y372615D03*
X802220Y393727D03*
X803150Y408512D03*
X795600Y402500D03*
X795520Y398212D03*
X800352Y408389D03*
X803120Y428762D03*
X797720Y428412D03*
X798370Y439932D03*
X799458Y431217D03*
X802790Y433832D03*
X795320Y439862D03*
X805720Y432902D03*
X801750Y444330D03*
X795320Y444862D03*
X810860Y454862D03*
X802810D03*
X795320D03*
Y449862D03*
X802810Y464862D03*
Y449862D03*
X810860Y459862D03*
X802810D03*
X795320D03*
X810860Y449862D03*
X795370Y474862D03*
X798990D03*
X802865D03*
X795320Y464862D03*
X810815Y474862D03*
X810860Y464862D03*
X810815Y469862D03*
X807220Y493362D03*
X801940Y485932D03*
X804510Y486122D03*
X809510D03*
X799230Y485922D03*
X812510Y486422D03*
X801567Y512942D03*
X802790Y495652D03*
X805470Y510522D03*
X807640Y506672D03*
X808100Y509900D03*
X797420Y512503D03*
X805445Y587582D03*
X798720Y585362D03*
X810720Y586862D03*
X811143Y605265D03*
X798220Y597362D03*
X808860Y603802D03*
X807945Y594362D03*
X803220D03*
X797200Y599883D03*
X797720Y617862D03*
X795720Y614862D03*
X796702Y761195D03*
X810850Y770272D03*
X799577Y760985D03*
X807000Y757562D03*
X806323Y1343076D03*
X812130Y1343022D03*
X809210Y1343062D03*
X804100Y1435010D03*
X800000Y1431100D03*
X804652Y1581793D03*
Y1573793D03*
X812652Y1577793D03*
X801652Y1584539D03*
X812698Y1587047D03*
X804652Y1597793D03*
Y1585993D03*
X799152Y1586507D03*
X804652Y1589793D03*
Y1609793D03*
X825095Y49388D03*
X819114Y115223D03*
X827114D03*
X823114D03*
X821118Y134632D03*
X825698Y139062D03*
X824498Y145198D03*
X814570Y145952D03*
X814531Y139851D03*
X820900Y147112D03*
X813900Y269698D03*
X815060Y280072D03*
X813490Y273862D03*
X816220Y277162D03*
X827403Y286625D03*
X816420Y287062D03*
X813293D03*
X826300Y311962D03*
X823800D03*
X813855Y354008D03*
X820936Y356956D03*
X821164Y372312D03*
X813210Y374292D03*
X815710D03*
X825003Y389012D03*
X819220Y397664D03*
X824980Y405260D03*
Y409260D03*
X819220Y412264D03*
X823600Y421194D03*
X821720Y428437D03*
X815310Y440100D03*
X818500Y451700D03*
X816810Y464862D03*
X816500Y476800D03*
X824860Y464862D03*
X816400Y472900D03*
X820720Y493862D03*
X821720Y511082D03*
X814305Y499503D03*
X819320Y502347D03*
X821720Y527082D03*
Y519082D03*
Y523082D03*
X815040Y590772D03*
X820220Y586862D03*
X814220Y582530D03*
X823720Y594862D03*
X820470Y595112D03*
X815120Y593582D03*
X820613Y744641D03*
X823589Y746924D03*
X822374Y757039D03*
X814770Y763874D03*
X815789Y1008845D03*
X814234Y1340465D03*
X826090Y1334362D03*
Y1339362D03*
Y1329362D03*
Y1344362D03*
X820920Y1344342D03*
X818420D03*
X815652Y1582570D03*
Y1573793D03*
X813352Y1590893D03*
X812652Y1593793D03*
X815551D03*
X818652Y1590444D03*
X812652Y1605793D03*
Y1601793D03*
X812208Y1731911D03*
X836779Y68008D03*
X836126Y62681D03*
X828600Y61752D03*
X839898Y87248D03*
X837791Y85186D03*
X841584Y94181D03*
X837250Y93221D03*
X831297Y104206D03*
X842864Y110296D03*
X831114Y115223D03*
X839360Y114862D03*
X835114Y115223D03*
X845220Y135862D03*
Y129362D03*
X829114Y150273D03*
Y147123D03*
X836502Y161553D03*
X828145Y160362D03*
X838220Y163862D03*
X835220D03*
X837320Y175112D03*
X842720Y181360D03*
X837975Y210064D03*
X837160Y218212D03*
Y213207D03*
X844526Y204968D03*
X838820Y206872D03*
X830339Y228143D03*
X837500Y229642D03*
X829680Y264580D03*
X836210Y272452D03*
X829720Y277562D03*
X829800Y271562D03*
X840063Y285022D03*
X839450Y272662D03*
X835400Y268800D03*
X829620Y280345D03*
X829820Y275045D03*
X840850Y278948D03*
X829320Y296762D03*
X834400Y283862D03*
X834900Y293462D03*
X829720Y292762D03*
X839860Y294702D03*
X827620Y302962D03*
X830417Y311865D03*
X828222Y359960D03*
X835471Y363003D03*
X843133Y366158D03*
X833300Y386500D03*
X838784Y392880D03*
X836300Y418800D03*
X840400Y418900D03*
X839200Y434300D03*
X841300Y446800D03*
X831720Y457700D03*
X839640Y449612D03*
X832700Y446800D03*
X838220Y459562D03*
X841200Y456500D03*
X842600Y477200D03*
X842341Y474241D03*
X832720Y494862D03*
X829720D03*
X841795Y492862D03*
X830870Y480010D03*
X832590Y512888D03*
X829745Y498082D03*
Y502082D03*
X832370Y525849D03*
X843287Y527817D03*
X834635Y515447D03*
X830480Y527817D03*
X841461Y525849D03*
X840990Y529786D03*
X828009Y587913D03*
X831705Y593877D03*
X829230Y582772D03*
X831700Y596962D03*
X831530Y651932D03*
X830587Y741205D03*
X833120Y743392D03*
X838587Y766825D03*
X841827Y766795D03*
X837127Y758976D03*
X829420Y758422D03*
X841997Y773085D03*
X838020Y1232432D03*
X832090Y1326862D03*
X828799Y1336870D03*
X828910Y1331756D03*
X832090Y1331862D03*
Y1336862D03*
X828910Y1341725D03*
X832090Y1341862D03*
X843652Y1584539D03*
X841152Y1586507D03*
X832208Y1731911D03*
X845095Y49388D03*
X858629Y60293D03*
X850015Y87341D03*
X843855Y87711D03*
X847472Y94754D03*
X854577Y99651D03*
X854107Y91232D03*
X850280Y113852D03*
X847660Y113962D03*
X853100Y113762D03*
X856776Y129268D03*
X846846Y127064D03*
X854100Y132972D03*
X854220Y135862D03*
Y129362D03*
X854200Y138562D03*
X851895Y160262D03*
X848745Y160187D03*
X848709Y156752D03*
X848360Y182872D03*
X845720Y181362D03*
X849710Y212062D03*
X845220Y216532D03*
X855858Y212425D03*
X855933Y215375D03*
X860050Y215310D03*
X854706Y229878D03*
X852206D03*
X847580Y232222D03*
X853828Y265057D03*
X854333Y276117D03*
X854338Y280027D03*
Y283527D03*
X853828Y269043D03*
X850133Y271049D03*
X861865Y273730D03*
X852800Y288562D03*
X853200Y297462D03*
X850093Y286625D03*
X855480Y299692D03*
X856243Y286447D03*
X856700Y304862D03*
X859920Y308852D03*
X848000Y374622D03*
X851396Y369614D03*
X859734Y373032D03*
X859740Y399081D03*
X846040Y399210D03*
X856842Y410760D03*
X846490Y422131D03*
X857560Y417762D03*
X844200Y418800D03*
X850610Y444352D03*
X847830Y443892D03*
X843810Y453322D03*
X851606Y447927D03*
X844210Y455902D03*
X846700Y473000D03*
X855200Y476900D03*
X857620Y492862D03*
X848710Y505641D03*
X858600Y511130D03*
X848620Y509752D03*
X853070Y515447D03*
X860345Y522162D03*
X857195D03*
X859888Y593970D03*
X859054Y583752D03*
X845523Y582126D03*
X856698Y594011D03*
X856520Y751262D03*
X853200Y751062D03*
X859450Y750462D03*
X854687Y761685D03*
X844957Y763065D03*
X854620Y1242125D03*
X854237Y1250358D03*
X846652Y1581793D03*
Y1573793D03*
X854652Y1577793D03*
X857652Y1582570D03*
Y1573793D03*
X854777Y1586968D03*
X846652Y1597793D03*
X855352Y1590893D03*
X854652Y1593793D03*
X846652Y1585993D03*
X857551Y1593793D03*
X846652Y1589793D03*
X854652Y1605793D03*
Y1601793D03*
X846652Y1609793D03*
X852208Y1731911D03*
X865095Y49388D03*
X862930Y70072D03*
X866330D03*
X876124Y66072D03*
X868187Y72006D03*
X860937Y71877D03*
X861350Y61672D03*
X876124Y86072D03*
Y106072D03*
Y126072D03*
X862452Y151590D03*
X874295Y163862D03*
X867620Y154362D03*
X871145Y163862D03*
X863488Y176332D03*
X871580Y183370D03*
X875169Y185113D03*
X871980Y199500D03*
X864859Y187110D03*
X873200Y194262D03*
X871890Y196740D03*
X877971Y196652D03*
X867528Y231788D03*
X875543Y266447D03*
X867700Y268262D03*
X860833Y276817D03*
X863933Y276917D03*
X875543Y269347D03*
X863747Y280870D03*
X867237Y273325D03*
X868552Y285537D03*
X862043Y290047D03*
X874243Y287047D03*
X877322Y296051D03*
X867922Y376450D03*
X875922Y379793D03*
X870700Y382415D03*
Y390620D03*
Y394620D03*
Y386476D03*
Y398620D03*
X868113Y409372D03*
X871320Y416752D03*
X870513Y414276D03*
X863415Y445829D03*
X860574Y445404D03*
X861080Y459742D03*
X870360Y493042D03*
X862620Y503162D03*
Y499062D03*
Y507162D03*
X868110Y499142D03*
X865290Y499032D03*
X865810Y521862D03*
X860345Y513062D03*
X866820Y736562D03*
X863925Y737697D03*
X864680Y751582D03*
X874155Y756993D03*
X864700Y778300D03*
X860652Y1590444D03*
X872208Y1731911D03*
X892214Y141891D03*
X886280Y174085D03*
X878327Y183169D03*
X876695Y171362D03*
Y176862D03*
X887520Y171362D03*
Y176862D03*
X878220Y192055D03*
X877724Y200837D03*
X878220Y187449D03*
X888929Y209223D03*
X891620Y209662D03*
X888929Y206723D03*
X891620Y207162D03*
X880943Y283347D03*
X884003Y278712D03*
X883870Y275802D03*
X883909Y281862D03*
X879587Y270004D03*
X883870Y272652D03*
X880943Y286347D03*
X880473Y329370D03*
X882520Y327562D03*
X885020D03*
X887520D03*
X890422Y333879D03*
X893440Y336232D03*
X887869Y386618D03*
X883472Y382910D03*
X890820Y389362D03*
X890920Y386352D03*
X889453Y458926D03*
X887590Y471552D03*
X889439Y489599D03*
Y492999D03*
X887671Y487831D03*
Y494767D03*
X878931Y509051D03*
X878941Y503813D03*
X881680Y504742D03*
Y508142D03*
X884512Y523800D03*
X882410Y526132D03*
X888130Y532612D03*
X891530D03*
X886362Y534380D03*
X887810Y582442D03*
X886500Y739162D03*
X889000Y737562D03*
X885310Y736442D03*
X886720Y741902D03*
X878152Y876760D03*
X878192Y879910D03*
X884747Y871745D03*
X879100Y912608D03*
X884619Y916477D03*
X892317Y915872D03*
X881372Y920655D03*
X880102Y923235D03*
X889439Y1437938D03*
X891560Y1435510D03*
X888652Y1581793D03*
Y1573793D03*
X885652Y1584539D03*
X888652Y1597793D03*
Y1585993D03*
X883152Y1586507D03*
X888652Y1589793D03*
Y1609793D03*
X892208Y1731911D03*
X908620Y188899D03*
X903930Y202885D03*
X903980Y210355D03*
X903930Y217059D03*
X896620Y209662D03*
X894120D03*
Y207162D03*
X896620D03*
X903980Y224529D03*
X906120Y261252D03*
X894770Y283062D03*
X893500Y339062D03*
X896540Y341132D03*
X908675Y455386D03*
X899625Y473856D03*
X902260Y473153D03*
Y475653D03*
X903124Y470797D03*
X900020Y470672D03*
X896060Y481222D03*
Y484622D03*
X893321Y480293D03*
X893311Y485531D03*
X907678Y488177D03*
X895340Y497882D03*
Y501282D03*
X893572Y503050D03*
Y496114D03*
X900061Y510962D03*
X906127Y496343D03*
X901829Y512730D03*
Y516130D03*
X900061Y517898D03*
X893450Y516862D03*
X901230Y531612D03*
X904630D03*
X893298Y534380D03*
X899462Y533380D03*
X906398D03*
X894897Y871745D03*
X897000Y891895D03*
X894375Y913692D03*
X894965Y917422D03*
X898062Y976652D03*
Y969716D03*
X899830Y971484D03*
Y974884D03*
X907770Y1045242D03*
X894830Y1435970D03*
X896652Y1577793D03*
X899652Y1582570D03*
Y1573793D03*
X896672Y1587073D03*
X897352Y1590893D03*
X896652Y1593793D03*
X899551D03*
X902652Y1590444D03*
X896652Y1605793D03*
Y1601793D03*
X912214Y141891D03*
X917680Y174999D03*
Y177999D03*
Y171999D03*
X920246Y184138D03*
X922726Y176302D03*
X922100Y181791D03*
X917386Y184114D03*
X909386Y195925D03*
X924920Y196199D03*
X923836Y193563D03*
X909386Y203011D03*
Y210098D03*
Y217185D03*
Y224271D03*
Y231358D03*
X914550Y239924D03*
X923897Y445545D03*
X927034Y445594D03*
X912984Y458135D03*
X909584D03*
X913913Y455396D03*
X919279Y461244D03*
X924447Y463012D03*
X921047D03*
X909190Y473392D03*
X912288Y472430D03*
X920682Y494586D03*
X918532Y492445D03*
X927154Y492103D03*
X924623Y492097D03*
X918078Y495177D03*
X921189Y492086D03*
X918212Y497677D03*
X918131Y503330D03*
X921060Y506086D03*
X923783Y506076D03*
X918212Y500777D03*
X909984Y496330D03*
X926173Y512391D03*
X920980Y503393D03*
X913394Y521662D03*
X916794D03*
X909600Y521162D03*
X911720Y511662D03*
X911626Y523430D03*
X918562D03*
X924647Y526808D03*
X922879Y531976D03*
Y528576D03*
X924647Y533744D03*
X918420Y804062D03*
X909720Y798861D03*
Y794862D03*
X913720Y799362D03*
X914152Y803294D03*
X924600Y824262D03*
X921757Y962082D03*
X916974Y962108D03*
X923403Y983327D03*
X923930Y976652D03*
X917980Y974952D03*
X923322Y990227D03*
X924440Y996852D03*
X914838Y985989D03*
X918720Y1009937D03*
X921880Y1525110D03*
X924380D03*
X921880Y1527610D03*
X924380D03*
X919488Y1660733D03*
X918020Y1672860D03*
X914500Y1671400D03*
X912208Y1731911D03*
X932214Y141891D03*
X938160Y173389D03*
X935550Y173329D03*
X940720Y173389D03*
X938160Y176389D03*
X935550Y176329D03*
X940720Y176389D03*
X940424Y184190D03*
X936424D03*
X927133Y189386D03*
X935496Y195925D03*
X935770Y191419D03*
X939270D03*
X940410Y188852D03*
X935496Y203012D03*
X925320Y203399D03*
X935496Y210098D03*
Y217185D03*
Y224272D03*
Y231358D03*
X930472Y246093D03*
X938603Y240063D03*
X933122Y246115D03*
X933686Y242922D03*
X935454Y241154D03*
X941059Y427911D03*
Y424511D03*
X940709Y460438D03*
X938437Y455454D03*
X932724Y455538D03*
X926215Y461244D03*
X937447Y457862D03*
X934047D03*
X928394Y472201D03*
Y474701D03*
X932373Y495175D03*
X929234Y494915D03*
X938588Y485197D03*
X932089Y492691D03*
X929654Y492103D03*
X929698Y503595D03*
X940596Y498648D03*
X932218Y499314D03*
X939872Y495813D03*
X932089Y505986D03*
X932289Y502986D03*
X926637Y506069D03*
X929281Y506086D03*
X931720Y524862D03*
X939097Y527257D03*
X940550Y517400D03*
X940140Y514925D03*
X933773Y530479D03*
X930731D03*
X941050Y532252D03*
Y528852D03*
X928231Y530479D03*
X936273Y530478D03*
X939282Y534020D03*
X938742Y803831D03*
X931573Y816109D03*
X927470Y815112D03*
X927200Y811462D03*
X935052Y812630D03*
X934260Y808312D03*
X938371Y809311D03*
X930786Y811785D03*
X925220Y817862D03*
X928237Y824844D03*
X926469Y826612D03*
X931496Y962082D03*
X926823D03*
X940170Y962842D03*
X930233Y983298D03*
X930274Y990237D03*
X939740Y987762D03*
X936998Y985750D03*
X932310Y996812D03*
X929221Y1014664D03*
X927220Y1012362D03*
X931220D03*
X939380Y1525110D03*
X926880D03*
X929380D03*
X931880D03*
X934380D03*
X936880D03*
X926880Y1527610D03*
X929380D03*
X931880D03*
X934380D03*
X936880D03*
X939380D03*
X938652Y1581393D03*
X928152Y1584539D03*
X938652Y1593393D03*
Y1585393D03*
X925152Y1586507D03*
X938652Y1589393D03*
X933979Y1661327D03*
X929979Y1661352D03*
X942100Y1671100D03*
X932208Y1731911D03*
X952214Y141891D03*
X957420Y153699D03*
X945720Y173389D03*
X943220D03*
X945720Y176389D03*
X943220D03*
X948400Y176499D03*
X949120Y184912D03*
X949710Y198289D03*
X941634Y199051D03*
Y193451D03*
X944250Y194489D03*
Y197889D03*
X957020Y193299D03*
X949550Y192819D03*
X951354Y209437D03*
Y203837D03*
X944880Y210959D03*
Y216559D03*
Y230697D03*
Y225097D03*
X954874Y232071D03*
X954904Y225741D03*
X957020Y264862D03*
X953046Y390103D03*
X951181Y391916D03*
X950660Y399472D03*
X956487Y394831D03*
X942646Y400793D03*
X949920Y404602D03*
X942827Y422743D03*
Y429679D03*
X944032Y437631D03*
Y434231D03*
X945800Y432463D03*
Y439399D03*
X946492Y460410D03*
X945447Y463012D03*
X942047D03*
X946727Y507952D03*
Y504552D03*
X954420Y511252D03*
Y500552D03*
Y497152D03*
X956188Y495384D03*
Y502320D03*
X948495Y502784D03*
X948693Y509497D03*
X956188Y509484D03*
X954420Y514652D03*
X954390Y527596D03*
X956188Y516420D03*
X947190Y527330D03*
X945524Y515483D03*
X944261Y517871D03*
X941740Y512922D03*
X942610Y515350D03*
X952622Y529364D03*
X945100Y534464D03*
X955123Y533642D03*
X948415Y534313D03*
X956518Y531567D03*
X957220Y582862D03*
X953594Y787477D03*
X956700Y786862D03*
X954447Y791735D03*
X951043Y796140D03*
X950190Y791382D03*
X944272Y803410D03*
X943366Y798707D03*
X946786Y795287D03*
X947921Y799761D03*
X941400Y810062D03*
X944170Y962842D03*
X946865Y974077D03*
X953235Y972642D03*
X949560Y981392D03*
X946938Y991162D03*
X943720Y985772D03*
X951560Y997422D03*
X956800Y1663725D03*
X956600Y1666875D03*
X952208Y1731911D03*
X972214Y141891D03*
X960420Y153699D03*
X962604Y165313D03*
X962458Y162398D03*
X965150Y193412D03*
X966720Y198099D03*
X970720D03*
X961120Y193299D03*
X963520Y214699D03*
X960703Y212668D03*
X971471Y242358D03*
X968384Y242051D03*
X965884D03*
X960020Y264862D03*
X963020D03*
X962570Y282812D03*
X962882Y314512D03*
X967239Y320073D03*
X963854Y320113D03*
X963300Y347962D03*
X965792Y350959D03*
X962623Y350642D03*
X965420Y365719D03*
X970730Y377872D03*
X963856Y394202D03*
X960059Y387004D03*
X972986Y393171D03*
X972220Y386251D03*
Y390239D03*
X975670Y392063D03*
X965890Y405967D03*
X963720Y439862D03*
X970054Y478773D03*
X961320Y476242D03*
X970054Y485709D03*
X968286Y483941D03*
Y480541D03*
X966720Y511362D03*
X960620Y509462D03*
X972379Y509303D03*
X964347Y509462D03*
X970788Y501230D03*
X964347Y501262D03*
X969351Y512416D03*
X957790Y527596D03*
X963930Y533362D03*
X967330D03*
X959558Y529364D03*
X962162Y535130D03*
X969098D03*
X959351Y533566D03*
X958755Y657078D03*
X960920Y644762D03*
Y649762D03*
Y654762D03*
X963720Y647262D03*
Y657262D03*
Y652262D03*
X963520Y665062D03*
X958866Y662378D03*
X960820Y665062D03*
X960920Y659762D03*
X963720Y662262D03*
X959100Y789862D03*
X963610Y981292D03*
X959535Y990477D03*
X963780Y997496D03*
X967750Y1376460D03*
X965904Y1554364D03*
X960904D03*
X969000Y1554262D03*
X965086Y1603984D03*
X962086D03*
X972208Y1731911D03*
X975688Y152950D03*
Y149950D03*
X990501Y152397D03*
X986369Y155358D03*
X975690Y157220D03*
X983811Y156694D03*
X985499Y168753D03*
X988835Y185443D03*
X981445Y181058D03*
X990115Y173039D03*
X987320Y194599D03*
Y198099D03*
Y201599D03*
X977220Y201399D03*
X986020Y191099D03*
X987259Y276094D03*
X981470Y268532D03*
X988818Y346372D03*
X985016Y344659D03*
X974791Y339990D03*
X986182Y361062D03*
X978000Y362462D03*
X988723Y369650D03*
X991934Y368443D03*
X989500Y376362D03*
X979380Y373082D03*
X986400Y383123D03*
X983770Y373962D03*
X979766Y377507D03*
X977949Y384205D03*
X980916Y384286D03*
X980856Y392502D03*
X986955Y391939D03*
X983629Y397628D03*
X979559Y399362D03*
X983970Y392562D03*
X991369Y408252D03*
X988159Y409068D03*
X979240Y425212D03*
X983760Y424292D03*
X980092Y421289D03*
X987440Y431193D03*
X985672Y432961D03*
X980720Y512362D03*
X986400Y503200D03*
X983720Y512362D03*
X976283Y534226D03*
X986273Y532996D03*
X980535Y532643D03*
X986418Y530019D03*
X975900Y1265062D03*
X987920Y1290662D03*
X985320Y1288762D03*
X992306Y1295049D03*
X979373Y1342724D03*
X984270Y1554364D03*
X989270D03*
X995000Y150883D03*
X1001500D03*
X995180Y153689D03*
X1002735Y153943D03*
X999735D03*
X1001101Y165510D03*
X999915Y180548D03*
X996415D03*
X992505Y180553D03*
X993205Y174053D03*
X993305Y170953D03*
X996415Y172579D03*
X1002920Y174799D03*
X990220Y195699D03*
Y199199D03*
X1008120Y198293D03*
X990495Y212923D03*
X990220Y202699D03*
X1000610Y211039D03*
X1005640Y210969D03*
X1001195Y219898D03*
X1005120Y230399D03*
X1002500Y266862D03*
X998500Y269862D03*
X1002500D03*
X994743Y289843D03*
X1001065Y304622D03*
Y307122D03*
Y309622D03*
X994553Y365711D03*
X994689Y379348D03*
X1006201Y370004D03*
X999440Y371782D03*
X996922Y367764D03*
X997598Y382952D03*
X997612Y391804D03*
X1006221Y382945D03*
X997900Y400720D03*
X994322Y404090D03*
X1005123Y414662D03*
X997617Y412383D03*
X997394Y415578D03*
X991770Y418835D03*
X993387Y429827D03*
X993012Y421570D03*
X997225Y419162D03*
X990840Y431193D03*
X992608Y432961D03*
X1005720Y498862D03*
X1003220Y512862D03*
X1005520Y510932D03*
X999720Y512862D03*
X991097Y529902D03*
X991237Y533043D03*
X1008560Y589682D03*
X1002640Y594692D03*
X1005960Y594682D03*
X1005373Y748826D03*
X995120Y773122D03*
X994942Y777055D03*
X996675Y1286985D03*
X996320Y1280683D03*
Y1284062D03*
X997920Y1278762D03*
X994574Y1297318D03*
X1007636Y1554364D03*
X992466Y1554262D03*
X996698Y1604000D03*
X993698D03*
X992208Y1731911D03*
X1021908Y60392D03*
Y120392D03*
X1012214Y141826D03*
X1015300Y148736D03*
X1012187Y148749D03*
X1008129Y150948D03*
X1012791Y157596D03*
X1006435Y172843D03*
X1009895Y192359D03*
X1008067Y194356D03*
X1020645Y190499D03*
X1011320Y202169D03*
X1019935Y206463D03*
Y203333D03*
X1019355Y218423D03*
X1019802Y214099D03*
X1010005Y208424D03*
X1011720Y229699D03*
X1019355Y222423D03*
X1019530Y226423D03*
X1007820Y229999D03*
X1018000Y263862D03*
X1022000Y264362D03*
X1014500Y263862D03*
X1010500D03*
X1018000Y266862D03*
X1022002Y267342D03*
X1010500Y266862D03*
X1006500D03*
X1014500D03*
Y269862D03*
X1018000D03*
X1022002Y270142D03*
X1006500Y269862D03*
X1010500D03*
X1021118Y294290D03*
X1010828Y304822D03*
Y307322D03*
Y309822D03*
X1021419Y305704D03*
X1015520Y302862D03*
X1013500Y344900D03*
X1009800Y343800D03*
X1006710Y372931D03*
X1015096Y373758D03*
X1017163Y367963D03*
X1009883Y367955D03*
X1015638Y382968D03*
X1015637Y391334D03*
X1006589Y392017D03*
X1010420Y416062D03*
X1006750Y401010D03*
X1015657Y401013D03*
X1015420Y410862D03*
X1021259Y420548D03*
X1007249Y422682D03*
X1011611Y430038D03*
X1017511D03*
X1016261Y432888D03*
X1012861D03*
X1008720Y498362D03*
X1019145Y503823D03*
X1024200Y510362D03*
X1018092Y520212D03*
X1020392Y521826D03*
X1011720Y589362D03*
X1018720Y592362D03*
X1016360Y594682D03*
X1016220Y590862D03*
X1021720Y601862D03*
X1019000Y601042D03*
X1021654Y606302D03*
X1011160Y594682D03*
X1010630Y748741D03*
X1007873Y748826D03*
X1007600Y1298250D03*
X1007610Y1295040D03*
X1016012Y1554262D03*
X1012636Y1554364D03*
X1012208Y1731911D03*
X1038609Y49388D03*
X1027520Y122732D03*
X1037650Y128842D03*
X1026620Y125662D03*
X1034229Y128953D03*
X1032894Y155185D03*
X1023220Y187574D03*
X1025000Y264362D03*
X1031502Y267342D03*
X1028202D03*
X1025102D03*
X1037618Y261200D03*
X1031702Y264130D03*
X1033133Y272564D03*
X1031502Y270142D03*
X1029833Y272564D03*
X1026733D03*
X1023633D03*
X1028202Y270142D03*
X1025102D03*
X1036915Y290969D03*
X1025862Y291727D03*
X1032317Y291284D03*
X1036278Y303993D03*
Y307393D03*
X1029395Y375844D03*
X1025004Y374662D03*
X1031950Y383771D03*
Y387171D03*
X1031153Y390152D03*
X1029094Y383070D03*
Y387872D03*
X1026820Y394362D03*
X1033860Y400802D03*
X1026548Y400571D03*
X1035920Y428962D03*
Y420062D03*
Y417462D03*
X1038294Y506504D03*
X1027190Y510672D03*
X1026370Y503562D03*
X1032155Y509737D03*
X1029220Y520032D03*
X1025530Y519627D03*
X1033040Y519852D03*
X1038130Y518417D03*
X1038220Y589862D03*
X1040720Y591862D03*
X1030980Y598722D03*
X1023740Y596152D03*
X1036480Y596272D03*
X1024154Y601152D03*
X1029630Y601252D03*
X1026654Y596152D03*
X1035760Y592952D03*
X1033260Y601272D03*
X1038260D03*
X1033817Y735612D03*
X1036954Y734669D03*
X1030660Y735082D03*
X1031002Y1554364D03*
X1036002D03*
X1028298Y1604000D03*
X1025298D03*
X1032208Y1731911D03*
X1040970Y128332D03*
X1053028Y246518D03*
X1053428Y261118D03*
X1040924Y286073D03*
X1043720Y363462D03*
X1043629Y375078D03*
Y372578D03*
X1044120Y366362D03*
X1049100Y390162D03*
X1046156Y442699D03*
X1041420Y443962D03*
X1043920D03*
X1050470Y447062D03*
X1041444Y506504D03*
X1053690Y520760D03*
X1043720Y589362D03*
X1045720Y591672D03*
X1050200Y598062D03*
X1050390Y604172D03*
X1043260Y601272D03*
X1045760Y596272D03*
X1048260Y601272D03*
X1053200Y612162D03*
X1051680Y614772D03*
X1053745Y742341D03*
X1054368Y1554364D03*
X1039298Y1554262D03*
X1056898Y1604000D03*
X1052208Y1731911D03*
X1058609Y49388D03*
X1067220Y145362D03*
X1066820Y151632D03*
X1067220Y142862D03*
Y148362D03*
X1058028Y246518D03*
X1055528D03*
X1068093Y265503D03*
X1058428Y261118D03*
X1055928D03*
X1067618Y273800D03*
X1070718Y273700D03*
X1067718Y288500D03*
X1070618D03*
X1067718Y285600D03*
X1070618D03*
X1072310Y364422D03*
X1059943Y435314D03*
X1062120Y477462D03*
X1056190Y520760D03*
X1058220Y585862D03*
X1061470D03*
X1056280Y601232D03*
X1056220Y605052D03*
X1055205Y744853D03*
X1066462Y1520088D03*
X1062464Y1554262D03*
X1059368Y1554364D03*
X1059898Y1604000D03*
X1078609Y49388D03*
X1075100Y55682D03*
X1071920Y53862D03*
X1084146Y67102D03*
X1079114Y75775D03*
X1080168Y90721D03*
X1078270Y93462D03*
X1081282Y180937D03*
X1086756Y187540D03*
X1084130Y298342D03*
X1086630D03*
X1076353Y363966D03*
X1078853D03*
X1077270Y369061D03*
Y374131D03*
Y379251D03*
X1075462Y386723D03*
X1078151Y413911D03*
X1078120Y411262D03*
X1084245Y435437D03*
X1078545Y435637D03*
X1081045D03*
X1087280Y435437D03*
X1073724Y476867D03*
X1081906Y472577D03*
X1076598Y477087D03*
X1081930Y477132D03*
X1079320Y473892D03*
X1076820D03*
X1076739Y506461D03*
X1077751Y522235D03*
X1082220Y522362D03*
X1085720Y522422D03*
X1073250Y582332D03*
X1084637Y744635D03*
X1074010Y1510650D03*
X1077734Y1554364D03*
X1085830Y1554262D03*
X1082734Y1554364D03*
X1084000Y1647110D03*
X1072208Y1731911D03*
X1098609Y49388D03*
X1097794Y67881D03*
X1094644Y67992D03*
X1102561Y78461D03*
X1102480Y133722D03*
X1105580Y132822D03*
X1100630Y130376D03*
X1099030Y245140D03*
X1089130Y298342D03*
X1091630D03*
X1094130D03*
X1105553Y356475D03*
X1089660Y408560D03*
X1095820Y420762D03*
X1090245Y435437D03*
X1096477Y744385D03*
X1093497Y744655D03*
X1105480Y1517982D03*
X1101600Y1554364D03*
X1104750Y1549346D03*
X1095436Y1603944D03*
X1092436D03*
X1088790Y1641830D03*
X1094225Y1671710D03*
X1091880Y1673720D03*
X1092072Y1734244D03*
X1118609Y49388D03*
X1110977Y55505D03*
X1110754Y60028D03*
X1113594Y69862D03*
X1109020Y80592D03*
X1118486Y208942D03*
X1120190Y255652D03*
X1117820Y456132D03*
X1113207Y744455D03*
X1118110Y1398010D03*
X1115853Y1426342D03*
Y1435532D03*
X1117574Y1448604D03*
X1114400Y1518237D03*
X1110725Y1518046D03*
X1109118Y1526046D03*
X1113725Y1530935D03*
X1115802Y1615010D03*
X1117407Y1628495D03*
X1113990Y1631370D03*
X1113325Y1627975D03*
X1117182Y1625460D03*
X1106480Y1641275D03*
X1113110Y1666460D03*
X1108320Y1680200D03*
X1112130Y1711600D03*
X1112252Y1706170D03*
X1112200Y1709000D03*
X1114150Y1715726D03*
X1110663Y1719189D03*
X1119200Y1730300D03*
Y1727200D03*
X1114300Y1722700D03*
X1119300Y1724100D03*
X1111866Y1737108D03*
X1132856Y52926D03*
X1129948Y66786D03*
X1132547Y64864D03*
X1129997Y69864D03*
X1124858Y197309D03*
X1128485Y198159D03*
X1133041Y194137D03*
X1124360Y259712D03*
X1125409Y305797D03*
X1120544Y312200D03*
X1129995Y301637D03*
X1122059Y305673D03*
X1124985Y302578D03*
X1127402Y456174D03*
X1136051Y503324D03*
X1124120Y643762D03*
X1136720Y641362D03*
X1133720Y642862D03*
X1129420Y644062D03*
X1122980Y741312D03*
X1127972Y747250D03*
X1135750Y1255672D03*
X1129729Y1385200D03*
X1124679D03*
X1127179D03*
X1127788Y1397126D03*
X1135709Y1397119D03*
X1133209D03*
X1131629Y1420615D03*
X1129029D03*
X1134229D03*
X1123674Y1414936D03*
X1121174D03*
X1123674Y1417536D03*
Y1420136D03*
X1121174Y1417536D03*
Y1420136D03*
X1131629Y1423722D03*
X1129029D03*
X1134229D03*
X1123674Y1422736D03*
X1121174D03*
X1131042Y1436061D03*
X1135942D03*
X1133512D03*
X1131042Y1430461D03*
X1135942D03*
X1133512D03*
X1134429Y1426829D03*
X1122879Y1431474D03*
Y1434024D03*
X1125995Y1439780D03*
X1136004Y1447858D03*
X1126117Y1450504D03*
X1123379Y1443583D03*
X1133169Y1445690D03*
X1129169Y1442998D03*
X1135568Y1442923D03*
X1129169Y1445719D03*
X1127008Y1524203D03*
X1135748Y1524187D03*
X1127008Y1550285D03*
X1133780Y1550301D03*
X1132142Y1555301D03*
X1132187Y1582738D03*
X1135187D03*
X1132187Y1590738D03*
X1135187D03*
X1120472Y1615010D03*
X1124862D03*
X1127377Y1628485D03*
X1131632Y1625969D03*
X1131866Y1737108D03*
X1138609Y49388D03*
X1145603Y73679D03*
X1140242Y101135D03*
X1152720Y180862D03*
X1150914Y197407D03*
X1148795Y213731D03*
X1141957Y227277D03*
X1144457D03*
X1139457D03*
X1148354Y222677D03*
X1146670Y230110D03*
X1147700Y362731D03*
X1140465Y379592D03*
X1142302Y366532D03*
X1147700Y368041D03*
X1148220Y501362D03*
X1138551Y503324D03*
X1144720Y501362D03*
Y498662D03*
X1142967Y592097D03*
X1138500Y586362D03*
X1142127Y586452D03*
X1140697Y608762D03*
X1150140Y610362D03*
X1142790Y611122D03*
X1144810Y613762D03*
X1150272Y638346D03*
X1142674Y1287608D03*
X1144247Y1385200D03*
X1149297D03*
X1146797D03*
X1146118Y1397126D03*
X1138209Y1397119D03*
X1150843Y1415126D03*
X1148243D03*
X1150843Y1417726D03*
X1148243D03*
X1150732Y1420326D03*
X1142629Y1420615D03*
X1145573Y1420631D03*
X1139429Y1420615D03*
X1136829D03*
X1145573Y1423738D03*
X1136829Y1423722D03*
X1145542Y1426861D03*
X1137029Y1426829D03*
X1146563Y1436334D03*
X1141903D03*
X1144233Y1435584D03*
X1139573D03*
X1149469Y1437098D03*
X1151669Y1435698D03*
Y1438598D03*
X1137311Y1445191D03*
X1147203Y1441968D03*
X1149569Y1440098D03*
X1151669Y1441498D03*
X1147203Y1439068D03*
X1150821Y1459607D03*
Y1456587D03*
X1145108Y1476732D03*
X1138430Y1524150D03*
X1151497Y1524187D03*
X1153465Y1550301D03*
X1149528D03*
X1145410Y1540640D03*
X1143060Y1538380D03*
X1141654Y1550301D03*
X1137717Y1558020D03*
X1141690Y1552920D03*
X1152187Y1574738D03*
X1142187D03*
X1145187D03*
X1142187Y1582738D03*
X1145187D03*
X1152187D03*
X1141525Y1597630D03*
X1152187Y1590738D03*
X1142187D03*
X1145187D03*
X1140750Y1604330D03*
X1150380Y1602590D03*
X1139392Y1620851D03*
X1146960Y1618960D03*
X1152257Y1628910D03*
X1158609Y49388D03*
X1155703Y73679D03*
X1160720Y180862D03*
X1165440Y176450D03*
X1168710Y176590D03*
X1165000Y190962D03*
X1162500D03*
X1164300Y197262D03*
X1159460Y194090D03*
X1163732Y204887D03*
X1160732D03*
X1160630Y213870D03*
X1158172Y230157D03*
X1159753Y361281D03*
X1159460Y366025D03*
X1156790Y373231D03*
X1161690Y374110D03*
X1164320Y451062D03*
X1156100Y456342D03*
X1167190Y526922D03*
X1153467Y586462D03*
X1158300Y585862D03*
X1170740Y602132D03*
X1153490Y610322D03*
X1159912Y638216D03*
X1166722Y636206D03*
X1158762Y642266D03*
X1168402Y642136D03*
X1155962Y746193D03*
X1156609Y1286685D03*
X1167829Y1385200D03*
X1162779D03*
X1165279D03*
X1165931Y1397126D03*
X1154714Y1398295D03*
X1157786Y1398252D03*
X1167172Y1420615D03*
X1153913Y1420606D03*
Y1415406D03*
Y1418006D03*
X1159124D03*
Y1420606D03*
Y1415406D03*
X1161724D03*
Y1420606D03*
Y1418006D03*
X1156524Y1415406D03*
Y1420606D03*
Y1418006D03*
X1167172Y1423722D03*
X1153913Y1423206D03*
X1159124D03*
X1161724D03*
X1156524D03*
X1161022Y1431499D03*
Y1433999D03*
X1164138Y1439780D03*
X1154288Y1432502D03*
X1155964Y1440864D03*
X1164260Y1450423D03*
X1158954Y1450274D03*
X1161522Y1443630D03*
X1167312Y1442998D03*
Y1445964D03*
X1159386Y1464253D03*
Y1466753D03*
X1156386Y1464253D03*
Y1466753D03*
X1159386Y1469253D03*
X1156386D03*
X1153821Y1459607D03*
Y1456587D03*
X1159386Y1461753D03*
X1159476Y1458918D03*
X1156386Y1461753D03*
X1156476Y1458918D03*
X1159446Y1456113D03*
X1156446D03*
X1167245Y1524187D03*
X1159371D03*
X1163308D03*
X1155433D03*
X1165276Y1550301D03*
X1169213D03*
X1157402D03*
X1161339D03*
X1161595Y1574738D03*
X1164595D03*
X1155187D03*
X1161595Y1582738D03*
X1164595D03*
X1155187D03*
X1163079Y1601479D03*
X1161595Y1590738D03*
X1164595D03*
X1155187D03*
X1168192Y1604130D03*
X1152950Y1616470D03*
X1165950Y1617729D03*
X1169460Y1606630D03*
Y1616630D03*
Y1611630D03*
X1152930Y1633880D03*
X1158030Y1619250D03*
X1164830Y1628830D03*
X1163970Y1620600D03*
X1169325Y1642600D03*
X1158325D03*
X1162383Y1652505D03*
X1164830Y1654632D03*
X1159930D03*
X1161076Y1680624D03*
X1157700Y1681100D03*
X1174120Y57111D03*
X1175926Y69151D03*
X1180676Y106858D03*
X1187413Y143132D03*
X1181420Y157962D03*
X1181700Y186962D03*
X1173314Y176452D03*
X1184510Y188962D03*
X1173065Y194174D03*
X1183460Y205342D03*
X1181470Y208802D03*
X1172865Y210174D03*
X1181500Y222162D03*
X1172795Y222174D03*
X1180398Y289814D03*
X1186653Y302242D03*
X1171540Y310902D03*
X1181450Y306052D03*
X1174120Y355362D03*
X1169690Y526922D03*
X1172720Y527862D03*
X1172310Y584562D03*
X1181300Y584762D03*
X1174980Y585632D03*
X1174880Y592652D03*
X1170337Y607327D03*
X1173990Y602192D03*
X1177570Y602052D03*
X1175217Y595762D03*
X1176362Y636076D03*
X1180262Y642216D03*
X1183230Y739102D03*
X1173020Y745972D03*
X1175573Y1286765D03*
X1172573D03*
X1182747Y1385200D03*
X1185297D03*
X1184661Y1397126D03*
X1171752Y1397119D03*
X1176752D03*
X1174252D03*
X1183716Y1420631D03*
X1180772Y1420615D03*
X1174972D03*
X1177572D03*
X1172372D03*
X1169772D03*
X1183716Y1423738D03*
X1174972Y1423722D03*
X1172372D03*
X1169772D03*
X1174085Y1436061D03*
Y1430461D03*
X1171655Y1436061D03*
X1169185D03*
X1171655Y1430461D03*
X1169185D03*
X1183685Y1426861D03*
X1175172Y1426829D03*
X1172572D03*
X1184706Y1436334D03*
X1180046D03*
X1182376Y1435584D03*
X1177716D03*
X1174147Y1447858D03*
X1171342Y1445650D03*
X1175454Y1445191D03*
X1173711Y1442923D03*
X1179922Y1524203D03*
X1171182Y1524187D03*
X1179922Y1550285D03*
X1184330Y1573260D03*
X1184290Y1570080D03*
X1171595Y1574738D03*
X1174595D03*
X1171595Y1582738D03*
X1174595D03*
X1183410Y1594450D03*
X1183440Y1591640D03*
X1171595Y1590738D03*
X1174595D03*
X1178140Y1601100D03*
X1184200Y1599900D03*
X1183320Y1597080D03*
X1184501Y1606521D03*
X1169968Y1602370D03*
X1174550Y1615630D03*
X1178250Y1609100D03*
X1184200Y1602700D03*
X1185030Y1633010D03*
X1182470Y1618914D03*
X1172530Y1623020D03*
X1176900Y1627510D03*
X1185030Y1624660D03*
X1180325Y1642600D03*
X1173383Y1652505D03*
X1184383D03*
X1181930Y1654632D03*
X1175830D03*
X1170930D03*
X1183076Y1680624D03*
X1172076D03*
X1198609Y49388D03*
X1194478Y56986D03*
X1188720Y56755D03*
X1191700Y56822D03*
X1197520Y56962D03*
X1201158Y57130D03*
X1189393Y60183D03*
X1185500Y101400D03*
X1190700Y99000D03*
X1188700Y100700D03*
X1185400Y104000D03*
X1197627Y132859D03*
X1193532Y132644D03*
X1194800Y143112D03*
X1197414Y161592D03*
X1191020Y170862D03*
X1185420Y153762D03*
X1200720Y184862D03*
X1196100Y188962D03*
X1193500D03*
X1200720Y187862D03*
X1200963Y212648D03*
X1192600Y217662D03*
X1193000Y204486D03*
X1195500D03*
X1195100Y217662D03*
X1200830Y206002D03*
X1188600Y225962D03*
X1194840Y240672D03*
X1187013Y238972D03*
X1194840Y236592D03*
X1199720Y252362D03*
X1196720D03*
X1188810Y296088D03*
X1186280Y298972D03*
X1199027Y588714D03*
X1193198Y586172D03*
X1195698D03*
X1198198D03*
X1200698D03*
X1189902Y642086D03*
X1185687Y744475D03*
X1187797Y1385200D03*
X1189135Y1397529D03*
X1187736Y1420387D03*
X1188986Y1415287D03*
Y1417887D03*
X1186386Y1415287D03*
Y1417887D03*
X1191486Y1415287D03*
Y1417887D03*
X1190444Y1420384D03*
X1194750Y1424672D03*
X1197700Y1432672D03*
X1191930Y1424647D03*
X1187412Y1437498D03*
X1189612Y1436098D03*
X1191918Y1432516D03*
X1198010Y1441902D03*
X1185346Y1442128D03*
X1187512Y1440498D03*
X1189612Y1441898D03*
X1185346Y1439228D03*
X1189612Y1438998D03*
X1198880Y1457162D03*
X1187720Y1517688D03*
X1187830Y1522188D03*
X1198546Y1520188D03*
X1187830Y1526688D03*
X1198546Y1524688D03*
X1187720Y1536362D03*
X1198485Y1534313D03*
X1198436Y1529362D03*
X1187720Y1531862D03*
Y1553692D03*
X1198497Y1539667D03*
X1187720Y1548772D03*
X1198436Y1546492D03*
X1187720Y1544292D03*
X1198436Y1551192D03*
Y1556192D03*
X1197181Y1563587D03*
X1198436Y1561062D03*
X1187720Y1558682D03*
Y1563182D03*
X1194510Y1563076D03*
X1187600Y1622064D03*
X1201600Y1633790D03*
X1199400Y1627800D03*
X1190895Y1642910D03*
X1186000Y1640000D03*
X1197400Y1654942D03*
X1192500D03*
X1186830Y1654632D03*
X1193646Y1680934D03*
X1201106Y1677873D03*
X1190735Y1688390D03*
X1194793Y1698295D03*
X1201505Y1688435D03*
X1192340Y1700422D03*
X1197240D03*
X1193174Y1726414D03*
X1191866Y1737108D03*
X1213026Y56742D03*
X1216176D03*
X1201800Y94600D03*
X1202860Y120392D03*
X1215763Y114363D03*
X1206093Y120362D03*
X1204800Y108900D03*
X1206900Y115900D03*
X1215800Y111300D03*
X1202920Y117162D03*
X1210910Y129502D03*
X1206114Y132962D03*
X1206434Y129492D03*
X1206694Y139512D03*
X1214573Y148909D03*
X1214415Y153962D03*
X1206664Y158952D03*
X1214091Y164962D03*
X1214593Y168962D03*
X1214054Y186092D03*
X1208518Y174162D03*
X1203858Y185451D03*
X1213720Y200309D03*
X1204420Y195362D03*
X1213720Y189362D03*
X1204220D03*
X1213720Y195362D03*
X1215720Y204862D03*
X1203200Y202514D03*
X1219060Y213312D03*
X1210084Y224362D03*
X1206660Y224742D03*
X1213540Y224792D03*
X1207220Y247148D03*
X1217720Y249862D03*
X1207220Y243998D03*
X1210900Y265300D03*
X1208365Y271151D03*
X1204475Y350684D03*
X1205165Y380962D03*
X1218870Y418082D03*
X1214000Y599262D03*
X1208980Y598462D03*
X1207100Y600882D03*
X1204880Y754032D03*
X1211277Y744265D03*
X1206757Y744455D03*
X1210288Y754081D03*
X1202300Y753962D03*
X1207607Y754095D03*
X1202600Y759662D03*
X1215896Y756942D03*
X1206432Y758995D03*
X1202307Y757082D03*
X1205820Y1652910D03*
X1210830Y1676500D03*
X1217210Y1684520D03*
X1212305Y1688700D03*
X1216363Y1698605D03*
X1205563Y1698340D03*
X1207180Y1685680D03*
X1208010Y1700467D03*
X1213910Y1700732D03*
X1203110Y1700467D03*
X1203939Y1726459D03*
X1214834Y1726724D03*
X1211866Y1737108D03*
X1218609Y49388D03*
X1228420Y58862D03*
X1230250Y89450D03*
X1228425Y91500D03*
X1222100Y91600D03*
X1225100Y91500D03*
X1225700Y108962D03*
X1228704Y112122D03*
X1223500Y111162D03*
X1223100Y127300D03*
X1229500Y125100D03*
X1223100Y130700D03*
X1226093Y152792D03*
X1234093Y144962D03*
X1222920Y144909D03*
Y148909D03*
X1222593Y168962D03*
X1222890Y157002D03*
X1226093Y168162D03*
Y177962D03*
X1222724Y176102D03*
X1226093Y172962D03*
X1223134Y190802D03*
X1225574Y188662D03*
X1228520Y202162D03*
X1229720Y197302D03*
X1226093Y193462D03*
X1225320Y200162D03*
X1233282Y201875D03*
X1223720Y217862D03*
Y205862D03*
X1223180Y210552D03*
X1233780Y214572D03*
X1231720Y217862D03*
Y209862D03*
X1232000Y244332D03*
Y248332D03*
X1219220Y243862D03*
Y247148D03*
X1230720Y380362D03*
X1227500Y380400D03*
X1221220Y380362D03*
X1232720Y377862D03*
X1224300Y380400D03*
X1219060Y757272D03*
X1223327Y757615D03*
X1228320Y758598D03*
X1218810Y1700732D03*
X1231866Y1737108D03*
X1238609Y49388D03*
X1236620Y58862D03*
X1239907Y95008D03*
X1241010Y110782D03*
X1243808Y116832D03*
X1244200Y112862D03*
X1249362Y111600D03*
X1241035Y114399D03*
X1247333Y121999D03*
X1234746Y136040D03*
X1240728Y136198D03*
X1241100Y145842D03*
X1242520Y165362D03*
X1244120Y167462D03*
X1246272Y164889D03*
X1243100Y160181D03*
X1236410Y201462D03*
X1236593Y197462D03*
X1236584Y205762D03*
X1236593Y209562D03*
X1236584Y217462D03*
X1236520Y213462D03*
X1245486Y203000D03*
X1245593Y211762D03*
X1236620Y221562D03*
X1245614Y227462D03*
X1245574Y234042D03*
X1244720Y230362D03*
X1245593Y219662D03*
X1239045Y224062D03*
X1245593Y241462D03*
Y237462D03*
X1240500Y248332D03*
Y244332D03*
X1246444Y256098D03*
X1236720Y257362D03*
X1252040Y306480D03*
X1243589Y379595D03*
X1236720Y377862D03*
X1234720Y380362D03*
X1242260Y757602D03*
X1258609Y49388D03*
X1261227Y52061D03*
X1258727D03*
X1263454Y83060D03*
X1266464Y83090D03*
X1264098Y88787D03*
X1262320Y96012D03*
X1262800Y101100D03*
X1264620Y92724D03*
X1252520Y92022D03*
X1258539Y109263D03*
X1260641Y114399D03*
X1252961Y111903D03*
X1264220Y110462D03*
X1250424Y108943D03*
X1257581Y114579D03*
X1266093Y129962D03*
X1256093Y143462D03*
Y149462D03*
X1265010Y162222D03*
X1264685Y175506D03*
X1261899Y174648D03*
X1253624Y201362D03*
X1267315Y220701D03*
X1264874Y217462D03*
X1256504D03*
X1255613Y209568D03*
X1265207Y208442D03*
X1259703Y209808D03*
X1253440Y230552D03*
X1253860Y235622D03*
X1256070Y229512D03*
X1256593Y233972D03*
Y225972D03*
X1253950Y246692D03*
X1266715Y244692D03*
X1254370Y241302D03*
X1265065Y249982D03*
X1256494Y243177D03*
X1256574Y238662D03*
X1266518Y237042D03*
X1256584Y248002D03*
X1256454Y252122D03*
X1264854Y253996D03*
Y256496D03*
X1258883Y280558D03*
X1258250Y292986D03*
X1263150Y294726D03*
X1267150Y305998D03*
X1256220Y434362D03*
X1261220Y454362D03*
X1253220Y451362D03*
X1267220D03*
X1260220Y477362D03*
X1255920Y511362D03*
X1256787Y749605D03*
X1258667Y751405D03*
X1255520Y747362D03*
X1263486Y739949D03*
X1253586Y1334649D03*
X1257586D03*
X1257672Y1351008D03*
X1251866Y1737108D03*
X1276820Y58142D03*
X1282360Y58132D03*
X1279580D03*
X1278300Y81232D03*
X1279390Y87697D03*
X1275820Y87962D03*
X1270329Y101011D03*
X1278456Y96187D03*
X1279415Y90847D03*
X1281704Y95402D03*
X1279485Y105752D03*
X1271284Y108971D03*
X1276745Y125850D03*
X1275807Y132922D03*
X1278949Y123567D03*
X1282764Y135398D03*
X1281600Y137962D03*
X1277820Y140682D03*
X1281093Y144516D03*
X1271954Y159143D03*
X1271593Y165962D03*
X1278093Y184462D03*
X1278993Y193262D03*
X1273093Y200038D03*
X1278183Y201262D03*
X1275493Y193962D03*
X1272893Y191262D03*
X1271315Y220701D03*
X1282568Y212722D03*
X1267773Y208373D03*
X1273093Y213962D03*
X1275727Y209597D03*
X1267618Y225382D03*
X1277661Y225685D03*
X1267593Y229462D03*
X1278783Y221386D03*
X1282176Y221436D03*
X1282654Y226309D03*
X1278320Y239292D03*
X1282293Y248962D03*
X1279493Y248662D03*
X1282645Y255671D03*
Y252271D03*
X1280223Y256841D03*
X1279841Y253052D03*
X1277771Y255173D03*
X1273754Y256504D03*
X1275557Y269477D03*
Y272436D03*
X1282653Y269446D03*
X1278557Y272436D03*
Y269477D03*
X1272557Y272436D03*
X1276800Y276562D03*
X1269960Y294536D03*
X1272530Y429362D03*
X1284220D03*
X1280270Y434362D03*
X1272220D03*
X1278380Y463362D03*
X1276220Y477362D03*
X1283220D03*
X1269220D03*
X1274420Y463362D03*
X1275576Y730879D03*
X1266727Y752955D03*
X1280135Y1340002D03*
Y1337402D03*
X1272707Y1334865D03*
X1279812Y1353552D03*
X1279334Y1356089D03*
X1275856Y1358098D03*
X1271990Y1358079D03*
X1276891Y1362891D03*
X1282928Y1361833D03*
X1269012Y1371693D03*
Y1368293D03*
X1271866Y1737108D03*
X1291280Y58262D03*
X1293860Y58312D03*
X1285201Y58121D03*
X1293430Y84072D03*
X1293454Y81232D03*
X1289210D03*
X1298640Y93062D03*
X1292880Y93162D03*
X1292899Y98519D03*
X1294354Y103166D03*
Y105912D03*
X1288093Y125962D03*
X1284930Y124922D03*
X1291478Y137745D03*
X1286150Y131092D03*
X1295053Y140181D03*
X1285793Y141562D03*
X1292293Y143162D03*
X1288258Y145501D03*
X1283781Y149115D03*
X1297605Y145824D03*
X1283781Y155788D03*
X1283425Y179272D03*
X1283397Y202085D03*
X1287943Y233748D03*
X1284437Y230280D03*
X1293893Y237962D03*
X1285710Y249182D03*
X1290293Y247562D03*
X1288637Y240448D03*
X1292630Y240462D03*
X1286611Y260908D03*
X1290005Y293768D03*
X1295278Y297056D03*
X1290322D03*
X1294500Y299692D03*
X1291100D03*
X1295887Y315571D03*
X1291500Y312862D03*
Y315362D03*
X1291420Y320662D03*
Y318162D03*
X1295540Y440902D03*
X1301310Y440862D03*
X1291220Y463362D03*
X1294440Y477267D03*
X1296630Y463462D03*
X1300220Y477362D03*
X1284220Y463362D03*
X1289936Y732539D03*
X1294937Y746965D03*
X1290520Y746562D03*
X1292904Y782048D03*
X1292572Y785575D03*
X1292614Y789910D03*
X1297298Y790982D03*
X1295150Y1323217D03*
X1298150D03*
X1291010Y1323307D03*
X1288010D03*
X1290102Y1365789D03*
X1286102Y1365051D03*
X1294312Y1367279D03*
X1292840Y1364821D03*
X1286102Y1368107D03*
X1291866Y1737108D03*
X1311960Y49672D03*
X1301820Y58672D03*
X1314741Y68652D03*
X1311424D03*
X1308174D03*
X1311960Y58152D03*
X1311260Y83032D03*
X1310857Y78542D03*
X1307120Y78562D03*
X1310906Y97807D03*
X1314406Y97756D03*
X1300454Y95302D03*
X1308274Y104162D03*
X1314059Y93877D03*
X1307244Y118452D03*
X1306836Y108242D03*
X1302080Y117032D03*
X1302060Y113852D03*
X1302964Y124633D03*
X1315156Y130656D03*
X1314920Y135361D03*
X1301993Y140462D03*
X1313117Y250605D03*
X1314685Y248651D03*
X1313950Y261612D03*
X1307431Y256099D03*
X1309283Y254162D03*
X1311275Y252297D03*
X1305552Y257974D03*
X1308736Y284948D03*
X1312136D03*
X1308790Y290172D03*
X1302450Y290072D03*
X1307798Y287561D03*
X1313246Y287631D03*
X1307042Y292636D03*
X1303642D03*
X1307442Y306998D03*
X1304042D03*
X1308220Y304262D03*
X1303120Y304162D03*
X1307677Y322996D03*
X1311077D03*
X1314450Y319841D03*
X1312845Y324764D03*
X1305909D03*
X1317100Y553900D03*
X1308600Y653500D03*
X1303576Y659671D03*
X1311420Y738262D03*
X1305187Y735630D03*
X1315020Y739862D03*
X1307469Y787772D03*
X1303017Y785837D03*
X1301034Y784165D03*
X1304260Y788265D03*
X1309930Y789852D03*
X1306701Y794779D03*
X1305117Y797125D03*
X1309210Y792802D03*
X1304066Y1323578D03*
X1305056Y1337104D03*
Y1326704D03*
Y1334504D03*
Y1329304D03*
Y1331904D03*
X1311820Y1330518D03*
Y1333018D03*
X1314936Y1338799D03*
X1312650Y1342572D03*
X1311866Y1737108D03*
X1318609Y49388D03*
X1316459Y58697D03*
X1330102Y59025D03*
X1322248Y68487D03*
X1321279Y58767D03*
X1317831Y68652D03*
X1322415Y75480D03*
X1327920Y84418D03*
X1322906Y94212D03*
X1319968Y98266D03*
X1316478Y92970D03*
X1329891Y99455D03*
X1322906Y109733D03*
X1330273Y128373D03*
X1323958Y146227D03*
X1326493Y249562D03*
X1323912Y245111D03*
X1317893Y257462D03*
X1328393Y264262D03*
X1320387Y258901D03*
X1325769Y259001D03*
X1325414Y293556D03*
X1328814D03*
X1319903Y299176D03*
X1323303D03*
X1319125Y296540D03*
X1324081D03*
X1324636Y290920D03*
X1329592D03*
X1319618Y318073D03*
X1325080Y323902D03*
X1316218Y318073D03*
X1328480Y323902D03*
X1330248Y325670D03*
X1323312D03*
X1321386Y319841D03*
X1329977Y334384D03*
X1330101Y540049D03*
X1327601D03*
X1328530Y747702D03*
X1325210Y744322D03*
X1322110Y1342755D03*
X1318110Y1342017D03*
X1326320Y1344245D03*
X1324848Y1341787D03*
X1318110Y1345073D03*
X1338609Y49388D03*
X1333190Y58825D03*
X1346720Y82912D03*
X1347640Y101950D03*
X1345583Y91307D03*
X1339280Y126175D03*
X1332497Y133931D03*
X1343034Y141698D03*
X1333811Y235348D03*
X1343362Y283155D03*
X1336761Y293404D03*
X1340161D03*
X1335947Y290755D03*
X1340903D03*
X1335145Y332616D03*
X1341431Y322693D03*
X1331745Y332616D03*
X1338031Y322693D03*
X1345424Y328981D03*
X1343656Y330749D03*
X1343199Y324461D03*
X1336263D03*
X1336913Y334384D03*
X1344720Y423162D03*
X1337220D03*
X1342220D03*
X1339720D03*
X1333143Y540049D03*
X1340420Y538422D03*
Y541822D03*
X1338652Y536654D03*
Y543590D03*
X1335643Y540048D03*
X1336187Y755635D03*
X1339784Y1306506D03*
X1337184D03*
X1337663Y1301001D03*
X1343968Y1300579D03*
X1340663Y1301001D03*
X1337184Y1309106D03*
Y1314306D03*
Y1311706D03*
X1343948Y1317092D03*
Y1319592D03*
X1344532Y1328161D03*
X1347397Y1325320D03*
X1331866Y1737108D03*
X1348610Y84712D03*
X1349480Y77072D03*
X1366369Y83820D03*
X1350550Y101632D03*
X1356223Y131569D03*
X1348620Y136162D03*
X1362793Y145262D03*
X1349704Y145385D03*
X1357888Y145893D03*
X1361111Y236448D03*
X1363846Y279848D03*
X1349362Y283155D03*
X1353902Y287540D03*
X1359902D03*
X1348824Y328981D03*
X1358371Y332275D03*
X1361771D03*
X1350592Y330749D03*
X1355200Y337843D03*
X1351800D03*
X1356968Y339611D03*
X1350032D03*
X1363539Y334043D03*
X1356603D03*
X1356220Y581862D03*
X1356047Y680000D03*
X1358907Y681262D03*
X1361727Y680665D03*
X1353982Y1287048D03*
X1362382D03*
X1359382D03*
X1350982D03*
X1354238Y1329329D03*
X1350238Y1328591D03*
X1358448Y1330819D03*
X1356976Y1328361D03*
X1350238Y1331647D03*
X1355357Y1396020D03*
X1364860Y1455172D03*
X1362410Y1445272D03*
X1351866Y1737108D03*
X1378839Y87626D03*
X1366124Y101529D03*
X1366369Y92450D03*
X1378550Y110692D03*
X1366868Y147341D03*
X1369593Y147462D03*
X1369916Y154132D03*
X1379969Y176330D03*
X1370586Y176366D03*
X1376991Y176430D03*
X1373591D03*
X1370405Y186938D03*
X1377597Y197604D03*
X1375300Y208422D03*
X1369479Y208384D03*
X1370636Y227292D03*
X1369410Y224504D03*
X1375619Y236261D03*
X1375257Y229756D03*
X1373493Y227762D03*
X1378452Y236055D03*
X1377742Y244372D03*
Y250372D03*
X1377626Y258914D03*
Y264914D03*
X1369846Y279848D03*
X1372381Y661428D03*
X1371931Y672978D03*
Y685278D03*
X1370207Y682245D03*
X1372243Y697108D03*
Y709108D03*
Y721108D03*
X1375463Y1287048D03*
X1372463D03*
X1371912Y1303480D03*
X1376208Y1303319D03*
X1371912Y1300880D03*
X1376208Y1300719D03*
Y1295586D03*
X1371912Y1295747D03*
Y1298280D03*
X1376208Y1298119D03*
X1369312Y1303480D03*
Y1300880D03*
Y1295747D03*
Y1298280D03*
X1376076Y1317092D03*
Y1319592D03*
X1379192Y1325373D03*
X1377214Y1327653D03*
X1377054Y1394028D03*
X1376666Y1402778D03*
X1376686Y1399758D03*
X1367316Y1399053D03*
Y1403458D03*
X1370577Y1421899D03*
X1377060Y1411231D03*
X1367436Y1414778D03*
X1370891Y1410306D03*
X1378417Y1415292D03*
X1367316Y1407458D03*
X1367889Y1419235D03*
X1371960Y1436172D03*
X1365040Y1431142D03*
X1377075Y1425014D03*
X1365235Y1428637D03*
X1370250Y1433715D03*
X1367620Y1431472D03*
X1367170Y1453142D03*
X1368842Y1449261D03*
X1364800Y1449231D03*
X1368980Y1457122D03*
X1370041Y1460374D03*
X1371866Y1737108D03*
X1393250Y93802D03*
X1383480Y88932D03*
X1389609Y145291D03*
X1389443Y147859D03*
X1386684Y145017D03*
X1386404Y149008D03*
X1394182Y171470D03*
X1398182D03*
X1386780Y197668D03*
X1395321D03*
X1395960Y226422D03*
X1393460D03*
X1386868Y222937D03*
X1384017Y223697D03*
X1386138Y225411D03*
X1384895Y221346D03*
X1381951Y221420D03*
X1381235Y236020D03*
X1383734Y243329D03*
Y237329D03*
X1388778Y250661D03*
X1388908Y260301D03*
X1386237Y265620D03*
Y275200D03*
X1385190Y501242D03*
X1390220Y497742D03*
X1392685Y498992D03*
X1387550Y502922D03*
X1387600Y499182D03*
X1391260Y507082D03*
X1381131Y656378D03*
Y668378D03*
X1395831Y666278D03*
X1386931Y660978D03*
X1381131Y680278D03*
X1396031Y680678D03*
X1386931Y675478D03*
X1387143Y690208D03*
X1380731Y692208D03*
X1395631Y695108D03*
X1380731Y704208D03*
X1387143Y704708D03*
X1380731Y716208D03*
X1395631Y709608D03*
X1387143Y719235D03*
X1395631Y724135D03*
X1382920Y733725D03*
X1391408Y738625D03*
X1384173Y1161549D03*
X1384089Y1153369D03*
X1386673Y1161520D03*
Y1153340D03*
X1384173Y1169599D03*
X1386673Y1169570D03*
X1386366Y1329329D03*
X1382366Y1328591D03*
X1390576Y1330819D03*
X1389104Y1328361D03*
X1382366Y1331647D03*
X1396311Y1385712D03*
X1398680Y1380582D03*
X1390474Y1385142D03*
X1387074Y1384272D03*
X1388813Y1393160D03*
X1396115Y1405289D03*
X1390513Y1395452D03*
X1387066Y1401734D03*
X1387291Y1408163D03*
X1396115Y1412789D03*
X1396615Y1420289D03*
X1387470Y1418302D03*
X1385109Y1410427D03*
X1390170Y1423942D03*
X1387068Y1413991D03*
X1384695Y1425047D03*
X1381066Y1425008D03*
X1393630Y1426562D03*
X1388557Y1431645D03*
X1395907Y1430227D03*
X1395443Y1434700D03*
X1398569Y1437860D03*
X1383429Y1427652D03*
X1392620Y1446708D03*
X1389220D03*
X1382600Y1563480D03*
X1391655Y1570037D03*
X1391055Y1565037D03*
X1384840Y1565640D03*
X1386790Y1563610D03*
X1392475Y1576097D03*
X1396600Y1582500D03*
Y1594000D03*
Y1590200D03*
Y1586400D03*
X1393000Y1590300D03*
X1395325Y1606862D03*
X1386200Y1645700D03*
X1386600Y1641400D03*
X1391866Y1737108D03*
X1412954Y138742D03*
X1409558Y151948D03*
X1404402Y138742D03*
X1407029Y152732D03*
X1410370Y138742D03*
X1406970D03*
X1409558Y156904D03*
X1407029Y156132D03*
X1407613Y177159D03*
X1398770D03*
X1402258Y184263D03*
X1411101D03*
X1409716Y171696D03*
X1401240Y171672D03*
X1401341Y177159D03*
X1404829Y184263D03*
X1404741Y177159D03*
X1408229Y184263D03*
X1407178Y171684D03*
X1403778D03*
X1404071Y197668D03*
X1412851D03*
X1404630Y220018D03*
X1412270Y230952D03*
X1413900Y225212D03*
X1396900Y228932D03*
X1405436Y238378D03*
X1400207Y238257D03*
X1407913Y1161569D03*
X1410413Y1153369D03*
X1407913D03*
X1410613Y1161569D03*
X1407913Y1170069D03*
X1410613D03*
X1410819Y1287198D03*
X1407819D03*
X1399419D03*
X1402419D03*
X1404040Y1303480D03*
X1408336Y1303319D03*
X1404040Y1300880D03*
X1408336Y1300719D03*
Y1295586D03*
X1404040Y1295747D03*
Y1298280D03*
X1408336Y1298119D03*
X1401440Y1303480D03*
Y1300880D03*
Y1295747D03*
Y1298280D03*
X1408204Y1317092D03*
Y1319592D03*
X1411320Y1325373D03*
X1408969Y1327645D03*
X1401655Y1384676D03*
X1406461Y1383862D03*
X1415171Y1383692D03*
X1412961Y1387387D03*
X1412608Y1391687D03*
X1403615Y1405289D03*
X1411115D03*
X1414362Y1402191D03*
X1411115Y1412789D03*
X1403615Y1420289D03*
X1411115D03*
X1414786Y1426890D03*
X1413440Y1436774D03*
X1409680Y1430613D03*
X1401371Y1434592D03*
X1410477Y1440117D03*
X1410038Y1434670D03*
X1405876Y1453298D03*
X1403687Y1444711D03*
X1400287D03*
X1403350Y1516435D03*
X1400220Y1518862D03*
X1403590Y1532255D03*
X1403350Y1521335D03*
X1409248Y1528862D03*
X1403740Y1548375D03*
X1403590Y1537155D03*
X1403740Y1543475D03*
X1400160Y1543342D03*
X1404433Y1565037D03*
X1400695Y1570037D03*
X1400715Y1565037D03*
X1407440Y1557552D03*
X1404433Y1570037D03*
X1402536Y1576097D03*
X1398700Y1597800D03*
X1407200Y1591400D03*
X1402680Y1597700D03*
X1411070Y1603282D03*
X1401300Y1619917D03*
X1400000Y1630362D03*
X1410900Y1624800D03*
X1400000Y1626362D03*
Y1642362D03*
Y1634362D03*
Y1638362D03*
X1410500Y1638862D03*
X1396900Y1642100D03*
X1411866Y1737108D03*
X1420222Y184263D03*
X1418268Y171696D03*
X1413950Y184263D03*
X1423110D03*
X1417350D03*
X1426510D03*
X1413350Y220018D03*
X1416020D03*
X1424690D03*
X1424520Y225002D03*
X1416810Y225422D03*
X1428640Y230022D03*
X1428336Y232762D03*
X1415340Y231812D03*
X1418630Y220018D03*
X1422030D03*
X1431430Y251265D03*
X1413847Y239528D03*
X1426020Y261501D03*
X1431430Y256383D03*
Y264060D03*
X1428940Y269292D03*
X1426647Y329050D03*
X1417022Y621419D03*
X1418494Y1329329D03*
X1414494Y1328591D03*
X1422704Y1330819D03*
X1421232Y1328361D03*
X1414494Y1331647D03*
X1418990Y1387452D03*
X1422594Y1383301D03*
X1419995Y1397492D03*
X1415620Y1396652D03*
X1419055Y1392497D03*
X1426872Y1405811D03*
X1423256Y1403728D03*
X1424255Y1396612D03*
X1421480Y1415731D03*
X1422371Y1407722D03*
X1421371Y1411719D03*
X1421864Y1419730D03*
X1419991Y1423404D03*
X1429345Y1433695D03*
X1424930Y1433850D03*
X1416272Y1433949D03*
X1421435Y1430415D03*
X1419746Y1435932D03*
X1427349Y1442776D03*
X1414264Y1439494D03*
X1419256Y1440258D03*
X1423829Y1442776D03*
X1414350Y1516435D03*
X1426020Y1521535D03*
X1414590Y1532255D03*
X1414350Y1521335D03*
X1427120Y1537355D03*
X1414590Y1537155D03*
X1414740Y1543475D03*
Y1548375D03*
X1427320Y1548575D03*
X1416800Y1564862D03*
X1425620Y1556662D03*
X1428403Y1581378D03*
X1418241Y1583441D03*
X1422145Y1575362D03*
X1416060Y1574922D03*
X1422680Y1582100D03*
X1419450Y1596150D03*
X1423700Y1600400D03*
X1426680Y1603262D03*
X1425770Y1633772D03*
X1429250Y1623391D03*
X1419270Y1631000D03*
X1413230Y1641042D03*
X1438609Y49388D03*
X1434600Y59262D03*
X1441125Y57362D03*
X1438680Y64412D03*
X1444275Y57262D03*
X1432220Y61862D03*
X1440800Y66862D03*
X1447340Y157402D03*
X1429382Y184263D03*
X1442434Y210757D03*
X1441490Y224062D03*
X1438720Y220018D03*
X1430000D03*
X1430120Y225182D03*
X1431636Y230448D03*
X1444570Y238372D03*
X1431933Y238125D03*
X1430130Y259342D03*
X1431431Y267378D03*
X1436436Y300319D03*
X1436120Y315772D03*
X1436270Y312592D03*
X1436335Y309407D03*
X1436320Y305862D03*
Y303362D03*
X1436050Y321352D03*
X1436120Y318272D03*
X1436232Y344176D03*
X1437177Y720965D03*
X1433418Y729104D03*
X1435387Y1161569D03*
X1435837Y1153369D03*
X1432887Y1161569D03*
X1433337Y1153369D03*
X1435387Y1170069D03*
X1432887D03*
X1437258Y1287198D03*
X1445106Y1287158D03*
X1440258Y1287198D03*
X1437182Y1298991D03*
X1434582Y1304191D03*
Y1301591D03*
Y1296458D03*
Y1298991D03*
X1440507Y1302830D03*
Y1300230D03*
X1440536Y1296455D03*
X1437182Y1304191D03*
Y1301591D03*
Y1296458D03*
X1440332Y1317092D03*
Y1319592D03*
X1443448Y1325373D03*
X1441332Y1327793D03*
X1439155Y1399064D03*
X1437443Y1406289D03*
X1444997Y1392885D03*
X1435462Y1393009D03*
Y1396409D03*
X1431717Y1420625D03*
Y1417125D03*
Y1409125D03*
X1431829Y1412370D03*
X1443325Y1410068D03*
X1434312Y1415197D03*
X1443112Y1417929D03*
X1445020Y1412672D03*
X1443676Y1432624D03*
X1431717Y1427632D03*
Y1424125D03*
X1439742Y1436924D03*
X1430204Y1452014D03*
X1434720Y1454862D03*
X1440440Y1454892D03*
X1436330Y1521152D03*
X1436570Y1536972D03*
X1436720Y1548192D03*
X1437140Y1576012D03*
X1444468Y1570610D03*
X1433720Y1569762D03*
X1438300Y1598400D03*
X1440105Y1593352D03*
X1446700Y1598400D03*
X1430250Y1608442D03*
X1438300Y1611000D03*
Y1606800D03*
Y1602600D03*
X1430250Y1612812D03*
X1441800Y1620300D03*
Y1632900D03*
Y1628700D03*
Y1624500D03*
X1438547Y1638212D03*
X1443617D03*
X1431575Y1634842D03*
X1442573Y1649862D03*
X1442587Y1659242D03*
X1438320Y1668292D03*
X1438273Y1671103D03*
X1438220Y1673955D03*
X1446715Y1679957D03*
X1431866Y1737108D03*
X1458609Y49388D03*
X1446000Y67802D03*
X1458720Y153362D03*
Y149362D03*
X1450270Y143022D03*
X1450720Y153362D03*
X1448820Y148092D03*
X1458720Y169862D03*
Y165862D03*
Y161862D03*
Y157862D03*
X1450720Y169862D03*
Y161862D03*
X1449740Y166912D03*
X1458720Y181862D03*
Y177862D03*
Y173862D03*
X1450720Y181862D03*
Y177862D03*
Y173862D03*
X1456423Y209362D03*
X1453823Y205982D03*
X1462561D03*
X1457361D03*
X1459961Y210432D03*
X1456150Y214382D03*
X1449110Y233742D03*
X1446830Y236232D03*
X1453670Y278170D03*
X1455600Y297200D03*
X1459312Y341130D03*
X1456770Y342942D03*
X1460849Y343327D03*
X1445777Y362021D03*
X1460600Y352742D03*
X1462790Y359042D03*
X1462870Y355012D03*
X1459900Y370823D03*
X1456700Y369642D03*
X1455920Y373941D03*
X1463600Y374462D03*
X1449777Y371039D03*
X1449296Y410497D03*
X1455642Y409646D03*
X1449296Y407347D03*
X1456777Y418596D03*
Y426546D03*
X1454889Y658712D03*
X1454439Y670262D03*
Y682562D03*
X1454751Y694392D03*
Y706392D03*
X1454439Y718362D03*
X1459057Y733545D03*
X1457597Y739035D03*
X1456237Y726945D03*
X1457620Y736195D03*
X1460187Y729805D03*
X1455692Y731401D03*
X1457714Y741622D03*
X1458911Y1161569D03*
Y1170069D03*
X1453366Y1287198D03*
X1458766D03*
X1461766D03*
X1450366D03*
X1450622Y1329329D03*
X1446622Y1328591D03*
X1454832Y1330819D03*
X1453360Y1328361D03*
X1446622Y1331647D03*
X1459968Y1402765D03*
X1451176Y1399026D03*
X1451198Y1403047D03*
X1461377Y1417844D03*
X1460224Y1407545D03*
X1458138Y1409955D03*
X1461062Y1413246D03*
X1454829Y1439732D03*
X1459135Y1439627D03*
X1459136Y1442241D03*
X1455006Y1447938D03*
X1459111Y1445669D03*
Y1448669D03*
X1457577Y1526689D03*
X1457817Y1542509D03*
X1457967Y1553729D03*
X1458200Y1565037D03*
Y1560037D03*
X1448620Y1556162D03*
X1446600Y1595400D03*
X1456030Y1590302D03*
X1456120Y1586262D03*
X1453600Y1595662D03*
X1460441Y1602441D03*
X1446786Y1610639D03*
X1451500Y1612800D03*
X1451580Y1627990D03*
X1454167Y1638302D03*
X1459127D03*
X1448507Y1638212D03*
X1452757Y1671399D03*
X1446380Y1676291D03*
X1448920Y1675062D03*
X1464200Y67802D03*
X1474142Y61767D03*
X1470220Y145362D03*
X1462000Y153362D03*
X1473090Y204502D03*
X1465179Y213102D03*
X1470101Y207751D03*
X1472335Y209362D03*
X1467761Y205982D03*
X1476858Y225448D03*
X1466940Y230272D03*
X1471308Y230640D03*
X1463833Y230448D03*
X1466958Y244948D03*
X1477700Y236522D03*
X1474660Y252878D03*
X1463833Y235566D03*
X1468620Y258857D03*
X1467230Y252472D03*
X1473820Y265962D03*
X1471510Y252878D03*
X1471690Y259862D03*
X1463950Y258172D03*
X1463330Y264060D03*
X1466660Y273878D03*
X1475452Y289708D03*
X1475352Y306308D03*
X1476826Y312177D03*
X1462777Y362021D03*
X1470877Y374496D03*
X1467700Y370953D03*
X1472758Y370817D03*
X1463277Y406446D03*
X1470954D03*
X1475790Y404842D03*
X1465836Y408668D03*
X1470942Y409718D03*
X1475250Y401812D03*
X1473310Y418502D03*
X1469777Y418396D03*
X1469951Y429251D03*
X1469720Y434542D03*
X1469760Y452622D03*
X1471460Y633402D03*
X1468060D03*
X1466292Y631634D03*
X1473228D03*
X1463639Y653662D03*
X1469651Y655992D03*
X1462010Y645842D03*
X1465171Y647132D03*
X1469020Y647102D03*
X1463639Y665662D03*
X1478139Y660892D03*
X1469439Y670262D03*
X1463639Y677562D03*
X1463239Y689492D03*
X1478139Y689892D03*
X1469651Y684992D03*
X1463239Y701492D03*
X1478139Y704392D03*
X1469477Y699475D03*
X1463239Y713492D03*
X1478139Y718892D03*
X1469651Y713992D03*
X1470841Y721493D03*
X1474100Y735662D03*
X1466451Y726992D03*
X1474939Y731892D03*
X1474180Y1300407D03*
X1471180D03*
X1465696Y1303480D03*
X1468296D03*
X1465696Y1300880D03*
X1468296D03*
X1473956Y1341068D03*
X1472460Y1330493D03*
Y1333043D03*
X1475576Y1338799D03*
X1475959Y1385027D03*
X1476000Y1393027D03*
X1465747Y1401405D03*
X1466448Y1421499D03*
X1475935Y1439627D03*
X1475936Y1442241D03*
X1467550Y1439642D03*
X1467536Y1442241D03*
X1467567Y1445669D03*
Y1448669D03*
X1475967Y1445669D03*
Y1448669D03*
X1478320Y1522962D03*
X1472565Y1623635D03*
X1478061Y1633864D03*
X1463767Y1638302D03*
X1476570Y1657974D03*
Y1661124D03*
X1478609Y49388D03*
X1493120Y240412D03*
X1487958Y236062D03*
X1490060Y255378D03*
X1485320Y260362D03*
X1487058Y281456D03*
X1478745Y281508D03*
X1493289Y280027D03*
X1484958Y289656D03*
X1487658D03*
X1478526Y289677D03*
X1481445Y289708D03*
X1484758Y312356D03*
X1487458D03*
X1484858Y305956D03*
X1487558D03*
X1479745Y312208D03*
X1478426Y306277D03*
X1481345Y306308D03*
X1481360Y358792D03*
X1481484Y361688D03*
X1486884Y374338D03*
X1479207D03*
X1481766Y372288D03*
X1489443D03*
X1494784Y374188D03*
X1486040Y368392D03*
X1478203Y406207D03*
X1488500Y410152D03*
X1481766Y406238D03*
X1490384Y407292D03*
X1493384Y411313D03*
X1482650Y411190D03*
X1495527Y406215D03*
X1493384Y419263D03*
X1481384Y419392D03*
X1486880Y416863D03*
X1484805Y427577D03*
X1489310Y426822D03*
X1478539Y675462D03*
X1491840Y1300447D03*
X1482750Y1342755D03*
X1478750Y1342017D03*
X1486960Y1344245D03*
X1485488Y1341787D03*
X1478750Y1345073D03*
X1481155Y1387742D03*
X1481255Y1382042D03*
X1478559Y1385027D03*
X1481159Y1384727D03*
X1481155Y1396342D03*
Y1398942D03*
Y1390342D03*
X1478600Y1393027D03*
X1481107Y1393095D03*
X1479658Y1405397D03*
X1485301Y1409442D03*
X1485274Y1406911D03*
X1485380Y1412202D03*
X1479671Y1410411D03*
Y1412911D03*
Y1407911D03*
X1482201Y1409442D03*
X1482174Y1406911D03*
X1482280Y1412202D03*
X1485387Y1420002D03*
X1481918Y1425579D03*
X1484395Y1439598D03*
X1484336Y1442241D03*
X1484442Y1445557D03*
Y1448557D03*
X1482830Y1525162D03*
X1478724Y1637189D03*
X1480800Y1663600D03*
X1491866Y1737108D03*
X1498609Y49388D03*
X1510500Y125992D03*
X1505821Y215802D03*
X1508959D03*
X1503020D03*
X1499922Y211240D03*
X1505378Y225502D03*
X1496720Y225292D03*
X1504484Y234562D03*
X1508410Y230842D03*
X1510017Y225516D03*
X1501840Y225502D03*
X1512420Y239116D03*
X1509571Y239053D03*
X1507860Y249792D03*
X1510810Y249742D03*
X1509040Y243362D03*
X1504890Y249862D03*
X1506600Y239092D03*
X1504650Y254392D03*
X1498984Y282797D03*
X1508558Y291175D03*
X1512244Y311522D03*
X1504602Y312867D03*
X1505922Y304583D03*
X1509539Y308467D03*
X1496200Y359522D03*
X1498184Y361723D03*
X1497880Y373062D03*
X1498184Y369798D03*
X1503450Y382693D03*
X1497770Y732502D03*
X1509638Y738627D03*
X1509350Y741315D03*
X1504747Y747293D03*
X1503514Y801361D03*
Y797961D03*
X1494840Y1300447D03*
X1504588Y1353316D03*
Y1355816D03*
X1505570Y1364212D03*
X1507704Y1361597D03*
X1510027Y1425825D03*
X1507617Y1424045D03*
X1518608Y49377D03*
X1522920Y113030D03*
Y116180D03*
X1513900Y117762D03*
X1518575Y138662D03*
X1526675Y140117D03*
X1526083Y146225D03*
X1524770Y195792D03*
X1521115Y193262D03*
X1521201Y215551D03*
X1524539D03*
X1522009Y210825D03*
X1518110Y215551D03*
X1526998Y209645D03*
X1527732Y219488D03*
X1514520Y231116D03*
X1526152Y225114D03*
X1513110Y247412D03*
X1514593Y249698D03*
X1513759Y263676D03*
X1519758Y265161D03*
X1522786Y262558D03*
X1522258Y265161D03*
X1516683Y278437D03*
X1519833Y277297D03*
X1511624Y291175D03*
X1517669Y291516D03*
X1522883Y305187D03*
X1519336Y303426D03*
X1520094Y306543D03*
X1514369Y308467D03*
X1526216Y306909D03*
X1524505Y748912D03*
X1515940Y795815D03*
Y799215D03*
X1522066Y1312808D03*
X1526066D03*
X1518066D03*
X1515066D03*
X1511066D03*
X1510738Y1345539D03*
Y1342432D03*
X1518538Y1345539D03*
Y1342432D03*
X1515938Y1345539D03*
Y1342432D03*
X1513338Y1345539D03*
Y1342432D03*
X1521138D03*
X1524338D03*
X1518738Y1348646D03*
X1516138D03*
X1514878Y1365553D03*
X1510878Y1364815D03*
X1519088Y1367043D03*
X1517616Y1364585D03*
X1510878Y1367871D03*
X1512177Y1427795D03*
X1516137Y1432135D03*
X1513657Y1429985D03*
X1511866Y1737108D03*
X1529002Y32290D03*
X1544010Y27552D03*
X1536310Y47492D03*
X1534818Y66801D03*
Y71793D03*
X1539774Y66801D03*
Y71793D03*
X1541774Y69297D03*
X1532818D03*
X1534774Y103093D03*
X1529818D03*
X1534060Y100162D03*
X1530660D03*
X1533520Y110662D03*
X1535320Y113062D03*
X1529500Y122122D03*
X1535575Y118862D03*
X1529500Y129602D03*
X1540090Y122782D03*
X1536925Y129937D03*
X1529500Y125862D03*
X1529233Y153162D03*
X1535450Y155262D03*
X1542401Y141561D03*
X1545447Y156035D03*
X1531750Y199762D03*
X1537262Y197834D03*
X1534720Y199803D03*
X1528720Y199862D03*
X1533385Y193108D03*
X1529610Y211614D03*
X1533148D03*
X1531824Y207677D03*
X1534194Y217519D03*
X1532590Y225432D03*
X1529670Y225522D03*
X1535561Y225393D03*
X1531110Y264862D03*
X1539150Y267132D03*
X1528716Y306909D03*
X1533716D03*
X1536216D03*
X1534899Y310447D03*
X1540937Y576522D03*
X1536527Y589012D03*
X1539720Y589862D03*
Y581862D03*
X1540989Y616587D03*
X1540377Y634165D03*
X1535052Y1325904D03*
X1532552Y1334504D03*
X1535052D03*
X1529952D03*
X1532552Y1339704D03*
X1529952D03*
X1537652Y1325904D03*
Y1334504D03*
X1532552Y1337104D03*
X1529952D03*
X1538510Y1346392D03*
X1531302Y1342204D03*
X1535892Y1346354D03*
Y1343754D03*
X1527282Y1345555D03*
Y1342448D03*
X1538757Y1356355D03*
X1527182Y1348651D03*
X1538757Y1360855D03*
Y1365355D03*
X1531866Y1737108D03*
X1547768Y3010D03*
X1555635Y16999D03*
Y21991D03*
X1553635Y19495D03*
X1556413D03*
X1553486Y23935D03*
X1548530D03*
X1546530Y25931D03*
X1555486D03*
X1547429Y28406D03*
Y37106D03*
X1554515Y28406D03*
Y37106D03*
X1549308Y26431D03*
X1552708D03*
X1554515Y40020D03*
Y48720D03*
X1547429Y40020D03*
Y48720D03*
X1554818Y69297D03*
X1556818Y66801D03*
Y71793D03*
X1543818Y75297D03*
X1552774D03*
X1550774Y77793D03*
Y72801D03*
X1545818Y77793D03*
Y72801D03*
X1554239Y138263D03*
X1552960Y124359D03*
X1553189Y127781D03*
X1556049Y147711D03*
X1545763Y159305D03*
X1554723Y200375D03*
X1557560Y196912D03*
X1551160Y189342D03*
X1557900Y220362D03*
X1557760Y214792D03*
X1550353Y217352D03*
X1554723Y224529D03*
X1559400Y229832D03*
X1554723Y248945D03*
X1559387Y589340D03*
X1547312Y579080D03*
X1543720Y581862D03*
X1548720D03*
X1552720Y589862D03*
Y581862D03*
X1554727Y631527D03*
X1554753Y628860D03*
X1553312Y636815D03*
X1559354Y655716D03*
Y659116D03*
X1550417Y677045D03*
X1550487Y681565D03*
X1550057Y693485D03*
X1548479Y706088D03*
X1550320Y696562D03*
X1550917Y704332D03*
X1550390Y709885D03*
X1551866Y1737108D03*
X1567768Y3010D03*
X1560591Y16999D03*
Y21991D03*
X1569808Y16999D03*
Y21991D03*
X1574764Y16999D03*
Y21991D03*
X1562591Y19495D03*
X1567808D03*
X1570586D03*
X1573986D03*
X1559813D03*
X1567659Y23935D03*
X1562703D03*
X1560703Y25931D03*
X1569659D03*
X1574876D03*
X1561602Y28406D03*
Y37106D03*
X1568688Y28406D03*
Y37106D03*
X1563481Y26431D03*
X1566881D03*
X1568688Y40020D03*
Y48720D03*
X1561602Y40020D03*
Y48720D03*
X1563774Y69297D03*
X1561774Y66801D03*
Y71793D03*
X1565818Y75297D03*
X1574774D03*
X1572774Y77793D03*
Y72801D03*
X1567818Y77793D03*
Y72801D03*
X1559860Y240002D03*
X1573560Y245078D03*
X1574760Y251032D03*
X1559722Y243110D03*
X1575169Y303929D03*
X1573246Y306650D03*
X1572396Y309450D03*
X1563714Y572792D03*
X1567114D03*
X1561494Y584292D03*
X1559557Y593290D03*
X1560717Y648522D03*
X1564690Y663302D03*
X1564768Y708159D03*
X1570720Y729362D03*
X1562871Y732316D03*
Y735716D03*
X1571577Y747145D03*
X1567547Y755485D03*
X1571920Y762662D03*
X1568490Y758162D03*
X1570374Y760093D03*
X1587768Y3010D03*
X1583981Y16999D03*
Y21991D03*
X1588937Y16999D03*
Y21991D03*
X1576764Y19495D03*
X1581981D03*
X1590937D03*
X1584759D03*
X1588159D03*
X1576876Y23935D03*
X1581832D03*
X1591050D03*
X1583832Y25931D03*
X1589050D03*
X1575775Y28406D03*
Y37106D03*
X1582862Y28406D03*
Y37106D03*
X1589948Y28406D03*
Y37106D03*
X1577654Y26431D03*
X1591828D03*
X1581054D03*
X1589948Y40020D03*
Y48720D03*
X1582862Y40020D03*
Y48720D03*
X1575775Y40020D03*
Y48720D03*
X1576818Y69297D03*
X1585774D03*
X1578818Y66801D03*
Y71793D03*
X1583774Y66801D03*
Y71793D03*
X1587818Y75297D03*
X1589818Y77793D03*
Y72801D03*
X1576589Y300927D03*
X1590915Y755793D03*
X1591866Y1737108D03*
X1607768Y3010D03*
X1598155Y16999D03*
Y21991D03*
X1603111Y16999D03*
Y21991D03*
X1596155Y19495D03*
X1605111D03*
X1598933D03*
X1602333D03*
X1596006Y23935D03*
X1598006Y25931D03*
X1597035Y28406D03*
Y37106D03*
X1604122Y28406D03*
Y37106D03*
X1595228Y26431D03*
X1604122Y40020D03*
Y48720D03*
X1597035Y40020D03*
Y48720D03*
X1598818Y69297D03*
X1607774D03*
X1600818Y66801D03*
Y71793D03*
X1605774Y66801D03*
Y71793D03*
X1596774Y75297D03*
X1594774Y77793D03*
Y72801D03*
X1603778Y189943D03*
X1603726Y198061D03*
X1603747Y192951D03*
X1603530Y202402D03*
X1596444Y215526D03*
X1603580Y206902D03*
X1604200Y234642D03*
X1604240Y227892D03*
X1603920Y222922D03*
X1604040Y219692D03*
X1598030Y251002D03*
X1604290Y242472D03*
X1604240Y238242D03*
X1602980Y560002D03*
X1607200Y583962D03*
X1598440Y736692D03*
X1592760Y736652D03*
X1595600D03*
X1606788Y756199D03*
X1602788D03*
X1606980Y1449922D03*
X1621920Y25962D03*
X1622220Y49862D03*
X1620818Y69297D03*
X1622818Y66801D03*
Y71793D03*
X1609818Y75297D03*
X1618774D03*
X1616774Y77793D03*
Y72801D03*
X1611818Y77793D03*
Y72801D03*
X1623881Y117627D03*
Y129627D03*
X1615800Y584062D03*
X1612980Y623762D03*
Y626362D03*
X1615580Y650092D03*
Y657762D03*
X1612980D03*
Y650092D03*
X1615580Y660362D03*
X1612980D03*
X1615580Y684092D03*
X1612980D03*
X1615580Y694362D03*
X1612980D03*
X1615580Y691762D03*
X1612980D03*
Y718092D03*
X1615580D03*
X1610100Y725152D03*
X1610788Y756199D03*
X1614788D03*
X1618788D03*
X1614116Y1411169D03*
X1623448Y1420028D03*
Y1417428D03*
Y1414828D03*
Y1412228D03*
X1612630Y1418842D03*
X1615062Y1421241D03*
X1613047Y1415669D03*
X1615597Y1433669D03*
X1614927Y1426076D03*
Y1429896D03*
X1624353Y1428766D03*
Y1431316D03*
X1617215Y1440822D03*
X1611866Y1737108D03*
X1634021Y16999D03*
Y21991D03*
X1638977Y16999D03*
Y21991D03*
X1632021Y19495D03*
X1634799D03*
X1638199D03*
X1631872Y23935D03*
X1626916D03*
X1624916Y25931D03*
X1633872D03*
X1639089D03*
X1625814Y28406D03*
Y37106D03*
X1632901Y28406D03*
Y37106D03*
X1639988Y28406D03*
Y37106D03*
X1627694Y26431D03*
X1631094D03*
X1625814Y40020D03*
Y48720D03*
X1632901Y40020D03*
Y48720D03*
X1639988Y40020D03*
Y48720D03*
X1629774Y69297D03*
X1627774Y66801D03*
Y71793D03*
X1633022Y75297D03*
X1635022Y77793D03*
X1639978D03*
Y72801D03*
X1635022D03*
X1636393Y181778D03*
X1635032Y196188D03*
X1632899Y213012D03*
X1633111Y206693D03*
X1632342Y216015D03*
X1635835Y343002D03*
X1642135Y414202D03*
X1636800Y429982D03*
X1639800D03*
X1636800Y426982D03*
X1639800D03*
X1636800Y438982D03*
X1639800D03*
X1636800Y435982D03*
X1639800D03*
X1636800Y432982D03*
X1639800D03*
X1638928Y756199D03*
X1630928D03*
X1634928D03*
X1638277Y1269065D03*
X1640812Y1270020D03*
X1637183Y1394411D03*
X1639683D03*
X1629262Y1394418D03*
X1634683Y1394411D03*
X1625948Y1417428D03*
Y1412228D03*
X1633103Y1417907D03*
X1630503D03*
X1635703D03*
X1633103Y1421014D03*
X1630503D03*
X1635703D03*
X1638303Y1417907D03*
Y1421014D03*
X1625948Y1414828D03*
Y1420028D03*
X1635903Y1424121D03*
X1638503D03*
X1632516Y1427753D03*
Y1433353D03*
X1634986Y1427753D03*
Y1433353D03*
X1637416Y1427753D03*
Y1433353D03*
X1630643Y1440290D03*
X1627469Y1437072D03*
X1627591Y1447796D03*
X1637478Y1445150D03*
X1624853Y1440875D03*
X1634643Y1442982D03*
X1638785Y1442483D03*
X1637042Y1440215D03*
X1630643Y1443090D03*
X1631866Y1737108D03*
X1648194Y16999D03*
Y21991D03*
X1653150Y16999D03*
Y21991D03*
X1640977Y19495D03*
X1646194D03*
X1655150D03*
X1648972D03*
X1652372D03*
X1641089Y23935D03*
X1646045D03*
X1648045Y25931D03*
X1654161Y28406D03*
Y37106D03*
X1647074Y28406D03*
Y37106D03*
X1641867Y26431D03*
X1645267D03*
X1647074Y40020D03*
Y48720D03*
X1654161Y40020D03*
Y48720D03*
X1644022Y69297D03*
X1652978D03*
X1646022Y66801D03*
Y71793D03*
X1650978Y66801D03*
Y71793D03*
X1655022Y75297D03*
X1641978D03*
X1657022Y77793D03*
Y72801D03*
X1652610Y394727D03*
X1652810Y407402D03*
X1650020Y408952D03*
X1647310Y408922D03*
X1650020Y411452D03*
X1647310Y411422D03*
X1647110Y434177D03*
X1654110D03*
X1652113Y527325D03*
X1652138Y524071D03*
X1651890Y520540D03*
X1657755Y517910D03*
X1651931Y540071D03*
Y536071D03*
X1649291Y556057D03*
X1651112Y545572D03*
X1645530Y549160D03*
X1653230Y549322D03*
X1642720Y560862D03*
X1656238Y592113D03*
X1649833Y594946D03*
X1653794Y594956D03*
X1653774Y598576D03*
X1649844Y598555D03*
X1656955Y611090D03*
X1645300Y612202D03*
X1653220Y620662D03*
X1645681Y624011D03*
X1648581D03*
X1651481D03*
X1654809Y638101D03*
X1653319Y642311D03*
X1652351Y639573D03*
X1648811Y628277D03*
X1647081Y626211D03*
X1645917Y628917D03*
Y633577D03*
X1645167Y631247D03*
Y635907D03*
X1650081Y626111D03*
X1651711Y628277D03*
X1651635Y651836D03*
X1652581Y646311D03*
X1643582Y652601D03*
X1655637Y646311D03*
X1641082Y652601D03*
X1649363Y649485D03*
X1654809Y672101D03*
X1652351Y673573D03*
X1645681Y658011D03*
X1648581D03*
X1648811Y662277D03*
X1647081Y660211D03*
X1645917Y662917D03*
Y667577D03*
X1645167Y665247D03*
Y669907D03*
X1650081Y660111D03*
X1651481Y658011D03*
X1651711Y662277D03*
X1641082Y686601D03*
X1651635Y685836D03*
X1652581Y680311D03*
X1653319Y676311D03*
X1643582Y686601D03*
X1655113Y680835D03*
X1649363Y683485D03*
X1654809Y706101D03*
X1648811Y696277D03*
X1645167Y703907D03*
X1645917Y701577D03*
X1645167Y699247D03*
X1645917Y696917D03*
X1650081Y694111D03*
X1645681Y692011D03*
X1647081Y694211D03*
X1648581Y692011D03*
X1651711Y696277D03*
X1651481Y692011D03*
X1641082Y720601D03*
X1651635Y719836D03*
X1652581Y714311D03*
X1653319Y710311D03*
X1652351Y707573D03*
X1643582Y720601D03*
X1655637Y714311D03*
X1649363Y717485D03*
X1651509Y756492D03*
X1656188Y1394736D03*
X1647592Y1394418D03*
X1655779Y1417618D03*
Y1412418D03*
Y1415018D03*
X1644103Y1417907D03*
X1647047Y1417923D03*
Y1421030D03*
X1653279Y1412418D03*
X1650679D03*
X1653279Y1415018D03*
X1650679D03*
X1653168Y1417618D03*
X1650557D03*
X1640903Y1417907D03*
X1647016Y1424153D03*
X1641047Y1432876D03*
X1645707D03*
X1643377Y1433626D03*
X1648037D03*
X1655762Y1429794D03*
X1648677Y1436220D03*
X1653243Y1435690D03*
X1651043Y1434190D03*
X1653243Y1432790D03*
X1651143Y1437190D03*
X1653243Y1438590D03*
X1648677Y1439120D03*
X1655295Y1453879D03*
X1652295D03*
X1655295Y1456899D03*
X1652295D03*
X1648947Y1476695D03*
X1646958Y1501553D03*
X1651866Y1737108D03*
X1671050Y23935D03*
X1669050Y25931D03*
X1669948Y28406D03*
Y37106D03*
X1671828Y26431D03*
X1669948Y40020D03*
Y48720D03*
X1666022Y69297D03*
X1668022Y66801D03*
Y71793D03*
X1672978Y66801D03*
Y71793D03*
X1663978Y75297D03*
X1661978Y77793D03*
Y72801D03*
X1668100Y180852D03*
X1668030Y200580D03*
X1667739Y187187D03*
X1666690Y193290D03*
X1674432Y216981D03*
X1672596Y220541D03*
X1666074Y229710D03*
X1660176Y231100D03*
X1670400Y229462D03*
X1668426Y222432D03*
X1664866Y225162D03*
X1660861Y227548D03*
X1659610Y394727D03*
X1663610D03*
X1661110Y434177D03*
X1664970Y472112D03*
X1662447Y480619D03*
X1663376Y515531D03*
X1667376D03*
X1665790Y523417D03*
X1670004Y537065D03*
Y543065D03*
Y531065D03*
X1662262Y537334D03*
X1659740Y542222D03*
X1661872Y534703D03*
X1660243Y532071D03*
X1660866Y546749D03*
X1668917Y549992D03*
X1666902Y555115D03*
X1663502D03*
X1664040Y569642D03*
X1668040D03*
X1672040D03*
X1665700Y583462D03*
X1661510Y583442D03*
X1672770Y580512D03*
X1669770D03*
X1658738Y592113D03*
X1661238D03*
X1664997Y604762D03*
X1662120Y604782D03*
X1664197Y602191D03*
X1669222Y604490D03*
X1670700Y594562D03*
X1672500Y596462D03*
X1660660Y602273D03*
X1657220Y620662D03*
X1663720Y620434D03*
X1664410Y617953D03*
X1668920Y617637D03*
X1660754Y609837D03*
X1669397Y614064D03*
X1663471Y609837D03*
X1659458Y637149D03*
X1658085Y639511D03*
X1659914Y649681D03*
X1666686Y757162D03*
X1673226Y1394411D03*
X1667405Y1394418D03*
X1659260Y1394693D03*
X1658390Y1420218D03*
Y1415018D03*
Y1412418D03*
Y1417618D03*
X1663590Y1420218D03*
X1660990D03*
Y1415018D03*
Y1417618D03*
Y1412418D03*
X1663590Y1415018D03*
Y1417618D03*
Y1412418D03*
X1668646Y1417907D03*
Y1421014D03*
X1671246Y1417907D03*
Y1421014D03*
X1670659Y1427753D03*
X1673129D03*
X1670659Y1433353D03*
X1673129D03*
X1657438Y1438156D03*
X1662496Y1428791D03*
Y1431291D03*
X1665612Y1437072D03*
X1660428Y1447566D03*
X1667577Y1447545D03*
X1662996Y1440922D03*
X1672786Y1442982D03*
X1668786Y1440290D03*
Y1443256D03*
X1657920Y1453405D03*
X1660920D03*
X1657860Y1466545D03*
Y1464045D03*
X1657950Y1456210D03*
X1657860Y1459045D03*
Y1461545D03*
X1660950Y1456210D03*
X1660860Y1466545D03*
Y1464045D03*
Y1459045D03*
Y1461545D03*
X1666123Y1497362D03*
Y1493362D03*
Y1501362D03*
X1665940Y1512862D03*
X1666110Y1504662D03*
X1666123Y1524862D03*
Y1537862D03*
Y1533862D03*
Y1520862D03*
Y1541862D03*
Y1553557D03*
Y1545862D03*
X1671673Y1550815D03*
X1666198Y1565557D03*
X1666123Y1557557D03*
X1666198Y1561557D03*
X1671660Y1569412D03*
X1666198Y1585321D03*
Y1581321D03*
X1671866Y1737108D03*
X1678155Y16999D03*
Y21991D03*
X1683111Y16999D03*
Y21991D03*
X1676155Y19495D03*
X1685111D03*
X1678933D03*
X1682333D03*
X1676006Y23935D03*
X1685223D03*
X1678006Y25931D03*
X1683223D03*
X1677035Y28406D03*
Y37106D03*
X1684122Y28406D03*
Y37106D03*
X1686001Y26431D03*
X1689401D03*
X1675228D03*
X1677035Y40020D03*
Y48720D03*
X1684122Y40020D03*
Y48720D03*
X1688156Y69297D03*
X1674978D03*
X1677156Y75297D03*
X1686112D03*
X1684112Y77793D03*
Y72801D03*
X1679156Y77793D03*
Y72801D03*
X1678994Y217231D03*
X1676300Y219762D03*
X1681900Y227962D03*
X1690208Y421855D03*
X1686154Y434160D03*
X1689095Y462640D03*
X1683394Y469878D03*
X1683476Y473378D03*
X1684356Y476290D03*
X1682810Y465940D03*
X1684940Y463030D03*
X1681602Y485180D03*
X1684356Y485628D03*
X1677464Y491790D03*
X1685779Y491230D03*
X1690229Y481845D03*
X1687238Y485496D03*
X1681817Y495290D03*
X1681612Y499290D03*
X1675664Y513802D03*
X1690999Y513107D03*
X1683702Y514687D03*
X1676600Y523902D03*
X1688768Y518107D03*
X1682004Y537065D03*
X1682180Y543065D03*
X1676004D03*
X1682004Y531065D03*
X1676004D03*
X1689544Y543874D03*
X1689506Y539882D03*
X1679941Y552222D03*
X1678860Y556752D03*
X1676040Y569627D03*
X1683369Y562698D03*
Y566098D03*
X1676644Y655345D03*
Y652745D03*
X1679244Y655345D03*
X1681864Y655286D03*
X1679244Y652745D03*
X1676624Y642404D03*
X1676644Y644945D03*
Y647545D03*
Y650145D03*
X1679244Y642345D03*
X1681864Y642286D03*
X1679244Y644945D03*
Y647545D03*
X1681864Y644886D03*
Y647486D03*
Y650086D03*
Y652686D03*
X1679244Y650145D03*
X1673860Y726522D03*
X1681810Y752955D03*
X1686135Y1394418D03*
X1675926Y1394411D03*
X1678426D03*
X1687860Y1415179D03*
X1689210Y1417679D03*
X1687860Y1412579D03*
X1685190Y1417923D03*
X1676446Y1417907D03*
X1679046D03*
X1682246D03*
X1676446Y1421014D03*
X1685190Y1421030D03*
X1673846Y1417907D03*
Y1421014D03*
X1676646Y1424121D03*
X1685159Y1424153D03*
X1675559Y1427753D03*
Y1433353D03*
X1674046Y1424121D03*
X1679190Y1432876D03*
X1683850D03*
X1681520Y1433626D03*
X1686180D03*
X1686820Y1436520D03*
X1688886Y1434790D03*
X1688986Y1437790D03*
X1675621Y1445150D03*
X1676928Y1442483D03*
X1675185Y1440215D03*
X1686820Y1439420D03*
X1680720Y1487062D03*
X1679508Y1503421D03*
Y1498303D03*
X1678340Y1500862D03*
X1679508Y1517803D03*
X1677930Y1520362D03*
X1679508Y1522921D03*
Y1543921D03*
Y1538803D03*
X1678340Y1541362D03*
X1679508Y1563380D03*
Y1583880D03*
X1678230Y1590542D03*
X1674220Y1585321D03*
X1692328Y16999D03*
Y21991D03*
X1697284Y16999D03*
Y21991D03*
X1690328Y19495D03*
X1699284D03*
X1696506D03*
X1693106D03*
X1703617Y26459D03*
X1700217D03*
X1690179Y23935D03*
X1692179Y25931D03*
X1691208Y28406D03*
Y37106D03*
X1698295Y28406D03*
Y37106D03*
X1705381Y28406D03*
Y37106D03*
X1703570Y50649D03*
X1700170D03*
X1698295Y48720D03*
X1697824Y39974D03*
X1691208Y40020D03*
Y48720D03*
X1705381D03*
X1697112Y69297D03*
X1690156Y66801D03*
Y71793D03*
X1695112Y66801D03*
Y71793D03*
X1699156Y75297D03*
X1701156Y77793D03*
Y72801D03*
X1695950Y96437D03*
X1697725Y205120D03*
X1702490Y204780D03*
X1704223Y209707D03*
Y212207D03*
X1701164Y209758D03*
X1698566Y214904D03*
X1696066D03*
X1693725Y217409D03*
X1698566Y212404D03*
X1696066D03*
X1698725Y217409D03*
X1696225D03*
X1701164Y212258D03*
X1704264Y217458D03*
X1701264D03*
X1704264Y214958D03*
X1701264D03*
X1698566Y209704D03*
X1696066D03*
X1693466Y209504D03*
Y214704D03*
Y212204D03*
X1693987Y230174D03*
Y233174D03*
X1703487Y232174D03*
X1693725Y219909D03*
X1698725D03*
X1696225D03*
X1704264Y219958D03*
X1701264D03*
X1704185Y222710D03*
X1698220Y369652D03*
X1704444Y407045D03*
X1699809Y403985D03*
X1695579D03*
X1702959Y404243D03*
X1707780Y410738D03*
X1697161Y406602D03*
X1692429Y403985D03*
X1697914Y427155D03*
X1698014Y424055D03*
X1701124Y423802D03*
X1694050Y416643D03*
X1695455Y422287D03*
X1707544Y431745D03*
X1707568Y420370D03*
X1701124Y433650D03*
X1697214Y433655D03*
X1704624Y433650D03*
X1690140Y434160D03*
X1700846Y455894D03*
X1697648Y463724D03*
X1693720Y455862D03*
X1697220D03*
X1693648Y463724D03*
X1702760Y478207D03*
X1696760D03*
X1702127Y468719D03*
X1693236Y472650D03*
X1702760Y490207D03*
X1696760D03*
Y484207D03*
X1691151Y493678D03*
X1689943Y479304D03*
X1696120Y506937D03*
X1703720Y509362D03*
X1701811Y501318D03*
X1701635Y497177D03*
X1699300Y498632D03*
X1697210Y500802D03*
X1694050Y501422D03*
X1693711Y498527D03*
X1691129Y501697D03*
X1707200Y498962D03*
X1699553Y513107D03*
X1707552Y506731D03*
X1707716Y513562D03*
X1702930Y526102D03*
X1699265Y525507D03*
X1696851Y515607D03*
X1693701D03*
X1699265Y521507D03*
X1690999Y525507D03*
X1701726Y518107D03*
X1699291Y537507D03*
X1699251Y529507D03*
X1699666Y541507D03*
X1699251Y533642D03*
X1691104Y530503D03*
X1691445Y535011D03*
X1704886Y534564D03*
X1689769Y537339D03*
X1699107Y555783D03*
X1699297Y549507D03*
X1702270Y552742D03*
X1703306Y550064D03*
X1698048Y705662D03*
X1701320Y705678D03*
X1698020Y702962D03*
X1696402Y709533D03*
X1699110Y727452D03*
X1705035Y729210D03*
X1704973Y753019D03*
X1703310Y749455D03*
X1690620Y760702D03*
X1691412Y1372492D03*
Y1367492D03*
Y1369992D03*
Y1377492D03*
Y1374992D03*
Y1382492D03*
Y1379992D03*
X1690809Y1393970D03*
X1699150Y1393613D03*
X1690460Y1415179D03*
Y1412579D03*
X1691918Y1417676D03*
X1692960Y1415179D03*
Y1412579D03*
X1693404Y1421939D03*
X1699593Y1428384D03*
X1697820Y1423616D03*
X1699545Y1425868D03*
X1699437Y1431295D03*
X1691086Y1436290D03*
Y1433390D03*
X1693392Y1429808D03*
X1699457Y1439185D03*
Y1447805D03*
X1691086Y1439190D03*
X1691988Y1498303D03*
X1704723Y1500862D03*
X1691988Y1517803D03*
X1704723Y1520362D03*
X1691988Y1538803D03*
X1704723Y1541362D03*
X1691988Y1558262D03*
X1705003Y1564057D03*
X1705723Y1583821D03*
X1691866Y1737108D03*
X1707220Y15662D03*
X1715210Y18282D03*
X1714589Y21562D03*
X1714520Y37162D03*
X1709589Y26062D03*
X1719589Y25862D03*
X1717089D03*
X1710106Y48720D03*
Y40020D03*
X1720895Y68062D03*
X1716875D03*
X1710920Y82162D03*
X1708112Y75297D03*
X1706112Y77793D03*
Y72801D03*
X1708000Y99122D03*
X1712520Y117862D03*
X1712720Y111862D03*
X1719943Y112667D03*
Y116667D03*
X1713418Y130862D03*
X1721418Y135327D03*
X1717418D03*
X1714180Y154790D03*
X1717140Y148910D03*
X1711700Y140200D03*
X1717619Y165909D03*
X1719530Y162950D03*
X1717280Y174970D03*
X1722078Y189483D03*
X1720310Y191252D03*
X1707159Y217580D03*
Y215080D03*
Y210080D03*
Y222580D03*
Y225080D03*
Y220080D03*
X1721400Y374462D03*
X1713720Y381152D03*
X1717220D03*
X1719200Y371162D03*
X1713720Y391652D03*
Y384652D03*
Y388152D03*
X1717220Y391652D03*
Y388152D03*
Y384652D03*
X1707444Y407045D03*
X1709000Y413362D03*
X1706500D03*
X1711144Y425945D03*
X1709000Y415862D03*
X1706500D03*
X1721220Y458362D03*
X1713977Y457137D03*
X1708977Y458542D03*
X1711477Y465229D03*
Y468379D03*
X1708760Y478031D03*
X1721936Y469263D03*
X1716134Y478443D03*
X1715711Y474399D03*
X1713977Y470804D03*
X1708977D03*
X1708760Y490207D03*
Y484207D03*
X1716148Y483720D03*
X1716087Y495665D03*
X1716156Y487685D03*
X1716278Y491676D03*
X1707552Y503331D03*
X1709844Y516106D03*
X1710500Y538162D03*
X1707610Y534113D03*
X1709356Y541144D03*
X1709680Y545432D03*
X1716110Y532632D03*
X1707346Y547504D03*
X1717987Y569705D03*
X1709027Y655141D03*
X1716480Y691410D03*
X1710550Y691327D03*
X1712824Y696476D03*
X1710122Y703509D03*
X1713920Y700962D03*
X1709828Y719283D03*
X1713450Y728222D03*
X1719727Y1472088D03*
X1718149Y1496270D03*
X1717149Y1505895D03*
X1720174D03*
X1717988Y1520951D03*
X1711988D03*
X1717149Y1513945D03*
X1720174D03*
X1714988Y1520951D03*
X1708988D03*
X1717988Y1530445D03*
X1714988D03*
X1708988D03*
X1711988D03*
X1711866Y1737108D03*
X1727768Y3010D03*
X1732320Y28162D03*
X1728820D03*
X1725320D03*
X1726720Y49862D03*
X1733720D03*
X1730220D03*
X1736040Y41792D03*
X1732810Y52482D03*
X1736040Y44292D03*
X1730140Y52552D03*
X1727600Y52582D03*
X1729520Y61762D03*
X1729620Y57262D03*
X1725320Y67962D03*
X1730820Y76362D03*
X1726918Y101967D03*
X1738220Y98862D03*
X1736720Y101862D03*
X1729080Y118132D03*
X1739720Y120892D03*
X1728999Y112895D03*
X1733378Y134907D03*
X1736508D03*
X1730765Y151362D03*
X1733920D03*
X1723670Y149102D03*
X1728320Y169862D03*
X1723240Y185200D03*
X1737704Y183139D03*
X1737470Y177147D03*
X1738200Y193862D03*
X1725344Y359334D03*
X1737260Y368132D03*
X1732660Y372692D03*
X1725400Y372062D03*
X1728300Y377787D03*
X1725500Y383662D03*
X1733780Y390620D03*
X1729810D03*
X1737660D03*
X1737434Y398990D03*
X1727760Y420415D03*
X1734290Y423820D03*
X1727700Y417265D03*
X1739316Y480939D03*
X1725473Y474859D03*
X1730954Y478062D03*
X1725522Y482869D03*
X1733354Y490869D03*
Y486869D03*
X1724431Y1336311D03*
X1734717Y1404340D03*
X1729700Y1462932D03*
X1733200D03*
X1736700D03*
X1736400Y1458942D03*
Y1455442D03*
X1731600Y1457230D03*
X1726120Y1490262D03*
X1726149Y1496270D03*
X1724649Y1513945D03*
X1727674D03*
X1729310Y1520951D03*
X1735310D03*
X1724649Y1505895D03*
X1727674D03*
X1726310Y1530445D03*
X1732310D03*
X1729310D03*
X1735310D03*
X1726310Y1520951D03*
X1732310D03*
X1731866Y1737108D03*
X1747768Y3010D03*
X1754090Y16302D03*
X1753388Y28360D03*
X1748400Y37262D03*
X1751065Y39017D03*
X1754620Y39062D03*
X1747720Y31862D03*
Y34362D03*
X1753398Y48720D03*
X1740858Y72330D03*
Y79830D03*
Y74830D03*
Y82330D03*
X1754398Y100307D03*
X1745220Y98862D03*
X1741720D03*
X1743720Y101862D03*
X1740220D03*
X1748720Y97362D03*
X1745485Y119539D03*
X1745010Y122952D03*
X1750820Y119972D03*
X1747482Y121367D03*
X1741222Y151527D03*
X1738520Y151362D03*
X1751220Y147562D03*
X1748465D03*
X1747591Y171733D03*
X1754120Y171562D03*
X1750920Y171662D03*
X1751084Y190928D03*
X1752200Y197762D03*
X1748500Y193862D03*
X1745500D03*
X1741200D03*
X1754234Y190836D03*
X1754307Y262186D03*
X1751068Y262123D03*
X1754245Y269724D03*
X1751068Y266048D03*
X1754307Y266111D03*
X1754414Y275329D03*
X1752165Y273901D03*
X1749565D03*
X1751006Y269661D03*
X1749595Y276711D03*
X1752195D03*
X1746484Y279682D03*
X1745000Y299862D03*
X1756204Y301695D03*
X1752000Y306562D03*
X1748989Y380206D03*
X1756933Y372452D03*
X1744380Y382892D03*
X1744510Y377452D03*
X1747080Y435870D03*
X1746720Y464862D03*
X1740831Y489362D03*
X1740886Y493960D03*
X1752316Y703969D03*
Y695669D03*
X1752217Y692988D03*
X1752276Y720529D03*
X1752316Y712269D03*
X1746970Y1451872D03*
X1738740Y1451742D03*
X1750970Y1459172D03*
Y1456172D03*
X1740200Y1462932D03*
X1745111Y1463262D03*
X1747677Y1507388D03*
X1744677D03*
X1747304Y1524976D03*
X1744304D03*
X1751866Y1737108D03*
X1767768Y3010D03*
X1762420Y21562D03*
X1765238Y22062D03*
X1768026Y24165D03*
X1769669Y15244D03*
X1761998Y15187D03*
X1765260Y18262D03*
X1757320Y15872D03*
X1758672Y26431D03*
X1755272D03*
X1760475Y28360D03*
X1769900Y37732D03*
X1767220Y26962D03*
X1758669Y50649D03*
X1755269D03*
X1760485Y48720D03*
X1762738Y53262D03*
X1767220Y53342D03*
X1767185Y48817D03*
X1767400Y39915D03*
X1769274Y50742D03*
X1771774Y53682D03*
X1759700Y57662D03*
X1764400Y57462D03*
X1758063Y68637D03*
X1758573Y87107D03*
Y83607D03*
X1768168Y80497D03*
X1758568Y79697D03*
X1765068Y80397D03*
X1767170Y83607D03*
X1767990Y76797D03*
X1760478Y90027D03*
X1770368Y72691D03*
X1766278Y93627D03*
X1764678Y122927D03*
X1758300Y128242D03*
X1768483Y166260D03*
X1765870Y179392D03*
X1765820Y182282D03*
X1767300Y174587D03*
X1766880Y234842D03*
Y231842D03*
X1758500Y231822D03*
Y234822D03*
X1755378Y233528D03*
X1763731Y283817D03*
X1766725Y282981D03*
X1763731Y279517D03*
X1760398Y279548D03*
X1766765Y279433D03*
X1757439Y279611D03*
X1760398Y283848D03*
X1759509Y292434D03*
X1762549Y286704D03*
X1757439Y283911D03*
X1768045Y295238D03*
X1765053Y295188D03*
X1762285Y295137D03*
X1759629Y295164D03*
X1767309Y290994D03*
X1763045Y289691D03*
X1759529Y289864D03*
X1766655Y286531D03*
X1760104Y301648D03*
X1767455Y302651D03*
X1764955Y301951D03*
X1758563Y310478D03*
X1754963D03*
X1769230D03*
X1770520Y364148D03*
X1756800Y364048D03*
X1770520Y368148D03*
X1768757Y380498D03*
X1756800Y368048D03*
X1770280Y372452D03*
X1770220Y377452D03*
Y382952D03*
X1757066Y435721D03*
X1767300Y461393D03*
X1765670Y458012D03*
X1757650Y461393D03*
X1767300Y465893D03*
X1768560Y539042D03*
X1766060D03*
X1768317Y686375D03*
X1764112Y703948D03*
X1761612D03*
X1764112Y695648D03*
X1763570Y693192D03*
X1761612Y695648D03*
X1755112Y703948D03*
Y695648D03*
X1755013Y692967D03*
X1757612Y703948D03*
Y695648D03*
X1764072Y720508D03*
X1761572D03*
X1764112Y712248D03*
X1761612D03*
X1755072Y720508D03*
X1755112Y712248D03*
X1757572Y720508D03*
X1757612Y712248D03*
X1758352Y1317368D03*
Y1322168D03*
X1760160Y1476032D03*
X1763730Y1483712D03*
Y1480712D03*
X1763830Y1490782D03*
Y1487782D03*
X1782305Y13647D03*
X1775556Y21471D03*
X1775830Y26522D03*
X1777754Y37746D03*
X1781774Y54462D03*
X1774274Y50742D03*
X1776710Y53562D03*
X1779411Y50692D03*
X1774328Y60087D03*
X1779778Y70027D03*
X1774328Y62987D03*
X1775580Y73330D03*
X1785178Y86927D03*
X1779778Y72927D03*
X1787790Y85132D03*
X1781485Y88192D03*
X1785142Y76032D03*
X1773611Y88293D03*
X1785178Y89927D03*
X1782000Y128455D03*
X1771915Y128393D03*
X1782000Y125955D03*
Y123455D03*
X1771915Y125893D03*
Y123393D03*
X1784238Y150744D03*
X1780320Y153162D03*
X1774950Y167392D03*
X1779500Y171692D03*
X1780320Y177602D03*
X1777520Y178403D03*
Y173903D03*
X1782600Y175932D03*
X1783878Y216928D03*
X1786690Y234782D03*
Y231782D03*
X1783800Y231762D03*
Y234762D03*
X1775140Y234792D03*
Y231792D03*
X1783878Y224428D03*
Y226928D03*
Y219428D03*
Y221928D03*
X1779226Y275604D03*
X1783563Y273471D03*
X1786089D03*
X1771029Y295164D03*
X1771229Y291064D03*
X1786089Y287641D03*
X1783563D03*
X1777354Y295489D03*
X1772863Y310478D03*
X1783018Y301729D03*
X1782324Y410432D03*
Y403932D03*
Y425432D03*
Y418932D03*
X1782420Y443987D03*
X1773870Y438222D03*
X1782420Y447137D03*
X1781470Y452065D03*
X1776160Y592792D03*
X1778310Y591152D03*
X1781720Y592742D03*
X1771866Y1737108D03*
X1787768Y3010D03*
X1793061Y24659D03*
X1794910Y44573D03*
X1799920Y52594D03*
X1788238Y82292D03*
Y78062D03*
Y74912D03*
X1797324Y161465D03*
X1803215Y154032D03*
X1797663Y269571D03*
X1800189D03*
X1790563Y273471D03*
X1793089D03*
X1793269Y287641D03*
X1790743D03*
X1791619Y294441D03*
X1789093D03*
X1802763Y308671D03*
X1795763D03*
X1798289D03*
X1788763D03*
X1791289D03*
X1803129Y362293D03*
X1800160Y362542D03*
X1800340Y387062D03*
X1802929Y385293D03*
X1791494Y386536D03*
X1795479Y408056D03*
X1792450Y410615D03*
X1792507Y403932D03*
X1795468Y421334D03*
X1792220Y425432D03*
X1792335Y418775D03*
X1796020Y451162D03*
X1791888Y683805D03*
X1800107Y1256426D03*
X1795484Y1496401D03*
X1800450Y1505230D03*
X1792645Y1511423D03*
X1798450Y1524830D03*
X1801450D03*
Y1527830D03*
X1795561Y1524729D03*
X1814322Y49388D03*
X1807549Y56415D03*
X1807580Y59397D03*
X1806920Y150862D03*
X1808910Y143902D03*
X1813335Y155435D03*
X1810835Y163986D03*
X1806365Y154032D03*
X1819939Y177243D03*
X1813325Y177257D03*
X1807220Y179897D03*
X1814349Y269634D03*
X1811823D03*
X1807249D03*
X1804723D03*
X1812349Y308734D03*
X1809823D03*
X1805289Y308671D03*
X1820307Y373829D03*
X1817157D03*
X1820144Y398052D03*
X1819374Y410432D03*
X1816224D03*
X1816994Y398052D03*
X1818874Y423932D03*
X1815724D03*
X1810792Y417432D03*
X1818816Y468872D03*
X1812161Y472521D03*
X1814537Y1322105D03*
X1803517Y1495567D03*
X1813700Y1494762D03*
X1807150Y1505675D03*
X1818289Y1501591D03*
X1811494Y1505349D03*
X1813994Y1507891D03*
X1818410Y1525815D03*
X1812250Y1521830D03*
X1811250Y1524830D03*
Y1527830D03*
X1807850D03*
X1804650D03*
Y1524830D03*
X1807850D03*
X1814370Y1528900D03*
X1814210Y1525815D03*
X1818524Y1528991D03*
X1834322Y49388D03*
X1828777Y156520D03*
X1823508Y158868D03*
X1835760Y185772D03*
X1828204Y328654D03*
X1829189Y363731D03*
X1829026Y367701D03*
X1829434Y406348D03*
X1834005Y401421D03*
X1821280Y413432D03*
X1834600Y406442D03*
X1826914Y431718D03*
X1823426Y1507916D03*
X1831994Y1525977D03*
X1835334Y1520921D03*
X1828510Y1525915D03*
X1821710D03*
X1830466Y1606658D03*
X1828880Y1626595D03*
Y1646595D03*
Y1666595D03*
Y1686595D03*
X1841257Y151402D03*
X1838910Y185772D03*
X1844157Y182210D03*
X1848435Y172187D03*
X1838880Y195162D03*
X1843134Y244362D03*
X1850331Y311946D03*
X1840691Y329470D03*
Y349470D03*
Y369470D03*
X1836750Y373632D03*
X1836294Y383592D03*
X1840691Y389470D03*
Y409470D03*
Y429470D03*
Y449470D03*
X1838020Y459121D03*
X1838379Y453921D03*
X1840691Y469470D03*
Y489470D03*
Y509470D03*
Y529470D03*
Y549470D03*
Y569470D03*
Y589470D03*
Y669470D03*
Y1329470D03*
Y1409470D03*
Y1429470D03*
Y1449470D03*
Y1469470D03*
Y1489470D03*
Y1509470D03*
Y1529470D03*
Y1549470D03*
Y1569470D03*
Y1589470D03*
X1854096Y52383D03*
X1854470Y112379D03*
Y152379D03*
Y172379D03*
Y192379D03*
Y212379D03*
Y232379D03*
Y252379D03*
Y272379D03*
Y292379D03*
G54D56*
X922441Y154311D03*
Y243799D03*
G54D30*
X174685Y637367D03*
Y647210D03*
X174393Y668511D03*
Y678354D03*
X205159Y1430034D03*
X195316D03*
X393067Y1354446D03*
X422833D03*
X453169D03*
X468443Y1379662D03*
X482543Y1353962D03*
X526478Y1439952D03*
Y1449795D03*
X708795Y1429579D03*
X718638D03*
X1077638Y133866D03*
X1131715Y1532913D03*
X1168627Y1466363D03*
X1178470D03*
X1175215Y1532913D03*
X1369208Y1353946D03*
X1398974D03*
X1429310D03*
X1444043Y1379362D03*
X1459076Y1353946D03*
X1502956Y1439530D03*
Y1449373D03*
X1670101Y1463655D03*
X1682882Y618174D03*
Y628017D03*
Y669109D03*
Y678952D03*
X1679944Y1463655D03*
X1769790Y194789D03*
X1799350D03*
Y204632D03*
X1836248Y269763D03*
X1826405D03*
X1836248Y299056D03*
X1826405D03*
G54D31*
X186697Y1578182D03*
Y1590094D03*
X191997Y1602380D03*
Y1614292D03*
X194497Y1578182D03*
X206557D03*
X198757D03*
X194497Y1590094D03*
X206557D03*
X198757D03*
X199797Y1614292D03*
Y1602380D03*
X204057Y1614292D03*
Y1602380D03*
X218617Y1578182D03*
X210817D03*
X222877D03*
X218617Y1590094D03*
X210817D03*
X222877D03*
X211857Y1614292D03*
Y1602380D03*
X223917Y1614292D03*
X216117D03*
X223917Y1602380D03*
X216117D03*
X230677Y1578182D03*
X234937D03*
X230677Y1590094D03*
X234937D03*
X228177Y1614292D03*
X235977D03*
X228177Y1602380D03*
X235977D03*
X240237D03*
Y1614292D03*
X242737Y1578182D03*
X246997D03*
X254797D03*
X242737Y1590094D03*
X246997D03*
X254797D03*
X248037Y1602380D03*
Y1614292D03*
X252297Y1602380D03*
Y1614292D03*
X266857Y1578182D03*
X259057D03*
X271117D03*
X266857Y1590094D03*
X259057D03*
X271117D03*
X260097Y1602380D03*
Y1614292D03*
X272157Y1602380D03*
Y1614292D03*
X264357D03*
Y1602380D03*
X278917Y1578182D03*
X283177D03*
X278917Y1590094D03*
X283177D03*
X284217Y1602380D03*
Y1614292D03*
X276417D03*
Y1602380D03*
X288477Y1614292D03*
Y1602380D03*
X290977Y1578182D03*
X295237D03*
X303037D03*
X290977Y1590094D03*
X295237D03*
X303037D03*
X296277Y1614292D03*
Y1602380D03*
X300537D03*
Y1614292D03*
X315097Y1578182D03*
X307297D03*
X319357D03*
X315097Y1590094D03*
X307297D03*
X319357D03*
X308337Y1602380D03*
Y1614292D03*
X320397D03*
X312597D03*
X320397Y1602380D03*
X312597D03*
X327157Y1578182D03*
X331417D03*
X327157Y1590094D03*
X331417D03*
X324657Y1602380D03*
X332457D03*
X324657Y1614292D03*
X332457D03*
X336717Y1602380D03*
Y1614292D03*
X339217Y1578182D03*
X343477D03*
X351277D03*
X339217Y1590094D03*
X343477D03*
X351277D03*
X344517Y1602380D03*
Y1614292D03*
X348777Y1602380D03*
Y1614292D03*
X363337Y1578088D03*
X355537Y1578182D03*
X367597D03*
X363337Y1590094D03*
X355537D03*
X367597D03*
X356577Y1602380D03*
Y1614292D03*
X368637D03*
X360837D03*
X368637Y1602286D03*
X360837Y1602380D03*
X375397Y1578182D03*
Y1590094D03*
X372897Y1602380D03*
X380697D03*
X372897Y1614292D03*
X380697D03*
X482911Y1578182D03*
X478651D03*
X470851D03*
X482911Y1590094D03*
X478651D03*
X470851D03*
X483951Y1614292D03*
Y1602380D03*
X476151D03*
Y1614292D03*
X494971Y1578182D03*
X490711D03*
X494971Y1590094D03*
X490711D03*
X500271Y1614292D03*
Y1602380D03*
X488211Y1614292D03*
Y1602380D03*
X496011D03*
Y1614292D03*
X507031Y1578182D03*
X514831D03*
X502771D03*
X507031Y1590094D03*
X514831D03*
X502771D03*
X512331Y1614292D03*
Y1602380D03*
X508071Y1614292D03*
Y1602380D03*
X531151Y1578182D03*
X519091D03*
X526891D03*
X531151Y1590094D03*
X519091D03*
X526891D03*
X532191Y1614292D03*
Y1602380D03*
X524391Y1614292D03*
Y1602380D03*
X520131D03*
Y1614292D03*
X543211Y1578182D03*
X538951D03*
X543211Y1590094D03*
X538951D03*
X548511Y1614292D03*
Y1602380D03*
X536451D03*
Y1614292D03*
X544251Y1602380D03*
Y1614292D03*
X555271Y1578182D03*
X563071D03*
X551011D03*
X555271Y1590094D03*
X563071D03*
X551011D03*
X560571Y1614292D03*
Y1602380D03*
X556311Y1614292D03*
Y1602380D03*
X579391Y1578182D03*
X567331D03*
X575131D03*
X579391Y1590094D03*
X567331D03*
X575131D03*
X580431Y1614292D03*
X572631D03*
X580431Y1602380D03*
X572631D03*
X568371D03*
Y1614292D03*
X599251Y1578182D03*
X591451D03*
X587191D03*
X599251Y1590094D03*
X591451D03*
X587191D03*
X596751Y1614292D03*
Y1602380D03*
X584691D03*
Y1614292D03*
X592491Y1602380D03*
Y1614292D03*
X615571Y1578182D03*
X603511D03*
X611311D03*
X615571Y1590094D03*
X603511D03*
X611311D03*
X608811Y1602380D03*
Y1614292D03*
X604551Y1602380D03*
Y1614292D03*
X627631Y1578182D03*
X623371D03*
X627631Y1590094D03*
X623371D03*
X628671Y1602380D03*
Y1614292D03*
X620871D03*
Y1602380D03*
X616611Y1614292D03*
Y1602380D03*
X647491Y1578088D03*
X639691Y1578182D03*
X635431D03*
X647491Y1590094D03*
X639691D03*
X635431D03*
X644991Y1614292D03*
Y1602380D03*
X632931D03*
Y1614292D03*
X640731D03*
Y1602380D03*
X651751Y1578182D03*
X659551D03*
X651751Y1590094D03*
X659551D03*
X657051Y1602380D03*
Y1614292D03*
X652791Y1602286D03*
Y1614292D03*
X664851Y1602380D03*
Y1614292D03*
X1194572Y1578182D03*
Y1590094D03*
X1199872Y1614292D03*
Y1602380D03*
X1202372Y1578182D03*
X1214432D03*
X1206632D03*
X1202372Y1590094D03*
X1214432D03*
X1206632D03*
X1207672Y1602380D03*
Y1614292D03*
X1211932D03*
Y1602380D03*
X1218692Y1578182D03*
X1226492D03*
X1230752D03*
X1218692Y1590094D03*
X1226492D03*
X1230752D03*
X1219732Y1614292D03*
Y1602380D03*
X1231792Y1614292D03*
Y1602380D03*
X1223992D03*
Y1614292D03*
X1238552Y1578182D03*
X1242812D03*
X1238552Y1590094D03*
X1242812D03*
X1236052Y1602380D03*
Y1614292D03*
X1243852D03*
Y1602380D03*
X1248112D03*
Y1614292D03*
X1250612Y1578182D03*
X1262672D03*
X1254872D03*
X1250612Y1590094D03*
X1262672D03*
X1254872D03*
X1255912Y1614292D03*
Y1602380D03*
X1260172D03*
Y1614292D03*
X1266932Y1578182D03*
X1274732D03*
X1278992D03*
X1266932Y1590094D03*
X1274732D03*
X1278992D03*
X1267972Y1614292D03*
Y1602380D03*
X1272232D03*
Y1614292D03*
X1280032D03*
Y1602380D03*
X1286792Y1578182D03*
X1298852D03*
X1291052D03*
X1286792Y1590094D03*
X1298852D03*
X1291052D03*
X1284292Y1602380D03*
Y1614292D03*
X1292092D03*
Y1602380D03*
X1296352D03*
Y1614292D03*
X1303112Y1578182D03*
X1310912D03*
X1315172D03*
X1303112Y1590094D03*
X1310912D03*
X1315172D03*
X1304152Y1602380D03*
Y1614292D03*
X1308412Y1602380D03*
Y1614292D03*
X1322972Y1578182D03*
X1327232D03*
X1322972Y1590094D03*
X1327232D03*
X1316212Y1614292D03*
Y1602380D03*
X1328272D03*
Y1614292D03*
X1320472Y1602380D03*
Y1614292D03*
X1335032Y1578182D03*
X1347092D03*
X1339292D03*
X1335032Y1590094D03*
X1347092D03*
X1339292D03*
X1340332Y1602380D03*
Y1614292D03*
X1332532Y1602380D03*
Y1614292D03*
X1344592Y1602380D03*
Y1614292D03*
X1351352Y1578182D03*
X1359152D03*
X1363412D03*
X1351352Y1590094D03*
X1359152D03*
X1363412D03*
X1352392Y1602380D03*
Y1614292D03*
X1356652Y1602380D03*
Y1614292D03*
X1371212Y1578088D03*
X1375472Y1578182D03*
X1371212Y1590094D03*
X1375472D03*
X1364452Y1602380D03*
Y1614292D03*
X1376512Y1602286D03*
Y1614292D03*
X1368712Y1602380D03*
Y1614292D03*
X1383272Y1578182D03*
Y1590094D03*
X1380772Y1602380D03*
Y1614292D03*
X1388572D03*
Y1602380D03*
X1460095Y1578182D03*
Y1590094D03*
X1472155Y1578182D03*
X1467895D03*
X1472155Y1590094D03*
X1467895D03*
X1477455Y1602380D03*
Y1614292D03*
X1473195D03*
Y1602380D03*
X1465395D03*
Y1614292D03*
X1492015Y1578182D03*
X1484215D03*
X1479955D03*
X1492015Y1590094D03*
X1484215D03*
X1479955D03*
X1489515Y1614292D03*
Y1602380D03*
X1485255D03*
Y1614292D03*
X1508335Y1578182D03*
X1496275D03*
X1504075D03*
X1508335Y1590094D03*
X1496275D03*
X1504075D03*
X1501575Y1614292D03*
Y1602380D03*
X1509375D03*
Y1614292D03*
X1497315Y1602380D03*
Y1614292D03*
X1520395Y1578182D03*
X1516135D03*
X1520395Y1590094D03*
X1516135D03*
X1525695Y1614292D03*
Y1602380D03*
X1521435D03*
Y1614292D03*
X1513635D03*
Y1602380D03*
X1540255Y1578182D03*
X1532455D03*
X1528195D03*
X1540255Y1590094D03*
X1532455D03*
X1528195D03*
X1537755Y1614292D03*
Y1602380D03*
X1533495D03*
Y1614292D03*
X1556575Y1578182D03*
X1544515D03*
X1552315D03*
X1556575Y1590094D03*
X1544515D03*
X1552315D03*
X1549815Y1614292D03*
Y1602380D03*
X1557615D03*
Y1614292D03*
X1545555Y1602380D03*
Y1614292D03*
X1568635Y1578182D03*
X1564375D03*
X1568635Y1590094D03*
X1564375D03*
X1573935Y1614292D03*
Y1602380D03*
X1569675Y1614292D03*
Y1602380D03*
X1561875Y1614292D03*
Y1602380D03*
X1588495Y1578182D03*
X1580695D03*
X1576435D03*
X1588495Y1590094D03*
X1580695D03*
X1576435D03*
X1585995Y1614292D03*
Y1602380D03*
X1581735D03*
Y1614292D03*
X1604815Y1578182D03*
X1592755D03*
X1600555D03*
X1604815Y1590094D03*
X1592755D03*
X1600555D03*
X1598055Y1614292D03*
Y1602380D03*
X1605855Y1614292D03*
Y1602380D03*
X1593795Y1614292D03*
Y1602380D03*
X1616875Y1578182D03*
X1612615D03*
X1616875Y1590094D03*
X1612615D03*
X1622175Y1614292D03*
Y1602380D03*
X1617915Y1614292D03*
Y1602380D03*
X1610115Y1614292D03*
Y1602380D03*
X1636735Y1578088D03*
X1628935Y1578182D03*
X1624675D03*
X1636735Y1590094D03*
X1628935D03*
X1624675D03*
X1634235Y1614292D03*
Y1602380D03*
X1629975Y1614292D03*
Y1602380D03*
X1640995Y1578182D03*
X1648795D03*
X1640995Y1590094D03*
X1648795D03*
X1646295Y1614292D03*
Y1602380D03*
X1654095Y1614292D03*
Y1602380D03*
X1642035Y1614292D03*
Y1602286D03*
G54D51*
X793879Y194881D03*
X789942Y204724D03*
X793879Y214567D03*
X805690Y188976D03*
Y220472D03*
X817501Y194881D03*
Y214567D03*
X821438Y204724D03*
X841240Y1407480D03*
X832154Y1411244D03*
X828390Y1420330D03*
X832154Y1429416D03*
X841240Y1433180D03*
X850326Y1411244D03*
X854090Y1420330D03*
X850326Y1429416D03*
X916545Y309459D03*
X911494Y321653D03*
X916545Y333847D03*
X940933Y309459D03*
X928739Y304408D03*
Y338898D03*
X940933Y333847D03*
X945984Y321653D03*
X1003390Y1420330D03*
X1016240Y1407480D03*
X1007154Y1411244D03*
Y1429416D03*
X1016240Y1433180D03*
X1025326Y1411244D03*
X1029090Y1420330D03*
X1025326Y1429416D03*
X1045847Y194881D03*
X1041910Y204724D03*
X1045847Y214567D03*
X1069469Y194881D03*
X1057658Y188976D03*
X1069469Y214567D03*
X1057658Y220472D03*
X1073406Y204724D03*
G54D24*
X70472Y173228D03*
Y236220D03*
G54D44*
X450000Y278543D03*
X460000D03*
X470000D03*
X483500Y246362D03*
X473500D03*
X480000Y278543D03*
X493500Y246362D03*
X490000Y278543D03*
X500000D03*
X498563Y607067D03*
X510000Y278543D03*
X520000D03*
X518563Y607067D03*
X508563D03*
X549236Y1441207D03*
X559236D03*
X569236D03*
X688500Y1601900D03*
Y1611900D03*
Y1621900D03*
X1041435Y143357D03*
Y153357D03*
X1056225Y143131D03*
Y153131D03*
X1041435Y163357D03*
X1056225Y163131D03*
X1099970Y1712570D03*
Y1722570D03*
X1689646Y115669D03*
X1679646D03*
X1689646Y125669D03*
Y135669D03*
X1679646Y125669D03*
Y135669D03*
X1689646Y145669D03*
Y155669D03*
X1679646Y145669D03*
Y155669D03*
X1689646Y165669D03*
X1679646D03*
X1689646Y175669D03*
X1679646D03*
X1771457Y1634646D03*
Y1624646D03*
Y1644646D03*
G54D14*
X27699Y1258727D03*
Y1255381D03*
Y1262074D03*
X43841Y994357D03*
X36399Y1054593D03*
X36449Y1257262D03*
X43841Y1255381D03*
Y1258727D03*
Y1252034D03*
X33546Y1273364D03*
X30746D03*
X57299Y766798D03*
X52541Y957546D03*
Y954200D03*
Y1021129D03*
Y1024475D03*
Y1051247D03*
X57399Y1258727D03*
X52820Y1253862D03*
X60446Y1273364D03*
X49546D03*
X46746D03*
X57399Y1262074D03*
X66099Y780184D03*
Y773491D03*
Y786877D03*
Y803609D03*
Y796916D03*
Y790223D03*
Y847113D03*
Y853806D03*
Y860499D03*
Y863845D03*
Y883924D03*
Y877231D03*
Y870538D03*
Y890617D03*
Y897310D03*
Y900656D03*
Y914042D03*
Y907349D03*
Y927428D03*
Y920735D03*
Y934121D03*
Y944160D03*
Y937467D03*
Y950853D03*
Y980971D03*
Y974278D03*
Y994357D03*
Y987664D03*
Y1027822D03*
Y1021129D03*
Y1047900D03*
Y1041207D03*
Y1034515D03*
Y1061286D03*
Y1054593D03*
Y1074672D03*
Y1067979D03*
Y1091404D03*
Y1081365D03*
Y1084711D03*
Y1098097D03*
Y1111483D03*
Y1104790D03*
Y1128215D03*
Y1118176D03*
Y1121522D03*
Y1141601D03*
Y1134908D03*
Y1148294D03*
Y1154987D03*
Y1158333D03*
Y1171719D03*
Y1165026D03*
Y1185105D03*
Y1178412D03*
Y1191798D03*
Y1208530D03*
Y1201837D03*
Y1195144D03*
X66189Y1257488D03*
X73541Y1255381D03*
Y1258727D03*
Y1252034D03*
X76446Y1273364D03*
X63246D03*
X82241Y770144D03*
X86999Y766798D03*
X82241Y776837D03*
Y786877D03*
Y783530D03*
Y800263D03*
Y793570D03*
Y850459D03*
Y843766D03*
Y867192D03*
Y860499D03*
Y857152D03*
Y873885D03*
Y880577D03*
Y887270D03*
Y897310D03*
Y893963D03*
Y917389D03*
Y910696D03*
Y904003D03*
Y924081D03*
Y934121D03*
Y930774D03*
Y947507D03*
Y940814D03*
Y957546D03*
Y954200D03*
Y977625D03*
Y970932D03*
Y991011D03*
Y984318D03*
Y994357D03*
Y1021129D03*
Y1024475D03*
Y1031168D03*
Y1044554D03*
Y1037861D03*
Y1051247D03*
Y1071326D03*
Y1064633D03*
Y1078018D03*
Y1094751D03*
Y1088058D03*
Y1081365D03*
Y1108137D03*
Y1101444D03*
Y1124869D03*
Y1118176D03*
Y1114829D03*
Y1144948D03*
Y1138255D03*
Y1131562D03*
Y1161680D03*
Y1154987D03*
Y1151641D03*
Y1175066D03*
Y1168373D03*
Y1181759D03*
Y1191798D03*
Y1188452D03*
Y1205184D03*
Y1198491D03*
X87099Y1258727D03*
X82241Y1248688D03*
X84334Y1254263D03*
X92946Y1273364D03*
X90146D03*
X79246D03*
X87099Y1262074D03*
X103241Y994357D03*
X95849Y1257262D03*
X103241Y1255381D03*
Y1258727D03*
Y1252034D03*
X108946Y1273364D03*
X106146D03*
X116567Y766775D03*
X125499Y867192D03*
Y880577D03*
Y873885D03*
Y893963D03*
Y887270D03*
Y917389D03*
Y910696D03*
Y904003D03*
Y930774D03*
Y924081D03*
Y947507D03*
Y940814D03*
Y964239D03*
Y954200D03*
X111941Y957546D03*
Y954200D03*
X125499Y977625D03*
Y970932D03*
Y991011D03*
Y984318D03*
Y1031168D03*
Y1024475D03*
Y1017782D03*
Y1044554D03*
Y1037861D03*
Y1057940D03*
Y1051247D03*
Y1061286D03*
Y1078018D03*
Y1071326D03*
Y1064633D03*
Y1094751D03*
Y1088058D03*
Y1108137D03*
Y1101444D03*
Y1124869D03*
Y1114829D03*
Y1144948D03*
Y1138255D03*
Y1131562D03*
Y1161680D03*
Y1151641D03*
Y1175066D03*
Y1168373D03*
Y1188452D03*
Y1181759D03*
Y1205184D03*
Y1198491D03*
Y1225263D03*
Y1218570D03*
Y1211877D03*
Y1241995D03*
Y1235302D03*
X125412Y1257102D03*
X125499Y1248688D03*
X116799Y1258727D03*
X111941Y1248688D03*
X114191Y1254604D03*
X119846Y1273364D03*
X122646D03*
X116799Y1262074D03*
X132941Y863845D03*
X141641D03*
X132941Y883924D03*
X141641D03*
X132941Y870538D03*
X141641D03*
X132941Y877231D03*
X141641D03*
X132941Y900656D03*
X141641D03*
X132941Y890617D03*
X141641D03*
X132941Y907349D03*
X141641D03*
X132941Y914042D03*
X141641D03*
X132941Y920735D03*
X141641D03*
X132941Y927428D03*
X141641D03*
X132941Y937467D03*
X141641D03*
X132941Y944160D03*
X141641D03*
X132941Y960892D03*
X141641D03*
X132941Y950853D03*
X141641D03*
Y957546D03*
Y954200D03*
X132941Y980971D03*
X141641D03*
X132941Y974278D03*
X141641D03*
X132941Y967585D03*
X141641D03*
X132941Y987664D03*
X141641D03*
Y994357D03*
X132941Y1027822D03*
X141641D03*
X132941Y1017782D03*
X141641D03*
X132941Y1047900D03*
X141641D03*
X132941Y1041207D03*
X141641D03*
X132941Y1034515D03*
X141641D03*
Y1061286D03*
X132941D03*
X141641Y1054593D03*
X132941D03*
X141641Y1057940D03*
Y1074672D03*
X132941D03*
X141641Y1067979D03*
X132941D03*
X141641Y1091404D03*
X132941D03*
X141641Y1084711D03*
X132941D03*
X141641Y1111483D03*
X132941D03*
X141641Y1104790D03*
X132941D03*
X141641Y1098097D03*
X132941D03*
X141641Y1128215D03*
X132941D03*
X141641Y1121522D03*
X132941D03*
X141641Y1141601D03*
X132941D03*
X141641Y1134908D03*
X132941D03*
X141641Y1158333D03*
X132941D03*
X141641Y1148294D03*
X132941D03*
X141641Y1171719D03*
X132941D03*
X141641Y1165026D03*
X132941D03*
X141641Y1185105D03*
X132941D03*
X141641Y1178412D03*
X132941D03*
X141641Y1208530D03*
X132941D03*
X141641Y1201837D03*
X132941D03*
X141641Y1195144D03*
X132941D03*
Y1221916D03*
X141641D03*
X132941Y1215223D03*
X141641D03*
X132941Y1238648D03*
X141641D03*
X132941Y1231955D03*
X141641D03*
X129933Y1238461D03*
X132941Y1245341D03*
X141641D03*
X132941Y1255381D03*
Y1258727D03*
Y1252034D03*
X141641Y1248688D03*
X143675Y1255567D03*
X135846Y1273364D03*
X138646D03*
X132941Y1262074D03*
X146367Y766775D03*
X155199Y867192D03*
X146499D03*
X155199Y880577D03*
X146499D03*
X155199Y873885D03*
X146499D03*
X155199Y893963D03*
X146499D03*
X155199Y887270D03*
X146499D03*
X155199Y917389D03*
X146499D03*
X155199Y910696D03*
X146499D03*
X155199Y904003D03*
X146499D03*
X155199Y930774D03*
X146499D03*
X155199Y924081D03*
X146499D03*
X155199Y947507D03*
X146499D03*
X155199Y940814D03*
X146499D03*
X155199Y964239D03*
X146499D03*
X155199Y954200D03*
X146499D03*
X155199Y977625D03*
X146499D03*
X155199Y970932D03*
X146499D03*
X155199Y991011D03*
X146499D03*
X155199Y984318D03*
X146499D03*
X155199Y1031168D03*
X146499D03*
X155199Y1024475D03*
X146499D03*
X155199Y1017782D03*
X146499D03*
X155199Y1044554D03*
X146499D03*
X155199Y1037861D03*
X146499D03*
X155199Y1057940D03*
X146499D03*
X155199Y1051247D03*
X146499D03*
X155199Y1078018D03*
X146499D03*
X155199Y1071326D03*
X146499D03*
X155199Y1064633D03*
X146499D03*
X155199Y1094751D03*
X146499D03*
X155199Y1088058D03*
X146499D03*
X155199Y1108137D03*
X146499D03*
X155199Y1101444D03*
X146499D03*
X155199Y1124869D03*
X146499D03*
X155199Y1114829D03*
X146499D03*
X155199Y1144948D03*
X146499D03*
X155199Y1138255D03*
X146499D03*
X155199Y1131562D03*
X146499D03*
X155199Y1161680D03*
X146499D03*
X155199Y1151641D03*
X146499D03*
X155199Y1175066D03*
X146499D03*
X155199Y1168373D03*
X146499D03*
X155199Y1188452D03*
X146499D03*
X155199Y1181759D03*
X146499D03*
X155199Y1205184D03*
X146499D03*
X155199Y1198491D03*
X146499D03*
X155199Y1225263D03*
X146499D03*
X155199Y1218570D03*
X146499D03*
X155199Y1211877D03*
X146499D03*
X155199Y1241995D03*
X146499D03*
X155199Y1235302D03*
X146499D03*
X155135Y1257134D03*
X155199Y1248688D03*
X146499D03*
X160130Y1251847D03*
X146499Y1258727D03*
X149546Y1273364D03*
X152346D03*
X146499Y1265420D03*
Y1262074D03*
X176099Y766798D03*
X176199Y867192D03*
X171341Y863845D03*
X162641D03*
X171341Y883924D03*
X162641D03*
X176199Y880577D03*
Y873885D03*
X171341Y877231D03*
X162641D03*
X171341Y870538D03*
X162641D03*
X171341Y900656D03*
X162641D03*
X176199Y893963D03*
Y887270D03*
X171341Y890617D03*
X162641D03*
X176199Y917389D03*
Y910696D03*
Y904003D03*
X171341Y914042D03*
X162641D03*
X171341Y907349D03*
X162641D03*
X176199Y930774D03*
Y924081D03*
X171341Y927428D03*
X162641D03*
X171341Y920735D03*
X162641D03*
X176199Y947507D03*
Y940814D03*
X171341Y944160D03*
X162641D03*
X171341Y937467D03*
X162641D03*
X176199Y964239D03*
Y954200D03*
X171341Y960892D03*
X162641D03*
X171341Y950853D03*
X162641D03*
X171341Y957546D03*
Y954200D03*
Y980971D03*
X162641D03*
X176199Y977625D03*
Y970932D03*
X171341Y974278D03*
X162641D03*
X171341Y967585D03*
X162641D03*
X176199Y991011D03*
Y984318D03*
X171341Y987664D03*
X162641D03*
Y994357D03*
X176199Y1031168D03*
Y1024475D03*
Y1017782D03*
X171341Y1027822D03*
X162641D03*
X171341Y1017782D03*
X162641D03*
X171341Y1047900D03*
X162641D03*
X176199Y1044554D03*
Y1037861D03*
X171341Y1041207D03*
X162641D03*
X171341Y1034515D03*
X162641D03*
X176199Y1057940D03*
Y1051247D03*
X171341Y1061286D03*
X162641D03*
X171341Y1054593D03*
X162641D03*
X176199Y1078018D03*
Y1071326D03*
Y1064633D03*
X171341Y1074672D03*
X162641D03*
X171341Y1067979D03*
X162641D03*
X176199Y1094751D03*
Y1088058D03*
X171341Y1091404D03*
X162641D03*
X171341Y1084711D03*
X162641D03*
X171341Y1111483D03*
X162641D03*
X176199Y1108137D03*
Y1101444D03*
X171341Y1104790D03*
X162641D03*
X171341Y1098097D03*
X162641D03*
X171341Y1128215D03*
X162641D03*
X176199Y1124869D03*
Y1114829D03*
X171341Y1121522D03*
X162641D03*
X176199Y1144948D03*
Y1138255D03*
Y1131562D03*
X171341Y1141601D03*
X162641D03*
X171341Y1134908D03*
X162641D03*
X176199Y1161680D03*
Y1151641D03*
X171341Y1158333D03*
X162641D03*
X171341Y1148294D03*
X162641D03*
X176199Y1175066D03*
Y1168373D03*
X171341Y1171719D03*
X162641D03*
X171341Y1165026D03*
X162641D03*
X176199Y1188452D03*
Y1181759D03*
X171341Y1185105D03*
X162641D03*
X171341Y1178412D03*
X162641D03*
X176199Y1205184D03*
Y1198491D03*
X171341Y1208530D03*
X162641D03*
X171341Y1201837D03*
X162641D03*
X171341Y1195144D03*
X162641D03*
X176199Y1225263D03*
Y1218570D03*
Y1211877D03*
X162641Y1221916D03*
X171341D03*
Y1215223D03*
X162641D03*
X176199Y1241995D03*
Y1235302D03*
X171341Y1238648D03*
X162641D03*
X171341Y1231955D03*
X162641D03*
X176199Y1248688D03*
X171341Y1245341D03*
X162641D03*
X176199Y1258727D03*
X162641Y1255381D03*
Y1258727D03*
Y1252034D03*
X171341Y1248688D03*
X171947Y1255837D03*
X165546Y1273364D03*
X168346D03*
X176199Y1265420D03*
X162641D03*
Y1262074D03*
X176199D03*
X191491Y863845D03*
X184899Y867192D03*
X192341Y883924D03*
Y877231D03*
Y870538D03*
X184899Y880577D03*
Y873885D03*
X192341Y900656D03*
Y890617D03*
X184899Y893963D03*
Y887270D03*
X192341Y914042D03*
Y907349D03*
X184899Y917389D03*
Y910696D03*
Y904003D03*
X191491Y927428D03*
X192341Y920735D03*
X184899Y930774D03*
Y924081D03*
X192341Y937467D03*
Y944160D03*
X184899Y947507D03*
Y940814D03*
X192341Y960892D03*
Y950853D03*
X184899Y964239D03*
Y954200D03*
X192341Y974278D03*
Y980971D03*
Y967585D03*
X184899Y977625D03*
Y970932D03*
X192341Y987664D03*
X184899Y991011D03*
Y984318D03*
X192341Y1027822D03*
Y1017782D03*
X184899Y1031168D03*
Y1024475D03*
Y1017782D03*
X192341Y1047900D03*
Y1041207D03*
Y1034515D03*
X184899Y1044554D03*
Y1037861D03*
X192341Y1054593D03*
Y1061286D03*
X184899Y1057940D03*
Y1051247D03*
Y1061286D03*
X192341Y1074672D03*
Y1067979D03*
X184899Y1078018D03*
Y1071326D03*
Y1064633D03*
X192341Y1091404D03*
X191491Y1084711D03*
X184899Y1094751D03*
Y1088058D03*
X192341Y1111483D03*
Y1104790D03*
Y1098097D03*
X184899Y1108137D03*
Y1101444D03*
X192341Y1128215D03*
Y1121522D03*
X184899Y1124869D03*
Y1114829D03*
X192341Y1141601D03*
Y1134908D03*
X184899Y1144948D03*
Y1138255D03*
Y1131562D03*
X191491Y1158333D03*
X192341Y1148294D03*
X184899Y1161680D03*
Y1151641D03*
X192341Y1171719D03*
Y1165026D03*
X184899Y1175066D03*
Y1168373D03*
X192341Y1185105D03*
Y1178412D03*
X184899Y1188452D03*
Y1181759D03*
X192341Y1208530D03*
Y1201837D03*
Y1195144D03*
X184899Y1205184D03*
Y1198491D03*
X192341Y1221916D03*
Y1215223D03*
X184899Y1225263D03*
Y1218570D03*
Y1211877D03*
X192341Y1238648D03*
X191491Y1231955D03*
X184899Y1241995D03*
Y1235302D03*
X184923Y1258871D03*
X192341Y1245341D03*
X184899Y1248688D03*
X192341Y1255381D03*
Y1258727D03*
Y1252034D03*
X192594Y1271262D03*
X192605Y1268774D03*
X182046Y1273364D03*
X179246D03*
X192341Y1265420D03*
Y1262074D03*
X188119Y1580678D03*
Y1575686D03*
X188897Y1578182D03*
X192297D03*
X188119Y1592590D03*
Y1587598D03*
X188897Y1590094D03*
X192297D03*
X205799Y766798D03*
X205049Y867192D03*
X201041Y863845D03*
X205899Y873885D03*
Y880577D03*
X201041Y883924D03*
Y877231D03*
Y870538D03*
X205899Y893963D03*
Y887270D03*
X201041Y900656D03*
Y890617D03*
X205899Y917389D03*
Y910696D03*
Y904003D03*
X201041Y914042D03*
Y907349D03*
X205049Y930774D03*
Y924081D03*
X201041Y927428D03*
Y920735D03*
X205899Y940814D03*
Y947507D03*
X201041Y937467D03*
Y944160D03*
X205899Y964239D03*
Y954200D03*
X201041Y960892D03*
Y950853D03*
Y957546D03*
Y954200D03*
X205899Y970932D03*
Y977625D03*
X201041Y974278D03*
Y980971D03*
Y967585D03*
X205899Y991011D03*
Y984318D03*
X201041Y987664D03*
Y994357D03*
X205899Y1031168D03*
Y1017782D03*
Y1024475D03*
X201041Y1027822D03*
Y1017782D03*
X205899Y1044554D03*
Y1037861D03*
X201041Y1047900D03*
Y1041207D03*
Y1034515D03*
X205899Y1057940D03*
Y1051247D03*
X201041Y1054593D03*
Y1061286D03*
X205049Y1078018D03*
X205899Y1071326D03*
Y1064633D03*
X201041Y1074672D03*
Y1067979D03*
X205899Y1094751D03*
X205049Y1088058D03*
X201041Y1091404D03*
Y1084711D03*
X205899Y1101444D03*
Y1108137D03*
X201041Y1111483D03*
Y1104790D03*
Y1098097D03*
X205899Y1114829D03*
Y1124869D03*
X201041Y1128215D03*
Y1121522D03*
X205899Y1144948D03*
Y1138255D03*
Y1131562D03*
X201041Y1141601D03*
Y1134908D03*
X205049Y1161680D03*
Y1151641D03*
X201041Y1158333D03*
Y1148294D03*
X205899Y1168373D03*
Y1175066D03*
X201041Y1171719D03*
Y1165026D03*
X205899Y1188452D03*
Y1181759D03*
X201041Y1185105D03*
Y1178412D03*
X205899Y1205184D03*
Y1198491D03*
X201041Y1208530D03*
Y1201837D03*
Y1195144D03*
X205049Y1225263D03*
X205899Y1211877D03*
Y1218570D03*
X201041Y1221916D03*
Y1215223D03*
X205899Y1241995D03*
X205049Y1235302D03*
X201041Y1238648D03*
Y1231955D03*
X205899Y1248688D03*
X201041Y1245341D03*
X205899Y1258727D03*
X201041Y1248688D03*
X201193Y1257900D03*
X206268Y1271348D03*
X206337Y1268720D03*
X205899Y1265420D03*
Y1262074D03*
X193075Y1580678D03*
Y1575686D03*
X200179D03*
X205135D03*
X200179Y1580678D03*
X205135D03*
X200957Y1578182D03*
X204357D03*
X193075Y1592590D03*
Y1587598D03*
X200179Y1592590D03*
X205135D03*
X200179Y1587598D03*
X205135D03*
X198375Y1599884D03*
X193419D03*
X205479D03*
X200957Y1590094D03*
X204357D03*
X193419Y1616788D03*
Y1611796D03*
X198375D03*
X193419Y1604876D03*
X198375D03*
Y1616788D03*
X205479Y1611796D03*
Y1604876D03*
Y1616788D03*
X221191Y863845D03*
X215449Y867192D03*
X222041Y877231D03*
X221191Y870538D03*
X222041Y883924D03*
X214599Y873885D03*
Y880577D03*
X222041Y900656D03*
Y890617D03*
X214599Y893963D03*
Y887270D03*
X222041Y914042D03*
Y907349D03*
X214599Y917389D03*
Y910696D03*
Y904003D03*
X221241Y927428D03*
X222041Y920735D03*
X215449Y930774D03*
Y924081D03*
X222041Y944160D03*
X221191Y937467D03*
X214599Y940814D03*
Y947507D03*
X222041Y960892D03*
Y950853D03*
X214599Y964239D03*
Y954200D03*
X222041Y957546D03*
Y954200D03*
Y980971D03*
Y974278D03*
Y967585D03*
X214599Y970932D03*
Y977625D03*
Y991011D03*
Y984318D03*
X222041Y987664D03*
Y994357D03*
Y1027822D03*
Y1017782D03*
X214599Y1031168D03*
Y1017782D03*
Y1024475D03*
X222041Y1047900D03*
Y1041207D03*
Y1034515D03*
X214599Y1044554D03*
Y1037861D03*
X222041Y1054593D03*
Y1061286D03*
X214599Y1057940D03*
Y1051247D03*
X222041Y1067979D03*
X221191Y1074672D03*
X215449Y1078018D03*
X214599Y1071326D03*
Y1064633D03*
X222041Y1091404D03*
X221191Y1084711D03*
X214599Y1094751D03*
X215449Y1088058D03*
X222041Y1111483D03*
Y1098097D03*
Y1104790D03*
X214599Y1101444D03*
Y1108137D03*
X222041Y1128215D03*
Y1121522D03*
X214599Y1114829D03*
Y1124869D03*
X222041Y1141601D03*
X221191Y1134908D03*
X214599Y1144948D03*
Y1138255D03*
Y1131562D03*
X222041Y1158333D03*
X221191Y1148294D03*
X215449Y1161680D03*
Y1151641D03*
X222041Y1165026D03*
Y1171719D03*
X214599Y1168373D03*
Y1175066D03*
X222041Y1185105D03*
Y1178412D03*
X214599Y1188452D03*
Y1181759D03*
X222041Y1208530D03*
Y1201837D03*
Y1195144D03*
X214599Y1205184D03*
Y1198491D03*
X222041Y1221916D03*
Y1215223D03*
X215449Y1225263D03*
X214599Y1211877D03*
Y1218570D03*
X221191Y1231955D03*
Y1238648D03*
X214599Y1241995D03*
X215449Y1235302D03*
X222041Y1245341D03*
X214824Y1258711D03*
X214599Y1248688D03*
X222041Y1255381D03*
X219660Y1260492D03*
X222041Y1252034D03*
X224987Y1273535D03*
X222041Y1265420D03*
Y1262074D03*
X212239Y1580678D03*
X217195D03*
Y1575686D03*
X212239D03*
X224299D03*
Y1580678D03*
X225077Y1578182D03*
X213017D03*
X216417D03*
X212239Y1587598D03*
X217195D03*
X212239Y1592590D03*
X217195D03*
X224299Y1587598D03*
Y1592590D03*
X210435Y1599884D03*
X222495D03*
X217539D03*
X225077Y1590094D03*
X213017D03*
X216417D03*
X210435Y1611796D03*
Y1604876D03*
Y1616788D03*
X222495D03*
X217539D03*
X222495Y1604876D03*
Y1611796D03*
X217539Y1604876D03*
Y1611796D03*
X235499Y766798D03*
X234749Y867492D03*
X231591Y863845D03*
X235599Y874185D03*
Y880577D03*
X230741Y877231D03*
X231059Y871084D03*
X230741Y883924D03*
X235599Y893963D03*
Y887270D03*
X230741Y900656D03*
Y890617D03*
X235599Y917389D03*
Y910696D03*
Y904003D03*
X230741Y914042D03*
Y907349D03*
X235599Y930774D03*
Y924081D03*
X231541Y927428D03*
X230741Y920735D03*
X235599Y947507D03*
X234859Y940814D03*
X230741Y944660D03*
X231591Y937467D03*
X235599Y964239D03*
Y954200D03*
X230741Y960892D03*
Y950853D03*
X235599Y977625D03*
Y970932D03*
X230741Y980971D03*
Y974278D03*
Y967585D03*
X235599Y991011D03*
X230741Y987664D03*
X235599Y984318D03*
Y1031168D03*
X230741Y1027822D03*
Y1017782D03*
X235599D03*
Y1024475D03*
Y1044554D03*
Y1037861D03*
X230741Y1047900D03*
Y1041207D03*
Y1034515D03*
X235599Y1051247D03*
Y1057940D03*
X230741Y1054593D03*
Y1061286D03*
X234749Y1078018D03*
X235599Y1071326D03*
Y1064633D03*
X230741Y1067979D03*
X231591Y1074672D03*
X235599Y1094751D03*
X234749Y1088058D03*
X230741Y1091404D03*
Y1084711D03*
X235599Y1108137D03*
Y1101444D03*
X230741Y1111483D03*
Y1098097D03*
Y1104790D03*
X234749Y1124869D03*
X235599Y1114829D03*
X230741Y1128215D03*
Y1121522D03*
X235599Y1144948D03*
Y1138255D03*
X234749Y1131562D03*
X230741Y1141601D03*
X231591Y1134908D03*
X235599Y1151641D03*
Y1161680D03*
X230741Y1158333D03*
X231591Y1148294D03*
X235599Y1175066D03*
Y1168373D03*
X230741Y1165026D03*
Y1171719D03*
X235599Y1188452D03*
Y1181759D03*
X230741Y1185105D03*
Y1178412D03*
X235599Y1205184D03*
Y1198491D03*
X230741Y1208530D03*
Y1201837D03*
Y1195144D03*
X234749Y1225263D03*
X235599Y1218570D03*
Y1211877D03*
X230741Y1221916D03*
Y1215223D03*
X235599Y1241995D03*
X235186Y1234977D03*
X231591Y1231955D03*
Y1238648D03*
X235599Y1248688D03*
X230741Y1245341D03*
X235599Y1258727D03*
X230741Y1248688D03*
X227746Y1273364D03*
X240966Y1273143D03*
X238971Y1274353D03*
X235480Y1265406D03*
X235599Y1262074D03*
X229255Y1575686D03*
Y1580678D03*
X236359D03*
Y1575686D03*
X241315Y1580678D03*
Y1575686D03*
X237137Y1578182D03*
X240537D03*
X228477D03*
X229255Y1587598D03*
Y1592590D03*
X236359D03*
Y1587598D03*
X241315Y1592590D03*
Y1587598D03*
X229599Y1599884D03*
X234555D03*
X237137Y1590094D03*
X240537D03*
X228477D03*
X229599Y1604876D03*
Y1611796D03*
X234555Y1604876D03*
Y1611796D03*
X229599Y1616788D03*
X234555D03*
X233268Y1679920D03*
Y1675383D03*
X241142Y1679320D03*
X233268Y1698627D03*
Y1694093D03*
Y1689556D03*
Y1684454D03*
X241142Y1683857D03*
Y1688391D03*
Y1693493D03*
Y1698030D03*
X233268Y1712800D03*
Y1708266D03*
Y1703729D03*
X241142Y1702564D03*
Y1707666D03*
Y1712203D03*
X233268Y1717903D03*
Y1722440D03*
Y1726974D03*
X241142Y1716737D03*
Y1730911D03*
Y1726377D03*
Y1721840D03*
X251741Y766798D03*
X244299Y770144D03*
X251741Y780184D03*
Y773491D03*
X244299Y783530D03*
Y776837D03*
X251741Y803609D03*
Y796916D03*
Y790223D03*
X244299Y800263D03*
Y793570D03*
X250891Y816995D03*
X251741Y810302D03*
X245149Y820341D03*
Y813648D03*
X244299Y806955D03*
X251741Y833727D03*
X250891Y827034D03*
X244299Y830381D03*
X251741Y847113D03*
Y840420D03*
X244299Y850459D03*
Y837074D03*
Y843766D03*
X250891Y863845D03*
Y853806D03*
X245149Y867192D03*
Y857152D03*
X251741Y870538D03*
Y883924D03*
Y877231D03*
X244299Y873885D03*
Y880577D03*
X250891Y900656D03*
X251741Y890617D03*
X244299Y893963D03*
Y887270D03*
X251741Y914042D03*
Y907349D03*
X244299Y917389D03*
Y910696D03*
Y904003D03*
X250891Y927428D03*
X251741Y920735D03*
X245149Y930774D03*
X244299Y924081D03*
X251741Y944160D03*
X250891Y937467D03*
X244299Y947507D03*
X245149Y940814D03*
X251741Y960892D03*
Y950853D03*
X244299Y964239D03*
Y954200D03*
X251741Y957546D03*
Y954200D03*
Y980971D03*
Y974278D03*
Y967585D03*
X244299Y977625D03*
Y970932D03*
X251741Y987664D03*
X244299Y991011D03*
Y984318D03*
X251741Y994357D03*
X244299Y1031168D03*
X251741Y1027822D03*
Y1017782D03*
X244299D03*
Y1024475D03*
X251741Y1047900D03*
Y1041207D03*
Y1034515D03*
X244299Y1044554D03*
Y1037861D03*
X251741Y1061286D03*
Y1054593D03*
X244299Y1051247D03*
Y1057940D03*
Y1061286D03*
X250891Y1074672D03*
Y1067979D03*
X245149Y1078018D03*
X244299Y1071326D03*
Y1064633D03*
X251741Y1091404D03*
Y1084711D03*
X244299Y1094751D03*
X245149Y1088058D03*
X251741Y1104790D03*
X250891Y1111483D03*
X251741Y1098097D03*
X244299Y1108137D03*
Y1101444D03*
X251741Y1128215D03*
X250891Y1121522D03*
X245149Y1124869D03*
X244299Y1114829D03*
X251741Y1134908D03*
Y1141601D03*
X244299Y1144948D03*
Y1138255D03*
X245149Y1131562D03*
X251741Y1158333D03*
Y1148294D03*
X244299Y1151641D03*
Y1161680D03*
X251741Y1171719D03*
Y1165026D03*
X244299Y1175066D03*
Y1168373D03*
X251741Y1185105D03*
Y1178412D03*
X244299Y1188452D03*
Y1181759D03*
X251741Y1208530D03*
Y1201837D03*
X250891Y1195144D03*
X244299Y1205184D03*
Y1198491D03*
X250891Y1221916D03*
X251741Y1215223D03*
X245149Y1225263D03*
X244299Y1218570D03*
Y1211877D03*
X250891Y1231955D03*
X244299Y1241995D03*
X245149Y1235302D03*
X251741Y1238648D03*
X244299Y1248688D03*
X251741Y1245341D03*
X248047Y1259155D03*
X250467Y1259175D03*
X251707Y1252034D03*
X244789Y1260093D03*
X254897Y1274040D03*
X257197Y1273640D03*
X249603Y1266204D03*
X251699Y1265254D03*
X248419Y1575686D03*
X253375D03*
X248419Y1580678D03*
X253375D03*
X249197Y1578182D03*
X252597D03*
X248419Y1587598D03*
X253375D03*
X248419Y1592590D03*
X253375D03*
X246615Y1599884D03*
X241659D03*
X253719D03*
X249197Y1590094D03*
X252597D03*
X241659Y1616788D03*
X246615D03*
Y1604876D03*
X241659D03*
X246615Y1611796D03*
X241659D03*
X253719Y1604876D03*
Y1611796D03*
Y1616788D03*
X249016Y1675383D03*
Y1679920D03*
X256890Y1679320D03*
X249016Y1684454D03*
Y1689556D03*
Y1694093D03*
Y1698627D03*
X256890Y1683857D03*
Y1688391D03*
Y1693493D03*
Y1698030D03*
X249016Y1703729D03*
Y1708266D03*
Y1712800D03*
X256890Y1702564D03*
Y1707666D03*
Y1712203D03*
X249016Y1726974D03*
Y1722440D03*
Y1717903D03*
X256890Y1716737D03*
Y1730911D03*
Y1726377D03*
Y1721840D03*
X260441Y766798D03*
Y780184D03*
Y773491D03*
Y803609D03*
Y796916D03*
Y790223D03*
X261291Y816995D03*
X260441Y810302D03*
Y833727D03*
X261291Y827034D03*
X260441Y847113D03*
Y840420D03*
X261291Y863845D03*
Y853806D03*
X260441Y870538D03*
Y883924D03*
Y877231D03*
Y900656D03*
Y890617D03*
Y914042D03*
Y907349D03*
X261291Y927428D03*
X260441Y920735D03*
Y944160D03*
X261291Y937467D03*
X260441Y960892D03*
Y950853D03*
Y980971D03*
Y974278D03*
Y967585D03*
Y987664D03*
Y1027822D03*
Y1017782D03*
Y1047900D03*
Y1041207D03*
Y1034515D03*
Y1061286D03*
Y1054593D03*
Y1057940D03*
X261291Y1074672D03*
Y1067979D03*
X260441Y1091404D03*
Y1084711D03*
Y1104790D03*
X261291Y1111483D03*
X260441Y1098097D03*
Y1128215D03*
X261291Y1121522D03*
X260441Y1134908D03*
Y1141601D03*
Y1158333D03*
Y1148294D03*
Y1171719D03*
Y1165026D03*
Y1185105D03*
Y1178412D03*
Y1208530D03*
Y1201837D03*
Y1195144D03*
X261291Y1221916D03*
X260441Y1215223D03*
X261291Y1231955D03*
X260441Y1238648D03*
Y1245341D03*
Y1248688D03*
X260479Y1580678D03*
X265435D03*
X260479Y1575592D03*
X265435D03*
X272539Y1575686D03*
Y1580678D03*
X273317Y1578182D03*
X261257D03*
X264657D03*
X260479Y1592590D03*
X265435D03*
X260479Y1587598D03*
X265435D03*
X272539D03*
Y1592590D03*
X258675Y1599884D03*
X270735Y1599790D03*
X265779D03*
X273317Y1590094D03*
X261257D03*
X264657D03*
X258675Y1604876D03*
Y1611796D03*
Y1616788D03*
X270735D03*
X265779D03*
X270735Y1611796D03*
Y1604876D03*
X265779D03*
Y1611796D03*
X264764Y1675383D03*
Y1679920D03*
X272638Y1679320D03*
X264764Y1684454D03*
Y1689556D03*
Y1694093D03*
Y1698627D03*
X272638Y1683857D03*
Y1688391D03*
Y1693493D03*
Y1698030D03*
X264764Y1703729D03*
Y1708266D03*
Y1712800D03*
X272638Y1702564D03*
Y1707666D03*
Y1712203D03*
X264764Y1726974D03*
Y1722440D03*
Y1717903D03*
X272638Y1716737D03*
Y1730911D03*
Y1726377D03*
Y1721840D03*
X277495Y1575686D03*
Y1580678D03*
X284599D03*
X289555D03*
Y1575686D03*
X284599D03*
X285377Y1578182D03*
X288777D03*
X276717D03*
X277495Y1587598D03*
Y1592590D03*
X284599D03*
X289555D03*
X284599Y1587598D03*
X289555D03*
X282795Y1599884D03*
X277839D03*
X289899D03*
X285377Y1590094D03*
X288777D03*
X276717D03*
X282795Y1604876D03*
Y1611796D03*
X277839D03*
Y1604876D03*
X282795Y1616788D03*
X277839D03*
X289899D03*
Y1604876D03*
Y1611796D03*
X280512Y1675383D03*
Y1679920D03*
Y1684454D03*
Y1689556D03*
Y1694093D03*
Y1698627D03*
Y1703729D03*
Y1708266D03*
Y1712800D03*
Y1726974D03*
Y1722440D03*
Y1717903D03*
X296659Y1575686D03*
X301615D03*
X296659Y1580678D03*
X301615D03*
X297437Y1578182D03*
X300837D03*
X296659Y1587598D03*
X301615D03*
X296659Y1592590D03*
X301615D03*
X294855Y1599884D03*
X301959D03*
X297437Y1590094D03*
X300837D03*
X294855Y1616788D03*
Y1604876D03*
Y1611796D03*
X301959Y1604876D03*
Y1611796D03*
Y1616788D03*
X300197Y1679920D03*
Y1675383D03*
Y1698627D03*
Y1694093D03*
Y1689556D03*
Y1684454D03*
Y1712800D03*
Y1708266D03*
Y1703729D03*
Y1717903D03*
Y1722440D03*
Y1726974D03*
X308719Y1580678D03*
X313675D03*
X308719Y1575686D03*
X313675D03*
X320779D03*
Y1580678D03*
X321557Y1578182D03*
X309497D03*
X312897D03*
X308719Y1592590D03*
X313675D03*
X308719Y1587598D03*
X313675D03*
X320779D03*
Y1592590D03*
X306915Y1599884D03*
X318975D03*
X314019D03*
X321557Y1590094D03*
X309497D03*
X312897D03*
X306915Y1604876D03*
Y1611796D03*
Y1616788D03*
X318975D03*
X314019D03*
X318975Y1604876D03*
Y1611796D03*
X314019Y1604876D03*
Y1611796D03*
X308071Y1679320D03*
X315945Y1679920D03*
Y1675383D03*
X308071Y1683857D03*
Y1698030D03*
Y1693493D03*
Y1688391D03*
X315945Y1698627D03*
Y1694093D03*
Y1689556D03*
Y1684454D03*
X308071Y1702564D03*
Y1712203D03*
Y1707666D03*
X315945Y1712800D03*
Y1708266D03*
Y1703729D03*
X308071Y1716737D03*
Y1721840D03*
Y1726377D03*
Y1730911D03*
X315945Y1717903D03*
Y1722440D03*
Y1726974D03*
X325735Y1575686D03*
Y1580678D03*
X332839D03*
X337795D03*
X332839Y1575686D03*
X337795D03*
X333617Y1578182D03*
X337017D03*
X324957D03*
X325735Y1587598D03*
Y1592590D03*
X332839D03*
X337795D03*
X332839Y1587598D03*
X337795D03*
X326079Y1599884D03*
X331035D03*
X338139D03*
X333617Y1590094D03*
X337017D03*
X324957D03*
X326079Y1604876D03*
Y1611796D03*
X331035Y1604876D03*
Y1611796D03*
X326079Y1616788D03*
X331035D03*
X338139D03*
Y1604876D03*
Y1611796D03*
X323819Y1679320D03*
X331693Y1679920D03*
Y1675383D03*
X323819Y1683857D03*
Y1698030D03*
Y1693493D03*
Y1688391D03*
X331693Y1698627D03*
Y1694093D03*
Y1689556D03*
Y1684454D03*
X323819Y1702564D03*
Y1712203D03*
Y1707666D03*
X331693Y1712800D03*
Y1708266D03*
Y1703729D03*
X323819Y1716737D03*
Y1721840D03*
Y1726377D03*
Y1730911D03*
X331693Y1717903D03*
Y1722440D03*
Y1726974D03*
X344899Y1575686D03*
X349855D03*
X344899Y1580678D03*
X349855D03*
X345677Y1578182D03*
X349077D03*
X344899Y1587598D03*
X349855D03*
X344899Y1592590D03*
X349855D03*
X343095Y1599884D03*
X355155D03*
X350199D03*
X345677Y1590094D03*
X349077D03*
X343095Y1616788D03*
Y1604876D03*
Y1611796D03*
X355155Y1604876D03*
Y1611796D03*
X350199Y1604876D03*
Y1611796D03*
X355155Y1616788D03*
X350199D03*
X339567Y1679320D03*
X347441Y1679920D03*
Y1675383D03*
X355315Y1679320D03*
X339567Y1683857D03*
Y1698030D03*
Y1693493D03*
Y1688391D03*
X347441Y1698627D03*
Y1694093D03*
Y1689556D03*
Y1684454D03*
X355315Y1683857D03*
Y1698030D03*
Y1693493D03*
Y1688391D03*
X339567Y1702564D03*
Y1712203D03*
Y1707666D03*
X347441Y1712800D03*
Y1708266D03*
Y1703729D03*
X355315Y1702564D03*
Y1712203D03*
Y1707666D03*
X339567Y1716737D03*
Y1721840D03*
Y1726377D03*
Y1730911D03*
X347441Y1717903D03*
Y1722440D03*
Y1726974D03*
X355315Y1716737D03*
Y1721840D03*
Y1726377D03*
Y1730911D03*
X356959Y1580678D03*
X361915D03*
X356959Y1575592D03*
X361915D03*
X369019Y1575686D03*
Y1580678D03*
X369797Y1578182D03*
X357737D03*
X361137D03*
X356959Y1592590D03*
X361915D03*
X356959Y1587598D03*
X361915D03*
X367215Y1599790D03*
X362259D03*
X369019Y1587598D03*
Y1592590D03*
X369797Y1590094D03*
X357737D03*
X361137D03*
X367215Y1616788D03*
X362259D03*
X367215Y1604876D03*
Y1611796D03*
X362259Y1604876D03*
Y1611796D03*
X380930Y1531402D03*
X384210Y1534152D03*
X373975Y1575686D03*
Y1580678D03*
X373197Y1578182D03*
X373975Y1587598D03*
Y1592590D03*
X379275Y1599884D03*
X374319D03*
X373197Y1590094D03*
X379275Y1604876D03*
Y1611796D03*
X374319Y1604876D03*
Y1611796D03*
X379275Y1616788D03*
X374319D03*
X484333Y1575686D03*
Y1580678D03*
X477229D03*
X472273D03*
Y1575686D03*
X477229D03*
X476451Y1578182D03*
X485111D03*
X473051D03*
X482529Y1599884D03*
X477573D03*
X484333Y1587598D03*
Y1592590D03*
X472273D03*
X477229D03*
Y1587598D03*
X472273D03*
X476451Y1590094D03*
X485111D03*
X473051D03*
X482529Y1616788D03*
X477573D03*
Y1611796D03*
X482529D03*
X477573Y1604876D03*
X482529D03*
X501349Y1580678D03*
X496393D03*
Y1575686D03*
X501349D03*
X489289D03*
Y1580678D03*
X500571Y1578182D03*
X488511D03*
X497171D03*
X501693Y1599884D03*
X494589D03*
X489633D03*
X501349Y1592590D03*
X496393D03*
X501349Y1587598D03*
X496393D03*
X489289D03*
Y1592590D03*
X500571Y1590094D03*
X488511D03*
X497171D03*
X501693Y1611796D03*
Y1604876D03*
Y1616788D03*
X489633Y1611796D03*
X494589Y1604876D03*
X489633D03*
X494589Y1611796D03*
X489633Y1616788D03*
X494589D03*
X497441Y1675383D03*
Y1679920D03*
Y1684454D03*
Y1689556D03*
Y1694093D03*
Y1698627D03*
Y1703729D03*
Y1708266D03*
Y1712800D03*
Y1726974D03*
Y1722440D03*
Y1717903D03*
X508453Y1575686D03*
X513409D03*
X508453Y1580678D03*
X513409D03*
X512631Y1578182D03*
X509231D03*
X513753Y1599884D03*
X506649D03*
X508453Y1587598D03*
X513409D03*
X508453Y1592590D03*
X513409D03*
X512631Y1590094D03*
X509231D03*
X513753Y1616788D03*
Y1604876D03*
Y1611796D03*
X506649D03*
Y1604876D03*
Y1616788D03*
X513189Y1675383D03*
Y1679920D03*
X505315Y1679320D03*
X513189Y1684454D03*
Y1689556D03*
Y1694093D03*
Y1698627D03*
X505315Y1688391D03*
Y1693493D03*
Y1698030D03*
Y1683857D03*
X513189Y1703729D03*
Y1708266D03*
Y1712800D03*
X505315Y1707666D03*
Y1712203D03*
Y1702564D03*
X513189Y1726974D03*
Y1722440D03*
Y1717903D03*
X505315Y1730911D03*
Y1726377D03*
Y1721840D03*
Y1716737D03*
X532573Y1575686D03*
Y1580678D03*
X520513D03*
X525469D03*
X520513Y1575686D03*
X525469D03*
X524691Y1578182D03*
X533351D03*
X521291D03*
X525813Y1599884D03*
X530769D03*
X518709D03*
X532573Y1587598D03*
Y1592590D03*
X525469D03*
X520513D03*
Y1587598D03*
X525469D03*
X524691Y1590094D03*
X533351D03*
X521291D03*
X525813Y1611796D03*
X530769D03*
X525813Y1604876D03*
X530769D03*
Y1616788D03*
X525813D03*
X518709D03*
Y1604876D03*
Y1611796D03*
X528937Y1675383D03*
Y1679920D03*
X521063Y1679320D03*
X528937Y1684454D03*
Y1689556D03*
Y1694093D03*
Y1698627D03*
X521063Y1688391D03*
Y1693493D03*
Y1698030D03*
Y1683857D03*
X528937Y1703729D03*
Y1708266D03*
Y1712800D03*
X521063Y1707666D03*
Y1712203D03*
Y1702564D03*
X528937Y1726974D03*
Y1722440D03*
Y1717903D03*
X521063Y1730911D03*
Y1726377D03*
Y1721840D03*
Y1716737D03*
X549589Y1580678D03*
X544633D03*
X549589Y1575592D03*
X544633D03*
X537529Y1575686D03*
Y1580678D03*
X536751Y1578182D03*
X548811D03*
X545411D03*
X549933Y1599790D03*
X537873Y1599884D03*
X542829D03*
X549589Y1592590D03*
X544633D03*
X549589Y1587598D03*
X544633D03*
X537529D03*
Y1592590D03*
X536751Y1590094D03*
X548811D03*
X545411D03*
X549933Y1611796D03*
Y1604876D03*
Y1616788D03*
X542829D03*
X537873D03*
Y1604876D03*
X542829D03*
X537873Y1611796D03*
X542829D03*
X544685Y1675383D03*
Y1679920D03*
X536811Y1679320D03*
X544685Y1684454D03*
Y1689556D03*
Y1694093D03*
Y1698627D03*
X536811Y1688391D03*
Y1693493D03*
Y1698030D03*
Y1683857D03*
X544685Y1703729D03*
Y1708266D03*
Y1712800D03*
X536811Y1707666D03*
Y1712203D03*
Y1702564D03*
X544685Y1726974D03*
Y1722440D03*
Y1717903D03*
X536811Y1730911D03*
Y1726377D03*
Y1721840D03*
Y1716737D03*
X556693Y1575686D03*
X561649D03*
X556693Y1580678D03*
X561649D03*
X560871Y1578182D03*
X557471D03*
X561993Y1599884D03*
X554889Y1599790D03*
X556693Y1587598D03*
X561649D03*
Y1592590D03*
X556693D03*
X560871Y1590094D03*
X557471D03*
X561993Y1616788D03*
Y1604876D03*
Y1611796D03*
X554889D03*
Y1604876D03*
Y1616788D03*
X552559Y1679320D03*
X564370Y1675383D03*
Y1679920D03*
X552559Y1688391D03*
Y1693493D03*
Y1698030D03*
Y1683857D03*
X564370Y1684454D03*
Y1689556D03*
Y1694093D03*
Y1698627D03*
X552559Y1707666D03*
Y1712203D03*
Y1702564D03*
X564370Y1703729D03*
Y1708266D03*
Y1712800D03*
X552559Y1730911D03*
Y1726377D03*
Y1721840D03*
Y1716737D03*
X564370Y1726974D03*
Y1722440D03*
Y1717903D03*
X580813Y1575686D03*
Y1580678D03*
X573709D03*
X568753D03*
Y1575686D03*
X573709D03*
X572931Y1578182D03*
X581591D03*
X569531D03*
X579009Y1599884D03*
X574053D03*
X566949D03*
X580813Y1587598D03*
Y1592590D03*
X573709D03*
X568753D03*
X573709Y1587598D03*
X568753D03*
X572931Y1590094D03*
X581591D03*
X569531D03*
X574053Y1616788D03*
X579009D03*
Y1611796D03*
X574053D03*
X579009Y1604876D03*
X574053D03*
X566949Y1616788D03*
Y1604876D03*
Y1611796D03*
X580118Y1675383D03*
Y1679920D03*
X572244Y1679320D03*
X580118Y1684454D03*
Y1689556D03*
Y1694093D03*
Y1698627D03*
X572244Y1688391D03*
Y1693493D03*
Y1698030D03*
Y1683857D03*
X580118Y1703729D03*
Y1708266D03*
Y1712800D03*
X572244Y1707666D03*
Y1712203D03*
Y1702564D03*
X580118Y1726974D03*
Y1722440D03*
Y1717903D03*
X572244Y1730911D03*
Y1726377D03*
Y1721840D03*
Y1716737D03*
X597829Y1580678D03*
X592873D03*
X597829Y1575686D03*
X592873D03*
X585769D03*
Y1580678D03*
X597051Y1578182D03*
X584991D03*
X593651D03*
X598173Y1599884D03*
X586113D03*
X591069D03*
X597829Y1592590D03*
X592873D03*
X597829Y1587598D03*
X592873D03*
X585769D03*
Y1592590D03*
X597051Y1590094D03*
X584991D03*
X593651D03*
X598173Y1616788D03*
Y1611796D03*
Y1604876D03*
X586113D03*
X591069D03*
X586113Y1611796D03*
X591069D03*
Y1616788D03*
X586113D03*
X595866Y1675383D03*
Y1679920D03*
X587992Y1679320D03*
X595866Y1684454D03*
Y1689556D03*
Y1694093D03*
Y1698627D03*
X587992Y1688391D03*
Y1693493D03*
Y1698030D03*
Y1683857D03*
X595866Y1703729D03*
Y1708266D03*
Y1712800D03*
X587992Y1707666D03*
Y1712203D03*
Y1702564D03*
X595866Y1726974D03*
Y1722440D03*
Y1717903D03*
X587992Y1730911D03*
Y1726377D03*
Y1721840D03*
Y1716737D03*
X609889Y1575686D03*
X604933D03*
X609889Y1580678D03*
X604933D03*
X609111Y1578182D03*
X605711D03*
X615189Y1599884D03*
X610233D03*
X603129D03*
X609889Y1587598D03*
X604933D03*
X609889Y1592590D03*
X604933D03*
X609111Y1590094D03*
X605711D03*
X615189Y1604876D03*
X610233D03*
X615189Y1611796D03*
X610233D03*
X615189Y1616788D03*
X610233D03*
X603129D03*
Y1611796D03*
Y1604876D03*
X611614Y1675383D03*
Y1679920D03*
X603740Y1679320D03*
X611614Y1684454D03*
Y1689556D03*
Y1694093D03*
Y1698627D03*
X603740Y1688391D03*
Y1693493D03*
Y1698030D03*
Y1683857D03*
X611614Y1703729D03*
Y1708266D03*
Y1712800D03*
X603740Y1707666D03*
Y1712203D03*
Y1702564D03*
X611614Y1726974D03*
Y1722440D03*
Y1717903D03*
X603740Y1730911D03*
Y1726377D03*
Y1721840D03*
Y1716737D03*
X629658Y766478D03*
X620005Y850459D03*
X630754D03*
X620899Y867192D03*
X629599D03*
X620058Y857152D03*
X630481D03*
X620899Y880577D03*
X629599D03*
X620899Y873885D03*
X629599D03*
X630756Y893963D03*
X620899D03*
X629599Y887270D03*
X620899D03*
Y910696D03*
X629599D03*
Y917389D03*
X620899D03*
X629599Y904003D03*
X620899D03*
X630399Y930697D03*
X619905Y930774D03*
X620899Y924081D03*
X629599D03*
Y947507D03*
X620899D03*
X619964Y940814D03*
X630777D03*
X629599Y964239D03*
X620899D03*
X629599Y954200D03*
X620899D03*
Y977625D03*
X629599D03*
Y970932D03*
X620899D03*
Y991011D03*
X629599D03*
Y984318D03*
X620899D03*
Y1031168D03*
X629599D03*
X620899Y1017782D03*
X629599D03*
X620899Y1024475D03*
X629599D03*
X620899Y1044554D03*
X629599D03*
X620899Y1037861D03*
X629599D03*
X620899Y1057940D03*
X629599D03*
Y1051247D03*
X620899D03*
Y1061286D03*
Y1078018D03*
X629599D03*
X630399Y1071326D03*
X619999D03*
X620899Y1064633D03*
X629599D03*
X620899Y1088058D03*
X629599D03*
Y1094751D03*
X620899D03*
Y1108137D03*
X629599D03*
Y1101444D03*
X620899D03*
X630363Y1124674D03*
X620369Y1124969D03*
X630399Y1114829D03*
X620099D03*
X620899Y1131562D03*
X629599D03*
Y1144948D03*
X620899D03*
X629599Y1138255D03*
X620899D03*
X620511Y1161680D03*
X629833Y1161581D03*
X629599Y1151641D03*
X620899D03*
X629599Y1175066D03*
X620899D03*
X629599Y1168373D03*
X620899D03*
X630623Y1188452D03*
X620899D03*
X629599Y1181759D03*
X620899D03*
X629599Y1205184D03*
X620899D03*
Y1198491D03*
X629599D03*
X620899Y1225263D03*
X629599D03*
Y1218570D03*
X620899D03*
X629599Y1211877D03*
X620899D03*
X629599Y1241995D03*
X620899D03*
X630922Y1235302D03*
X620036D03*
X620899Y1248688D03*
X629599D03*
X629931Y1258727D03*
X632080Y1262074D03*
X629699Y1255381D03*
X625246Y1273164D03*
X627646D03*
X631270Y1264942D03*
X629053Y1575686D03*
Y1580678D03*
X621949D03*
X616993D03*
X621949Y1575686D03*
X616993D03*
X621171Y1578182D03*
X629831D03*
X617771D03*
X622293Y1599884D03*
X627249D03*
X629053Y1587598D03*
Y1592590D03*
X621949D03*
X616993D03*
X621949Y1587598D03*
X616993D03*
X621171Y1590094D03*
X629831D03*
X617771D03*
X627249Y1616788D03*
X622293D03*
Y1611796D03*
X627249D03*
X622293Y1604876D03*
X627249D03*
X619488Y1679320D03*
Y1688391D03*
Y1693493D03*
Y1698030D03*
Y1683857D03*
Y1707666D03*
Y1712203D03*
Y1702564D03*
Y1730911D03*
Y1726377D03*
Y1721840D03*
Y1716737D03*
X637041Y847113D03*
X645801D03*
X646819Y853806D03*
X636332Y853955D03*
X645918Y863845D03*
X636266D03*
X637041Y877231D03*
X645741D03*
X637041Y870538D03*
X645741D03*
Y883924D03*
X637041D03*
Y900656D03*
X645741D03*
X637041Y890617D03*
X645741D03*
X637041Y914042D03*
X645741D03*
Y907349D03*
X637041D03*
X646393Y927526D03*
X636026Y927428D03*
X645741Y920735D03*
X637041D03*
X645741Y944160D03*
X637041D03*
X636170Y937467D03*
X646703D03*
X645741Y960892D03*
X637041D03*
Y950853D03*
X645741D03*
X636941Y957546D03*
Y954200D03*
X637041Y980971D03*
X645741D03*
X637041Y974278D03*
X645741D03*
X637041Y967585D03*
X645741D03*
X637041Y987664D03*
X645741D03*
X644257Y1000325D03*
X637041Y1027822D03*
X645741D03*
Y1017782D03*
X637041D03*
X645741Y1047900D03*
X637041D03*
Y1041207D03*
X645741D03*
X637041Y1034515D03*
X645741D03*
X637041Y1061286D03*
X645741D03*
Y1054593D03*
X637041D03*
X636141Y1074672D03*
X646541D03*
X645741Y1067979D03*
X636841D03*
X637041Y1091404D03*
X645741D03*
Y1084711D03*
X636241D03*
X645741Y1111483D03*
X637041D03*
X645741Y1098097D03*
X637041D03*
X645741Y1104790D03*
X637041D03*
Y1121522D03*
X645741D03*
X637041Y1128915D03*
X645741Y1128215D03*
X646584Y1135108D03*
X635744Y1134908D03*
X645741Y1141601D03*
X637041D03*
X645741Y1148294D03*
X637041D03*
X645741Y1158333D03*
X637041D03*
Y1171719D03*
X645741D03*
Y1165026D03*
X637041D03*
Y1185105D03*
X645741D03*
Y1178412D03*
X637041D03*
X645741Y1208530D03*
X637041D03*
X645741Y1201837D03*
X637041D03*
Y1195144D03*
X645741D03*
X636005Y1221916D03*
X646570D03*
X645741Y1215223D03*
X637041D03*
X645741Y1238648D03*
X637041D03*
X635995Y1231862D03*
X646539Y1231955D03*
X645741Y1245341D03*
X637041D03*
X634213Y1258679D03*
X636946Y1258414D03*
X647690Y1260812D03*
X637041Y1252034D03*
X645897Y1248785D03*
X647877Y1254076D03*
X642746Y1273364D03*
X639946D03*
X636877Y1261235D03*
X646069Y1580678D03*
X641113D03*
X646069Y1575592D03*
X641113D03*
X634009Y1575686D03*
Y1580678D03*
X645291Y1578182D03*
X633231D03*
X641891D03*
X646413Y1599790D03*
X639309Y1599884D03*
X634353D03*
X646069Y1592590D03*
X641113D03*
X646069Y1587598D03*
X641113D03*
X634009D03*
Y1592590D03*
X645291Y1590094D03*
X633231D03*
X641891D03*
X646413Y1616788D03*
Y1611796D03*
Y1604876D03*
X639309D03*
X634353D03*
X639309Y1611796D03*
X634353D03*
Y1616788D03*
X639309D03*
X667677Y441636D03*
X659299Y850459D03*
X650599D03*
X659299Y857152D03*
X650599D03*
X649563Y867192D03*
X660299D03*
X659299Y873885D03*
X650599D03*
Y880577D03*
X659299D03*
X650599Y893963D03*
X659299D03*
X650599Y887270D03*
X659299D03*
Y917389D03*
X650599D03*
X659299Y910696D03*
X650599D03*
Y904003D03*
X659299D03*
X660504Y924081D03*
X650599D03*
X660174Y930774D03*
X649661D03*
X659299Y947507D03*
X650599D03*
X659299Y940814D03*
X650599D03*
X659299Y964239D03*
X650599D03*
Y954200D03*
X659299D03*
Y977625D03*
X650599D03*
X659299Y970932D03*
X650599D03*
X659299Y991011D03*
X650599D03*
X659299Y984318D03*
X650599D03*
X659299Y1031168D03*
X650599D03*
X659299Y1017782D03*
X650599D03*
X659299Y1024475D03*
X650599D03*
X659299Y1044554D03*
X650599D03*
X659299Y1037861D03*
X650599D03*
X659299Y1051247D03*
X650599D03*
Y1057940D03*
X659299D03*
X660099Y1078018D03*
X649799D03*
X659299Y1071326D03*
X650599D03*
X659299Y1064633D03*
X650599D03*
X659299Y1094751D03*
X650599D03*
X660099Y1088058D03*
X649799D03*
X650599Y1108137D03*
X659299D03*
X650599Y1101444D03*
X659299D03*
X660199Y1124869D03*
X649932Y1124640D03*
X659299Y1114829D03*
X650599D03*
X659299Y1130762D03*
X650599D03*
X659299Y1138255D03*
X650599D03*
X659299Y1144948D03*
X650599D03*
X659299Y1151641D03*
X650599D03*
Y1161680D03*
X659299D03*
X650599Y1175066D03*
X659299D03*
X650599Y1168373D03*
X659299D03*
X650599Y1188452D03*
X659299D03*
X650599Y1181759D03*
X659299D03*
X650599Y1205184D03*
X659299D03*
X650599Y1198491D03*
X659299D03*
X660070Y1225263D03*
X649913D03*
X659299Y1218570D03*
X650599D03*
X659299Y1211877D03*
X650599D03*
X659299Y1241995D03*
X650599D03*
X660234Y1235302D03*
X649701D03*
X650599Y1248688D03*
X659299D03*
X659546Y1257664D03*
X650599Y1258727D03*
X666741Y1255381D03*
X664630Y1259442D03*
X656446Y1273364D03*
X653646D03*
X649587Y1266766D03*
X661400Y1263522D03*
X654606Y1431203D03*
X653173Y1575686D03*
X658129D03*
X653173Y1580678D03*
X658129D03*
X657351Y1578182D03*
X653951D03*
X663429Y1599884D03*
X658473D03*
X651369Y1599790D03*
X653173Y1587598D03*
X658129D03*
X653173Y1592590D03*
X658129D03*
X657351Y1590094D03*
X653951D03*
X663429Y1604876D03*
X658473D03*
X663429Y1611796D03*
X658473D03*
Y1616788D03*
X663429D03*
X651369D03*
Y1611796D03*
Y1604876D03*
X668329Y411714D03*
X674628Y424313D03*
X671479Y421163D03*
X667660Y429037D03*
X674628Y427462D03*
Y414864D03*
X677778D03*
Y424313D03*
X671479Y414864D03*
X674628Y421163D03*
Y418013D03*
X677778D03*
Y421163D03*
X668329D03*
X677778Y427462D03*
Y430612D03*
X674628Y436911D03*
Y443210D03*
X671479Y430612D03*
Y436911D03*
X677778Y433761D03*
X668329Y436911D03*
X677778Y440061D03*
X674628D03*
X677778Y436911D03*
Y443210D03*
X680928Y440061D03*
X674628Y430612D03*
X671479Y443211D03*
Y462108D03*
X677778Y449510D03*
X668329Y452659D03*
X674628D03*
X671479D03*
X677778D03*
X668329Y455809D03*
X671479Y458959D03*
X674628D03*
X668329D03*
X677778D03*
Y455809D03*
X674628D03*
X668067Y462090D03*
X677778Y462108D03*
X671479Y455809D03*
X680928Y458959D03*
X674628Y449510D03*
Y462108D03*
X677778Y477856D03*
Y471557D03*
Y474707D03*
X671479Y465258D03*
X674628D03*
X668329D03*
X677778D03*
Y468407D03*
X671479Y481006D03*
X667350Y470680D03*
X671479Y474707D03*
X674628Y484006D03*
X668329Y481006D03*
X680299Y766798D03*
X675441Y847113D03*
X666741D03*
X680299Y850459D03*
X676417Y853806D03*
X665890D03*
X680299Y867192D03*
Y857152D03*
X665916Y863845D03*
X676600D03*
X675441Y877231D03*
X666741D03*
X675441Y870538D03*
X666741D03*
Y883924D03*
X675441D03*
X680299Y880577D03*
Y873885D03*
X666741Y900656D03*
X675441D03*
X680299Y893963D03*
Y887270D03*
X666741Y890617D03*
X675441D03*
Y914042D03*
X666741D03*
X680299Y917389D03*
Y910696D03*
Y904003D03*
X666741Y907349D03*
X675441D03*
X676488Y927428D03*
X665896D03*
X675441Y920735D03*
X666741D03*
X680299Y930774D03*
Y924081D03*
X675441Y944160D03*
X666741D03*
X676359Y937467D03*
X665923D03*
X680299Y947507D03*
Y940814D03*
Y964239D03*
X675441Y960892D03*
X666741D03*
X680299Y954200D03*
X666741Y950853D03*
X675441D03*
X666641Y957546D03*
Y954200D03*
X675441Y980971D03*
X666741D03*
X680299Y970932D03*
X675441Y974278D03*
X666741D03*
X675441Y967585D03*
X666741D03*
X680299Y977625D03*
X675441Y987664D03*
X666741D03*
X680299Y991011D03*
Y984318D03*
X672063Y998632D03*
X680299Y1031168D03*
Y1024475D03*
X675441Y1027822D03*
X666741D03*
X675441Y1017782D03*
X666741D03*
X680299D03*
X675441Y1047900D03*
X666741D03*
X680299Y1037861D03*
X675441Y1041207D03*
X666741D03*
X675441Y1034515D03*
X666741D03*
X680299Y1044554D03*
Y1057940D03*
Y1051247D03*
X675441Y1054593D03*
X666741D03*
Y1061286D03*
X675441D03*
X680299D03*
X676341Y1074672D03*
X665841D03*
X675441Y1067979D03*
X666741D03*
X680299Y1078018D03*
Y1071326D03*
Y1064633D03*
X675441Y1091404D03*
X666741D03*
X676241Y1084711D03*
X665941D03*
X680299Y1094751D03*
Y1088058D03*
X666741Y1111483D03*
X675441D03*
X680299Y1108137D03*
Y1101444D03*
X666741Y1104790D03*
X675441D03*
X666741Y1098097D03*
X675441D03*
X666741Y1128215D03*
X675441D03*
X680299Y1124869D03*
Y1114829D03*
X666741Y1121522D03*
X675441D03*
X680299Y1144948D03*
Y1138255D03*
Y1131562D03*
X666741Y1141601D03*
X675441D03*
X666741Y1134908D03*
X675441D03*
X676652Y1148294D03*
X665602D03*
X676241Y1158333D03*
X665941D03*
X680299Y1161680D03*
Y1151641D03*
X675441Y1165026D03*
X666741D03*
X680299Y1175066D03*
Y1168373D03*
X666741Y1171719D03*
X675441D03*
X680299Y1188452D03*
Y1181759D03*
X666741Y1185105D03*
X675441D03*
X666741Y1178412D03*
X675441D03*
X680299Y1205184D03*
Y1198491D03*
X666741Y1208530D03*
X675441D03*
X666741Y1201837D03*
X675441D03*
X666741Y1195144D03*
X675441D03*
X680299Y1218570D03*
Y1225263D03*
X676448Y1221916D03*
X665651D03*
X675441Y1215223D03*
X666741D03*
X680299Y1211877D03*
X675441Y1238648D03*
X666741D03*
X676462Y1231955D03*
X665912D03*
X680299Y1241995D03*
Y1235302D03*
X675441Y1245341D03*
X666741D03*
X676046Y1257964D03*
X680299Y1248688D03*
Y1258727D03*
X666741Y1252034D03*
X675537Y1248885D03*
X677980Y1262074D03*
X672446Y1273364D03*
X669646D03*
X666741Y1262074D03*
X666646Y1264464D03*
X680046Y1264964D03*
X684077Y414864D03*
X680928Y424313D03*
X687227Y414864D03*
X690376Y421163D03*
Y418013D03*
Y414864D03*
X693526Y427462D03*
X687227Y424313D03*
X690376Y427462D03*
X680928Y414864D03*
Y418013D03*
X684077Y421163D03*
X680928Y427462D03*
X684077Y418013D03*
Y427462D03*
X680928Y421163D03*
X684077Y424313D03*
X687227Y427462D03*
X696676D03*
X693526Y421163D03*
Y424313D03*
X690376D03*
X696676Y421163D03*
Y424313D03*
Y418013D03*
Y436911D03*
X693526Y443210D03*
Y440061D03*
Y436911D03*
X690376Y440061D03*
Y433761D03*
X680928Y436911D03*
Y433761D03*
X693526Y430612D03*
X696676Y440061D03*
Y443210D03*
X684077Y430612D03*
Y440061D03*
X687227Y436911D03*
Y443210D03*
X684077D03*
Y436911D03*
X680928Y443210D03*
X690376Y436911D03*
Y443210D03*
X687227Y440061D03*
X693526Y433761D03*
X696676D03*
X684077D03*
X687227Y430612D03*
X690376D03*
X696676D03*
X687227Y433761D03*
X680928Y430612D03*
X687227Y462108D03*
X693526Y452659D03*
Y449510D03*
X696676Y455809D03*
X693526D03*
X690376Y452659D03*
Y458959D03*
X680928Y455809D03*
X693526Y462108D03*
X680928Y449510D03*
X687227D03*
X690376Y462108D03*
X684077Y449510D03*
X680928Y452659D03*
X684077D03*
X687227Y455809D03*
X684077D03*
X680928Y462108D03*
X696676Y449510D03*
Y452659D03*
X690376Y449510D03*
Y455809D03*
X687227Y452659D03*
X693526Y458959D03*
X696676D03*
Y462108D03*
X687227Y458959D03*
X684077D03*
Y468407D03*
X687227Y471557D03*
Y474707D03*
Y477856D03*
X684077Y471557D03*
X690376Y465258D03*
X684077D03*
X680928Y471557D03*
Y474707D03*
Y477856D03*
X696676D03*
X684077D03*
X680928Y468407D03*
X693526Y465258D03*
Y471557D03*
X690376Y468407D03*
Y477856D03*
Y471557D03*
X687227Y465258D03*
X690376Y474707D03*
X687227Y468407D03*
X693526D03*
X684077Y474707D03*
X696676Y465258D03*
Y474707D03*
Y468407D03*
X693526Y474707D03*
X696676Y471557D03*
X693526Y477856D03*
X696441Y847113D03*
X688999Y850459D03*
X696441Y863845D03*
Y853806D03*
X688999Y867192D03*
X689896Y857152D03*
X696441Y883924D03*
Y877231D03*
Y870538D03*
X688999Y880577D03*
Y873885D03*
X696441Y900656D03*
Y890617D03*
X688999Y893963D03*
Y887270D03*
X696441Y914042D03*
Y907349D03*
X688999Y917389D03*
Y910696D03*
Y904003D03*
X696441Y927428D03*
Y920735D03*
X690104Y930774D03*
X688999Y924081D03*
X696441Y944160D03*
Y937467D03*
X688999Y947507D03*
Y940814D03*
X696441Y960892D03*
Y950853D03*
X688999Y964239D03*
Y954200D03*
X696441Y957546D03*
Y954200D03*
Y980971D03*
Y974278D03*
Y967585D03*
X688999Y970932D03*
Y977625D03*
X696441Y987664D03*
X688999Y991011D03*
Y984318D03*
X696441Y994357D03*
Y1027822D03*
Y1017782D03*
X688999Y1031168D03*
Y1024475D03*
Y1017782D03*
X696441Y1047900D03*
Y1041207D03*
Y1034515D03*
X688999Y1037861D03*
Y1044554D03*
X696441Y1054593D03*
Y1061286D03*
X688999Y1057940D03*
Y1051247D03*
X696441Y1074672D03*
Y1067979D03*
X688999Y1077118D03*
Y1071326D03*
Y1064633D03*
X696441Y1091404D03*
Y1084711D03*
X688999Y1094751D03*
Y1088058D03*
X696441Y1111483D03*
Y1104790D03*
Y1098097D03*
X688999Y1108137D03*
Y1101444D03*
X696441Y1128215D03*
Y1121522D03*
X688999Y1124869D03*
Y1114829D03*
X696441Y1141601D03*
Y1134908D03*
X688999Y1144948D03*
Y1138255D03*
Y1131562D03*
X696441Y1158333D03*
Y1148294D03*
X688999Y1161680D03*
X689999Y1151641D03*
X696441Y1171719D03*
Y1165026D03*
X688999Y1175066D03*
Y1168373D03*
X696441Y1185105D03*
Y1178412D03*
X688999Y1188452D03*
Y1181759D03*
X696441Y1208530D03*
Y1201837D03*
Y1195144D03*
X688999Y1205184D03*
Y1198491D03*
X696441Y1221916D03*
Y1215223D03*
X688999Y1218570D03*
X689799Y1225263D03*
X688999Y1211877D03*
X696441Y1238648D03*
Y1231955D03*
X688999Y1241995D03*
Y1235302D03*
X688916Y1256964D03*
X696441Y1245341D03*
X688999Y1248688D03*
X696441Y1255381D03*
X694100Y1261562D03*
X696441Y1248688D03*
X692233Y1252480D03*
X686146Y1273364D03*
X683346D03*
X696046Y1263764D03*
X706125Y421163D03*
X702975Y414864D03*
X706125Y418013D03*
X712424Y424313D03*
X699825Y427462D03*
X699826Y414864D03*
X699825Y424313D03*
X709274Y436911D03*
X706125Y440061D03*
Y436911D03*
X699825Y440061D03*
Y436911D03*
X712424Y443210D03*
Y440061D03*
Y436911D03*
Y430612D03*
X709274Y440061D03*
Y443210D03*
X706125D03*
X699825D03*
X709274Y433761D03*
X712424D03*
X699825D03*
X706125D03*
X699825Y430612D03*
X706125Y462108D03*
X709274D03*
X712424D03*
Y455809D03*
X709274D03*
X706125D03*
Y452659D03*
X699825Y455809D03*
Y452659D03*
X712424D03*
Y449510D03*
X709274D03*
X699825D03*
X706125D03*
X709274Y452659D03*
X699825Y458959D03*
X706125D03*
X709274D03*
X712424D03*
X699825Y462108D03*
X709274Y474707D03*
Y471557D03*
Y465258D03*
Y468407D03*
X712424Y474707D03*
Y468407D03*
Y465258D03*
X709274Y477856D03*
X699825Y468407D03*
X706125Y471557D03*
Y468407D03*
X699825Y471557D03*
Y474707D03*
X706125Y477856D03*
X699825Y465258D03*
X712424Y471557D03*
X706125Y481006D03*
X709899Y766798D03*
X705141Y847113D03*
X709999Y850459D03*
X705141Y863845D03*
Y853806D03*
X709999Y867192D03*
Y857152D03*
X705141Y883924D03*
Y877231D03*
Y870538D03*
X709999Y880577D03*
Y873885D03*
X705141Y900656D03*
Y890617D03*
X709999Y893963D03*
Y887270D03*
X705141Y914042D03*
Y907349D03*
X709999Y917389D03*
Y910696D03*
Y904003D03*
X705141Y927428D03*
Y920735D03*
X709999Y930774D03*
Y924081D03*
X705141Y944160D03*
Y937467D03*
X709999Y947507D03*
Y940814D03*
X705141Y960892D03*
Y950853D03*
X709999Y964239D03*
Y954200D03*
X705141Y980971D03*
Y974278D03*
Y967585D03*
X709999Y977625D03*
Y970932D03*
X705141Y987664D03*
X709999Y991011D03*
Y984318D03*
X705141Y1027822D03*
Y1017782D03*
X709999Y1031168D03*
Y1024475D03*
Y1017782D03*
X705141Y1047900D03*
Y1041207D03*
Y1034515D03*
X709999Y1044554D03*
Y1037861D03*
X705141Y1054593D03*
Y1061286D03*
X709999Y1057940D03*
Y1051247D03*
X705141Y1074672D03*
Y1067979D03*
X709999Y1078018D03*
Y1071326D03*
Y1064633D03*
X705141Y1091404D03*
Y1084711D03*
X709999Y1094751D03*
Y1088058D03*
X705141Y1111483D03*
Y1104790D03*
Y1098097D03*
X709999Y1108137D03*
Y1101444D03*
X705141Y1128215D03*
Y1121522D03*
X709999Y1124869D03*
Y1114829D03*
X705141Y1141601D03*
Y1134908D03*
X709999Y1144948D03*
Y1138255D03*
Y1131562D03*
X705141Y1158333D03*
Y1148294D03*
X709999Y1161680D03*
Y1151641D03*
X705141Y1171719D03*
Y1165026D03*
X709999Y1175066D03*
Y1168373D03*
X705141Y1185105D03*
Y1178412D03*
X709999Y1188452D03*
Y1181759D03*
X705141Y1208530D03*
Y1201837D03*
Y1195144D03*
X709999Y1205184D03*
Y1198491D03*
X705141Y1221916D03*
Y1215223D03*
X709999Y1225263D03*
Y1218570D03*
Y1211877D03*
X705141Y1238648D03*
Y1231955D03*
X709999Y1241995D03*
Y1235302D03*
X705141Y1245341D03*
X709999Y1248688D03*
Y1258727D03*
X708090Y1262074D03*
X705037Y1252034D03*
X706493Y1256563D03*
X713046Y1273364D03*
X702146D03*
X699346D03*
X705167Y1262074D03*
X709977Y1264985D03*
X721873Y427462D03*
X725022D03*
X728172Y418013D03*
X725022Y414864D03*
X718723Y418013D03*
X715574Y427462D03*
X728172Y421163D03*
X718723Y414864D03*
X725022Y424313D03*
X721873D03*
X725022Y421163D03*
X728172Y427462D03*
X731322Y421163D03*
X725022Y418013D03*
X718723Y427462D03*
Y424313D03*
Y421163D03*
X715574Y424313D03*
Y421163D03*
Y418013D03*
X728172Y424313D03*
X718723Y436911D03*
X721873Y433761D03*
Y436911D03*
Y440061D03*
Y430612D03*
X718723Y433761D03*
Y440061D03*
X725022Y436911D03*
Y433761D03*
X728172D03*
X715574D03*
X718723Y430612D03*
X715574D03*
X725022D03*
X728172Y436911D03*
X715574D03*
Y440061D03*
Y443210D03*
X728172D03*
Y430612D03*
X725022Y440061D03*
X718723Y443210D03*
X721873D03*
X725022D03*
X728172Y440061D03*
X731322D03*
X728172Y455809D03*
Y458959D03*
X718723Y455809D03*
X721873Y458959D03*
X715574D03*
X728172Y449510D03*
X721873Y452659D03*
X725022D03*
X728172D03*
X715574Y462108D03*
X725022Y458959D03*
X721873Y455809D03*
X725022Y462108D03*
X718723Y452659D03*
X715574Y449510D03*
Y452659D03*
Y455809D03*
X728172Y462108D03*
X718723Y449510D03*
X721873D03*
X725022D03*
X718723Y458959D03*
X721873Y462108D03*
X718723D03*
X725022Y468407D03*
X721873Y465258D03*
Y477856D03*
X725022D03*
X718723Y468407D03*
X715574Y474707D03*
Y471557D03*
Y468407D03*
Y465258D03*
X718723Y474707D03*
Y471557D03*
X728172Y477856D03*
X721873Y471557D03*
X725022D03*
X718723Y465258D03*
X728172D03*
X725022Y474707D03*
X728172Y468407D03*
X721873Y474707D03*
Y468407D03*
X728172Y474707D03*
Y471557D03*
X725022Y465258D03*
X718723Y477856D03*
X725132Y481116D03*
X728272Y481006D03*
X726041Y957546D03*
Y954200D03*
Y994357D03*
X726141Y1057940D03*
Y1255381D03*
X723700Y1258727D03*
X726141Y1248688D03*
X729046Y1273364D03*
X715846D03*
X737621Y411714D03*
X734471Y418013D03*
X731322Y427462D03*
Y418013D03*
X734471Y421163D03*
X731322Y424313D03*
X734471D03*
X737621D03*
X731322Y414864D03*
Y433761D03*
Y430612D03*
X734471Y436911D03*
X731322D03*
X734471Y443210D03*
X737621D03*
X731322D03*
Y455809D03*
X737621Y458959D03*
X731322D03*
Y462108D03*
X734471Y452659D03*
X731322D03*
Y449510D03*
X734471Y458959D03*
X731322Y465258D03*
Y477856D03*
X737621Y471557D03*
X734471Y468407D03*
X731322D03*
X731321Y474707D03*
X731322Y471557D03*
X737621Y481006D03*
X734471D03*
X739699Y766798D03*
Y1061286D03*
Y1258727D03*
X734967Y1252034D03*
X737580Y1262074D03*
X745546Y1273364D03*
X742746D03*
X731372Y1273464D03*
X755841Y957546D03*
Y954200D03*
Y994357D03*
X755541Y1057940D03*
X750890Y1248500D03*
X755890Y1255381D03*
X753000Y1261352D03*
X755841Y1252034D03*
Y1248688D03*
X750040Y1254179D03*
X758746Y1273364D03*
X761546D03*
X769399Y766798D03*
Y1258727D03*
X767080Y1262074D03*
X766148Y1255882D03*
X772446Y1273364D03*
X775246D03*
X785541Y957546D03*
Y954200D03*
Y994357D03*
Y1255381D03*
X783130Y1259372D03*
X794157Y1252034D03*
X785541Y1248688D03*
X796880Y1262074D03*
X796280Y1254402D03*
X788446Y1273364D03*
X791246D03*
X797417Y767345D03*
X799099Y780184D03*
Y773491D03*
Y786877D03*
Y803609D03*
Y796916D03*
Y790223D03*
Y847113D03*
Y853806D03*
Y860499D03*
Y863845D03*
Y883924D03*
Y877231D03*
Y870538D03*
Y890617D03*
Y897310D03*
Y900656D03*
Y914042D03*
Y907349D03*
Y927428D03*
Y920735D03*
Y934121D03*
Y944160D03*
Y937467D03*
Y950853D03*
Y980971D03*
Y974278D03*
Y994357D03*
Y987664D03*
Y1027822D03*
Y1021129D03*
Y1047900D03*
Y1041207D03*
Y1034515D03*
Y1061286D03*
Y1054593D03*
Y1074672D03*
Y1067979D03*
Y1091404D03*
Y1081365D03*
Y1084711D03*
Y1098097D03*
Y1111483D03*
Y1104790D03*
Y1128215D03*
Y1118176D03*
Y1121522D03*
Y1141601D03*
Y1134908D03*
Y1148294D03*
Y1154987D03*
Y1158333D03*
Y1171719D03*
Y1165026D03*
Y1185105D03*
Y1178412D03*
Y1191798D03*
Y1208530D03*
Y1201837D03*
Y1195144D03*
Y1258727D03*
X812440D03*
X804946Y1273364D03*
X802146D03*
X815241Y770144D03*
Y776837D03*
Y786877D03*
Y783530D03*
Y800263D03*
Y793570D03*
Y850459D03*
Y843766D03*
Y867192D03*
Y860499D03*
Y857152D03*
Y873885D03*
Y880577D03*
Y887270D03*
Y897310D03*
Y893963D03*
Y917389D03*
Y910696D03*
Y904003D03*
Y924081D03*
Y934121D03*
Y930774D03*
Y947507D03*
Y940814D03*
Y957546D03*
Y954200D03*
Y977625D03*
Y970932D03*
Y991011D03*
Y984318D03*
Y994357D03*
Y1021129D03*
Y1024475D03*
Y1031168D03*
Y1044554D03*
Y1037861D03*
X814941Y1051247D03*
X815241Y1071325D03*
Y1064633D03*
Y1078018D03*
Y1094751D03*
Y1088058D03*
Y1081365D03*
Y1108136D03*
Y1101444D03*
Y1124869D03*
Y1118176D03*
Y1114829D03*
Y1144947D03*
Y1138255D03*
Y1131562D03*
Y1161680D03*
Y1154987D03*
Y1151640D03*
Y1175066D03*
Y1168373D03*
Y1181758D03*
Y1191798D03*
Y1188451D03*
Y1205184D03*
Y1198491D03*
Y1255381D03*
X826750Y1262074D03*
X823877Y1252034D03*
X815241Y1248688D03*
X826501Y1254553D03*
X820946Y1273364D03*
X818146D03*
X828699Y766798D03*
X828799Y1054593D03*
Y1258727D03*
X842630Y1256912D03*
X839246Y1273064D03*
X842046D03*
X831846Y1273364D03*
X834646D03*
X844841Y957546D03*
Y954200D03*
Y994357D03*
X844941Y1021129D03*
Y1024475D03*
Y1051247D03*
Y1258727D03*
Y1252034D03*
X844997Y1248155D03*
X1001970Y1251522D03*
X1003831Y1259077D03*
X1002070Y1256942D03*
X1003841Y1262074D03*
X1012769Y766798D03*
X1019983Y994357D03*
X1012541Y1054593D03*
X1012543Y1257198D03*
X1017900Y1247632D03*
X1019983Y1255381D03*
Y1252034D03*
Y1248688D03*
X1017111Y1273299D03*
X1014111D03*
X1033441Y766798D03*
X1028683Y957546D03*
Y954200D03*
Y1021129D03*
Y1024475D03*
Y1051247D03*
X1033541Y1258727D03*
X1030830Y1261302D03*
X1030270Y1256042D03*
X1036588Y1273344D03*
X1022888D03*
X1025688D03*
X1042241Y780184D03*
Y773491D03*
Y786877D03*
Y803609D03*
Y796916D03*
Y790223D03*
Y847113D03*
Y853806D03*
Y860499D03*
Y863845D03*
Y883924D03*
Y877231D03*
Y870538D03*
Y890617D03*
Y897310D03*
Y900656D03*
Y914042D03*
Y907349D03*
Y927428D03*
Y920735D03*
Y934121D03*
Y944160D03*
Y937467D03*
Y950853D03*
Y980971D03*
Y974278D03*
Y994357D03*
Y987664D03*
Y1027822D03*
Y1021129D03*
Y1047900D03*
Y1041207D03*
Y1034515D03*
Y1061286D03*
Y1054593D03*
Y1074672D03*
Y1067979D03*
Y1091404D03*
Y1081365D03*
Y1084711D03*
Y1098097D03*
Y1111483D03*
Y1104790D03*
Y1128215D03*
Y1118176D03*
Y1121522D03*
Y1141601D03*
Y1134908D03*
Y1148294D03*
Y1154987D03*
Y1158333D03*
Y1171719D03*
Y1165026D03*
Y1185105D03*
Y1178412D03*
Y1191798D03*
Y1208530D03*
Y1201837D03*
Y1195144D03*
X1042331Y1257488D03*
X1047010Y1259222D03*
X1049683Y1258727D03*
X1052588Y1273344D03*
X1039388D03*
X1044930Y1263492D03*
X1058383Y770144D03*
X1063141Y766798D03*
X1058383Y776837D03*
Y786877D03*
Y783530D03*
Y800263D03*
Y793570D03*
Y850459D03*
Y843766D03*
Y867192D03*
Y860499D03*
Y857152D03*
Y873885D03*
Y880577D03*
Y887270D03*
Y897310D03*
Y893963D03*
Y917389D03*
Y910696D03*
Y904003D03*
Y924081D03*
Y934121D03*
Y930774D03*
Y947507D03*
Y940814D03*
Y957546D03*
Y954200D03*
Y977625D03*
Y970932D03*
Y991011D03*
Y984318D03*
Y994357D03*
Y1021129D03*
Y1024475D03*
Y1031168D03*
Y1044554D03*
Y1037861D03*
Y1051247D03*
Y1071326D03*
Y1064633D03*
Y1078018D03*
Y1094751D03*
Y1088058D03*
Y1081365D03*
Y1108137D03*
Y1101444D03*
Y1124869D03*
Y1118176D03*
Y1114829D03*
Y1144948D03*
Y1138255D03*
Y1131562D03*
Y1161680D03*
Y1154987D03*
Y1151641D03*
Y1175066D03*
Y1168373D03*
Y1181759D03*
Y1191798D03*
Y1188452D03*
Y1205184D03*
Y1198491D03*
X1063241Y1258727D03*
X1061330Y1262074D03*
X1058383Y1248688D03*
X1059410Y1252272D03*
X1069088Y1273344D03*
X1066288D03*
X1055388D03*
X1079383Y994357D03*
X1071991Y1257262D03*
X1076520Y1259072D03*
X1079383Y1258727D03*
X1088262Y1252293D03*
X1085088Y1273344D03*
X1082288D03*
X1092709Y766775D03*
X1088083Y957546D03*
Y954200D03*
X1101641Y1061286D03*
X1101554Y1257102D03*
X1090273Y1246800D03*
X1092941Y1258727D03*
X1088083Y1248688D03*
X1091000Y1262074D03*
X1106200Y1250162D03*
X1098788Y1273344D03*
X1095988D03*
X1103530Y1263602D03*
X1117783Y957546D03*
Y954200D03*
Y994357D03*
Y1057940D03*
X1120800Y1262074D03*
X1117783Y1248688D03*
X1111988Y1273344D03*
X1114788D03*
X1106740Y1267902D03*
X1122541Y766798D03*
X1131341Y867192D03*
X1122641D03*
X1131341Y880577D03*
X1122641D03*
X1131341Y873885D03*
X1122641D03*
X1131341Y893963D03*
X1122641D03*
X1131341Y887270D03*
X1122641D03*
X1131341Y917389D03*
X1122641D03*
X1131341Y910696D03*
X1122641D03*
X1131341Y904003D03*
X1122641D03*
X1131341Y930774D03*
X1122641D03*
X1131341Y924081D03*
X1122641D03*
Y947507D03*
X1131341D03*
Y940814D03*
X1122641D03*
X1131341Y964239D03*
X1122641D03*
X1131341Y954200D03*
X1122641D03*
X1131341Y977625D03*
X1122641D03*
X1131341Y970932D03*
X1122641D03*
X1131341Y991011D03*
X1122641D03*
X1131341Y984318D03*
X1122641D03*
X1131341Y1031168D03*
X1122641D03*
X1131341Y1024475D03*
X1122641D03*
X1131341Y1017782D03*
X1122641D03*
X1131341Y1044554D03*
X1122641D03*
X1131341Y1037861D03*
X1122641D03*
X1131341Y1057940D03*
X1122641D03*
X1131341Y1051247D03*
X1122641D03*
X1131341Y1078018D03*
X1122641D03*
X1131341Y1071326D03*
X1122641D03*
X1131341Y1064633D03*
X1122641D03*
X1131341Y1094751D03*
X1122641D03*
X1131341Y1088058D03*
X1122641D03*
X1131341Y1108137D03*
X1122641D03*
X1131341Y1101444D03*
X1122641D03*
X1131341Y1124869D03*
X1122641D03*
X1131341Y1114829D03*
X1122641D03*
X1131341Y1144948D03*
X1122641D03*
X1131341Y1138255D03*
X1122641D03*
X1131341Y1131562D03*
X1122641D03*
X1131341Y1161680D03*
X1122641D03*
X1131341Y1151641D03*
X1122641D03*
X1131341Y1175066D03*
X1122641D03*
X1131341Y1168373D03*
X1122641D03*
X1131341Y1188452D03*
X1122641D03*
X1131341Y1181759D03*
X1122641D03*
X1131341Y1205184D03*
X1122641D03*
X1131341Y1198491D03*
X1122641D03*
X1131341Y1225263D03*
X1122641D03*
X1131341Y1218570D03*
X1122641D03*
X1131341Y1211877D03*
X1122641D03*
X1131341Y1241995D03*
X1122641D03*
X1131341Y1235302D03*
X1122641D03*
X1131434Y1257291D03*
X1122641Y1248688D03*
X1131341D03*
X1122641Y1258727D03*
X1133200Y1255702D03*
X1126188Y1273344D03*
X1128988D03*
X1122620Y1264622D03*
X1152241Y766798D03*
X1152341Y867192D03*
X1147483Y863845D03*
X1138783D03*
X1152341Y880577D03*
Y873885D03*
X1147483Y883924D03*
X1138783D03*
X1147483Y877231D03*
X1138783D03*
X1147483Y870538D03*
X1138783D03*
X1152341Y893963D03*
Y887270D03*
X1138783Y900656D03*
X1147483D03*
X1138783Y890617D03*
X1147483D03*
X1152341Y917389D03*
Y910696D03*
Y904003D03*
X1147483Y914042D03*
X1138783D03*
X1147483Y907349D03*
X1138783D03*
X1152341Y930774D03*
Y924081D03*
X1147483Y927428D03*
X1138783D03*
X1147483Y920735D03*
X1138783D03*
X1152341Y947507D03*
Y940814D03*
X1147483Y944160D03*
X1138783D03*
X1147483Y937467D03*
X1138783D03*
X1152341Y964239D03*
Y954200D03*
X1147483Y960892D03*
X1138783D03*
X1147483Y950853D03*
X1138783D03*
X1147483Y957546D03*
Y954200D03*
X1152341Y977625D03*
Y970932D03*
X1147483Y980971D03*
X1138783D03*
X1147483Y974278D03*
X1138783D03*
X1147483Y967585D03*
X1138783D03*
X1152341Y991011D03*
Y984318D03*
X1147483Y987664D03*
X1138783D03*
Y994357D03*
X1152341Y1031168D03*
Y1024475D03*
Y1017782D03*
X1147483Y1027822D03*
X1138783D03*
X1147483Y1017782D03*
X1138783D03*
X1152341Y1044554D03*
Y1037861D03*
X1138783Y1047900D03*
X1147483D03*
Y1041207D03*
X1138783D03*
X1147483Y1034515D03*
X1138783D03*
X1152341Y1057940D03*
Y1051247D03*
X1147483Y1061286D03*
X1138783D03*
X1147483Y1054593D03*
X1138783D03*
X1152341Y1078018D03*
Y1071326D03*
Y1064633D03*
X1147483Y1074672D03*
X1138783D03*
X1147483Y1067979D03*
X1138783D03*
X1152341Y1094751D03*
Y1088058D03*
X1147483Y1091404D03*
X1138783D03*
X1147483Y1084711D03*
X1138783D03*
X1152341Y1108137D03*
Y1101444D03*
X1147483Y1111483D03*
X1138783D03*
X1147483Y1104790D03*
X1138783D03*
X1147483Y1098097D03*
X1138783D03*
X1152341Y1124869D03*
Y1114829D03*
X1147483Y1128215D03*
X1138783D03*
X1147483Y1121522D03*
X1138783D03*
X1152341Y1144948D03*
Y1138255D03*
Y1131562D03*
X1147483Y1141601D03*
X1138783D03*
X1147483Y1134908D03*
X1138783D03*
X1152341Y1161680D03*
Y1151641D03*
X1147483Y1158333D03*
X1138783D03*
Y1148294D03*
X1147483D03*
X1152341Y1175066D03*
Y1168373D03*
X1147483Y1171719D03*
X1138783D03*
X1147483Y1165026D03*
X1138783D03*
X1152341Y1188452D03*
Y1181759D03*
X1147483Y1185105D03*
X1138783D03*
X1147483Y1178412D03*
X1138783D03*
X1152341Y1205184D03*
Y1198491D03*
X1147483Y1208530D03*
X1138783D03*
X1147483Y1201837D03*
X1138783D03*
X1147483Y1195144D03*
X1138783D03*
X1152341Y1225263D03*
Y1218570D03*
Y1211877D03*
X1147483Y1221916D03*
X1138783D03*
X1147483Y1215223D03*
X1138783D03*
X1152341Y1241995D03*
Y1235302D03*
X1147483Y1238648D03*
X1138783D03*
X1147483Y1231955D03*
X1138783D03*
X1152341Y1248688D03*
X1147483Y1245341D03*
X1138783D03*
X1152341Y1258727D03*
X1138783Y1255381D03*
Y1258727D03*
Y1252034D03*
X1147483Y1248688D03*
X1150400Y1262074D03*
X1148563Y1257097D03*
X1152381Y1269684D03*
X1147681D03*
X1138201Y1270277D03*
X1152341Y1265420D03*
X1138783Y1262027D03*
X1137980Y1264212D03*
X1167633Y863845D03*
X1161041Y867192D03*
X1168483Y883924D03*
Y877231D03*
Y870538D03*
X1161041Y880577D03*
Y873885D03*
X1168483Y900656D03*
Y890617D03*
X1161041Y893963D03*
Y887270D03*
X1168483Y914042D03*
Y907349D03*
X1161041Y917389D03*
Y910696D03*
Y904003D03*
X1167633Y927428D03*
X1168483Y920735D03*
X1161041Y930774D03*
Y924081D03*
X1168483Y937467D03*
Y944160D03*
X1161041Y947507D03*
Y940814D03*
X1168483Y960892D03*
Y950853D03*
X1161041Y964239D03*
Y954200D03*
X1168483Y974278D03*
Y980971D03*
Y967585D03*
X1161041Y977625D03*
Y970932D03*
X1168483Y987664D03*
X1161041Y991011D03*
Y984318D03*
X1168483Y1027822D03*
Y1017782D03*
X1161041Y1031168D03*
Y1024475D03*
Y1017782D03*
X1168483Y1047900D03*
Y1041207D03*
Y1034515D03*
X1161041Y1044554D03*
Y1037861D03*
X1168483Y1054593D03*
Y1061286D03*
X1161041Y1057940D03*
Y1051247D03*
Y1061286D03*
X1168483Y1074672D03*
Y1067979D03*
X1161041Y1078018D03*
Y1071326D03*
Y1064633D03*
X1168483Y1091404D03*
X1167633Y1084711D03*
X1161041Y1094751D03*
Y1088058D03*
X1168483Y1111483D03*
Y1104790D03*
Y1098097D03*
X1161041Y1108137D03*
Y1101444D03*
X1168483Y1128215D03*
Y1121522D03*
X1161041Y1124869D03*
Y1114829D03*
X1168483Y1141601D03*
Y1134908D03*
X1161041Y1144948D03*
Y1138255D03*
Y1131562D03*
X1167633Y1158333D03*
X1168483Y1148294D03*
X1161041Y1161680D03*
Y1151641D03*
X1168483Y1171719D03*
Y1165026D03*
X1161041Y1175066D03*
Y1168373D03*
X1168483Y1185105D03*
Y1178412D03*
X1161041Y1188452D03*
Y1181759D03*
X1168483Y1208530D03*
Y1201837D03*
Y1195144D03*
X1161041Y1205184D03*
Y1198491D03*
X1168483Y1221916D03*
Y1215223D03*
X1161041Y1225263D03*
Y1218570D03*
Y1211877D03*
X1168483Y1238648D03*
X1167633Y1231955D03*
X1161041Y1241995D03*
Y1235302D03*
X1161065Y1258871D03*
X1168483Y1245341D03*
X1161041Y1248688D03*
X1168483Y1255381D03*
Y1258727D03*
Y1252034D03*
X1161781Y1269684D03*
X1168483Y1265420D03*
Y1262074D03*
X1181191Y867192D03*
X1177183Y863845D03*
X1182041Y873885D03*
Y880577D03*
X1177183Y883924D03*
Y877231D03*
Y870538D03*
X1182041Y893963D03*
Y887270D03*
X1177183Y900656D03*
Y890617D03*
X1182041Y917389D03*
Y910696D03*
Y904003D03*
X1177183Y914042D03*
Y907349D03*
X1181191Y930774D03*
Y924081D03*
X1177183Y927428D03*
Y920735D03*
X1182041Y940814D03*
Y947507D03*
X1177183Y937467D03*
Y944160D03*
X1182041Y964239D03*
Y954200D03*
X1177183Y960892D03*
Y950853D03*
Y957546D03*
Y954200D03*
X1182041Y970932D03*
Y977625D03*
X1177183Y974278D03*
Y980971D03*
Y967585D03*
X1182041Y991011D03*
Y984318D03*
X1177183Y987664D03*
Y994357D03*
X1182041Y1031168D03*
Y1017782D03*
Y1024475D03*
X1177183Y1027822D03*
Y1017782D03*
X1182041Y1044554D03*
Y1037861D03*
X1177183Y1047900D03*
Y1041207D03*
Y1034515D03*
X1182041Y1057940D03*
Y1051247D03*
X1177183Y1054593D03*
Y1061286D03*
X1181191Y1078018D03*
X1182041Y1071326D03*
Y1064633D03*
X1177183Y1074672D03*
Y1067979D03*
X1182041Y1094751D03*
X1181191Y1088058D03*
X1177183Y1091404D03*
Y1084711D03*
X1182041Y1101444D03*
Y1108137D03*
X1177183Y1111483D03*
Y1104790D03*
Y1098097D03*
X1182041Y1114829D03*
Y1124869D03*
X1177183Y1128215D03*
Y1121522D03*
X1182041Y1144948D03*
Y1138255D03*
Y1131562D03*
X1177183Y1141601D03*
Y1134908D03*
X1181191Y1161680D03*
Y1151641D03*
X1177183Y1158333D03*
Y1148294D03*
X1182041Y1168373D03*
Y1175066D03*
X1177183Y1171719D03*
Y1165026D03*
X1182041Y1188452D03*
Y1181759D03*
X1177183Y1185105D03*
Y1178412D03*
X1182041Y1205184D03*
Y1198491D03*
X1177183Y1208530D03*
Y1201837D03*
Y1195144D03*
X1181191Y1225263D03*
X1182041Y1211877D03*
Y1218570D03*
X1177183Y1221916D03*
Y1215223D03*
X1182041Y1241995D03*
X1181191Y1235302D03*
X1177183Y1238648D03*
Y1231955D03*
X1182041Y1248688D03*
X1177183Y1245341D03*
X1177120Y1248688D03*
X1177222Y1255567D03*
X1176867Y1270029D03*
X1182041Y1265420D03*
X1181850Y1260192D03*
X1179180Y1265872D03*
X1197333Y863845D03*
X1191591Y867192D03*
X1198183Y877231D03*
X1197333Y870538D03*
X1198183Y883924D03*
X1190741Y873885D03*
Y880577D03*
X1198183Y900656D03*
Y890617D03*
X1190741Y893963D03*
Y887270D03*
X1198183Y914042D03*
Y907349D03*
X1190741Y917389D03*
Y910696D03*
Y904003D03*
X1197383Y927428D03*
X1198183Y920735D03*
X1191591Y930774D03*
Y924081D03*
X1198183Y944160D03*
X1197333Y937467D03*
X1190741Y940814D03*
Y947507D03*
X1198183Y960892D03*
Y950853D03*
X1190741Y964239D03*
Y954200D03*
X1198183Y957546D03*
Y954200D03*
Y980971D03*
Y974278D03*
Y967585D03*
X1190741Y970932D03*
Y977625D03*
X1198183Y987664D03*
X1190741Y991011D03*
Y984318D03*
X1198183Y994357D03*
Y1027822D03*
Y1017782D03*
X1190741Y1031168D03*
Y1017782D03*
Y1024475D03*
X1198183Y1047900D03*
Y1041207D03*
Y1034515D03*
X1190741Y1044554D03*
Y1037861D03*
X1198183Y1054593D03*
Y1061286D03*
X1190741Y1057940D03*
Y1051247D03*
X1197333Y1074672D03*
X1198183Y1067979D03*
X1191591Y1078018D03*
X1190741Y1071326D03*
Y1064633D03*
X1198183Y1091404D03*
X1197333Y1084711D03*
X1190741Y1094751D03*
X1191591Y1088058D03*
X1198183Y1111483D03*
Y1098097D03*
Y1104790D03*
X1190741Y1101444D03*
Y1108137D03*
X1198183Y1128215D03*
Y1121522D03*
X1190741Y1114829D03*
Y1124869D03*
X1198183Y1141601D03*
X1197333Y1134908D03*
X1190741Y1144948D03*
Y1138255D03*
Y1131562D03*
X1198183Y1158333D03*
X1197333Y1148294D03*
X1191591Y1161680D03*
Y1151641D03*
X1198183Y1165026D03*
Y1171719D03*
X1190741Y1168373D03*
Y1175066D03*
X1198183Y1185105D03*
Y1178412D03*
X1190741Y1188452D03*
Y1181759D03*
X1198183Y1208530D03*
Y1201837D03*
Y1195144D03*
X1190741Y1205184D03*
Y1198491D03*
X1198183Y1221916D03*
Y1215223D03*
X1191591Y1225263D03*
X1190741Y1211877D03*
Y1218570D03*
X1197333Y1238648D03*
Y1231955D03*
X1190741Y1241995D03*
X1191591Y1235302D03*
X1198183Y1245341D03*
X1190966Y1258711D03*
X1190741Y1248688D03*
X1198183Y1252034D03*
X1191538Y1270004D03*
X1198180Y1262112D03*
X1196470Y1265382D03*
X1193590Y1267912D03*
X1195470Y1262802D03*
X1195994Y1580678D03*
Y1575686D03*
X1200950Y1580678D03*
Y1575686D03*
X1201294Y1599884D03*
X1195994Y1592590D03*
Y1587598D03*
X1200950Y1592590D03*
Y1587598D03*
X1201294Y1604876D03*
Y1611796D03*
Y1616788D03*
X1211641Y766798D03*
X1210891Y867492D03*
X1207733Y863845D03*
X1211741Y874185D03*
Y880577D03*
X1206883Y877231D03*
X1207201Y871084D03*
X1206883Y883924D03*
X1211741Y893963D03*
Y887270D03*
X1206883Y900656D03*
Y890617D03*
X1211741Y917389D03*
Y910696D03*
Y904003D03*
X1206883Y914042D03*
Y907349D03*
X1211741Y930774D03*
Y924081D03*
X1207683Y927428D03*
X1206883Y920735D03*
X1211741Y947507D03*
X1211001Y940814D03*
X1206883Y944660D03*
X1207733Y937467D03*
X1211741Y964239D03*
Y954200D03*
X1206883Y960892D03*
Y950853D03*
X1211741Y977625D03*
Y970932D03*
X1206883Y980971D03*
Y974278D03*
Y967585D03*
X1211741Y991011D03*
X1206883Y987664D03*
X1211741Y984318D03*
Y1031168D03*
X1206883Y1027822D03*
Y1017782D03*
X1211741D03*
Y1024475D03*
Y1044554D03*
Y1037861D03*
X1206883Y1047900D03*
Y1041207D03*
Y1034515D03*
X1211741Y1051247D03*
Y1057940D03*
X1206883Y1054593D03*
Y1061286D03*
X1210891Y1078018D03*
X1211741Y1064633D03*
Y1071326D03*
X1207733Y1074672D03*
X1206883Y1067979D03*
X1211741Y1094751D03*
X1210891Y1088058D03*
X1206883Y1091404D03*
Y1084711D03*
X1211741Y1108137D03*
Y1101444D03*
X1206883Y1111483D03*
Y1098097D03*
Y1104790D03*
X1210891Y1124869D03*
X1211741Y1114829D03*
X1206883Y1128215D03*
Y1121522D03*
X1211741Y1144948D03*
Y1138255D03*
X1210891Y1131562D03*
X1206883Y1141601D03*
X1207733Y1134908D03*
X1211741Y1151641D03*
Y1161680D03*
X1206883Y1158333D03*
X1207733Y1148294D03*
X1211741Y1175066D03*
Y1168373D03*
X1206883Y1165026D03*
Y1171719D03*
X1211741Y1188452D03*
Y1181759D03*
X1206883Y1185105D03*
Y1178412D03*
X1211741Y1205184D03*
Y1198491D03*
X1206883Y1208530D03*
Y1201837D03*
Y1195144D03*
X1210891Y1225263D03*
X1211741Y1218570D03*
Y1211877D03*
X1206883Y1221916D03*
Y1215223D03*
X1211741Y1241995D03*
X1211328Y1234977D03*
X1207733Y1238648D03*
Y1231955D03*
X1206883Y1245341D03*
X1211741Y1248688D03*
X1208830Y1256692D03*
X1206883Y1248688D03*
X1207048Y1255174D03*
X1204608Y1273119D03*
X1202043Y1273123D03*
X1211240Y1265502D03*
X1208750Y1266546D03*
X1213010Y1575686D03*
X1208054D03*
X1213010Y1580678D03*
X1208054D03*
X1206250Y1599884D03*
X1213354D03*
X1213010Y1587598D03*
X1208054D03*
X1213010Y1592590D03*
X1208054D03*
X1206250Y1604876D03*
Y1611796D03*
Y1616788D03*
X1213354D03*
Y1604876D03*
Y1611796D03*
X1214132Y1614292D03*
X1202072D03*
X1217532D03*
X1205472D03*
X1214132Y1602380D03*
X1202072D03*
X1217532D03*
X1205472D03*
X1227033Y863845D03*
X1221291Y867192D03*
X1227883Y870538D03*
Y883924D03*
Y877231D03*
X1220441Y873885D03*
Y880577D03*
X1227033Y900656D03*
X1227883Y890617D03*
X1220441Y893963D03*
Y887270D03*
X1227883Y914042D03*
Y907349D03*
X1220441Y917389D03*
Y910696D03*
Y904003D03*
X1227033Y927428D03*
X1227883Y920735D03*
X1221291Y930774D03*
X1220441Y924081D03*
X1227883Y944160D03*
X1227033Y937467D03*
X1220441Y947507D03*
X1221291Y940814D03*
X1227883Y960892D03*
Y950853D03*
X1220441Y964239D03*
Y954200D03*
X1227883Y957546D03*
Y954200D03*
Y974278D03*
Y967585D03*
X1220441Y977625D03*
Y970932D03*
X1227883Y980971D03*
Y987664D03*
X1220441Y991011D03*
Y984318D03*
X1227883Y994357D03*
Y1027822D03*
X1220441Y1031168D03*
X1227883Y1017782D03*
X1220441D03*
Y1024475D03*
X1227883Y1047900D03*
Y1041207D03*
Y1034515D03*
X1220441Y1044554D03*
Y1037861D03*
X1227883Y1061286D03*
Y1054593D03*
X1220441Y1051247D03*
Y1057940D03*
Y1061286D03*
X1227033Y1074672D03*
Y1067979D03*
X1221291Y1078018D03*
X1220441Y1064633D03*
Y1071326D03*
X1227883Y1091404D03*
Y1084711D03*
X1220441Y1094751D03*
X1221291Y1088058D03*
X1227883Y1104790D03*
X1227033Y1111483D03*
X1227883Y1098097D03*
X1220441Y1108137D03*
Y1101444D03*
X1227883Y1128215D03*
X1227033Y1121522D03*
X1221291Y1124869D03*
X1220441Y1114829D03*
X1227883Y1134908D03*
Y1141601D03*
X1220441Y1144948D03*
Y1138255D03*
X1221291Y1131562D03*
X1227883Y1158333D03*
Y1148294D03*
X1220441Y1151641D03*
Y1161680D03*
X1227883Y1171719D03*
Y1165026D03*
X1220441Y1175066D03*
Y1168373D03*
X1227883Y1185105D03*
Y1178412D03*
X1220441Y1188452D03*
Y1181759D03*
X1227883Y1208530D03*
Y1201837D03*
X1227033Y1195144D03*
X1220441Y1205184D03*
Y1198491D03*
X1227033Y1221916D03*
X1227883Y1215223D03*
X1221291Y1225263D03*
X1220441Y1218570D03*
Y1211877D03*
X1227883Y1238648D03*
X1227033Y1231955D03*
X1220441Y1241995D03*
X1221291Y1235302D03*
X1220441Y1248688D03*
X1227883Y1245341D03*
X1224189Y1259155D03*
X1226899Y1257968D03*
X1227847Y1251715D03*
X1220601Y1269684D03*
X1220931Y1260093D03*
X1233327Y1274515D03*
X1231377Y1275855D03*
X1227670Y1265162D03*
X1225540Y1266402D03*
X1225070Y1580678D03*
Y1575686D03*
X1220114D03*
Y1580678D03*
X1232174D03*
Y1575686D03*
X1218310Y1599884D03*
X1225414D03*
X1230370D03*
X1225070Y1592590D03*
X1220114D03*
X1225070Y1587598D03*
X1220114D03*
X1232174D03*
Y1592590D03*
X1218310Y1616788D03*
Y1604876D03*
Y1611796D03*
X1225414D03*
Y1604876D03*
X1230370Y1611796D03*
Y1604876D03*
X1225414Y1616788D03*
X1230370D03*
X1226192Y1614292D03*
X1229592D03*
X1226192Y1602380D03*
X1229592D03*
X1237433Y863845D03*
X1236583Y870538D03*
Y883924D03*
Y877231D03*
Y900656D03*
Y890617D03*
Y914042D03*
Y907349D03*
X1237433Y927428D03*
X1236583Y920735D03*
Y944160D03*
X1237433Y937467D03*
X1236583Y960892D03*
Y950853D03*
Y974278D03*
Y967585D03*
Y980971D03*
Y987664D03*
Y1027822D03*
Y1017782D03*
Y1047900D03*
Y1041207D03*
Y1034515D03*
Y1061286D03*
Y1054593D03*
Y1057940D03*
X1237433Y1074672D03*
Y1067979D03*
X1236583Y1091404D03*
Y1084711D03*
Y1104790D03*
X1237433Y1111483D03*
X1236583Y1098097D03*
Y1128215D03*
X1237433Y1121522D03*
X1236583Y1134908D03*
Y1141601D03*
Y1158333D03*
Y1148294D03*
Y1171719D03*
Y1165026D03*
Y1185105D03*
Y1178412D03*
Y1208530D03*
Y1201837D03*
Y1195144D03*
X1237433Y1221916D03*
X1236583Y1215223D03*
Y1238648D03*
X1237433Y1231955D03*
X1236583Y1245341D03*
Y1248688D03*
X1237130Y1575686D03*
Y1580678D03*
X1244234D03*
X1249190D03*
X1244234Y1575686D03*
X1249190D03*
X1242430Y1599884D03*
X1237474D03*
X1249534D03*
X1237130Y1587598D03*
Y1592590D03*
X1249190D03*
X1244234D03*
Y1587598D03*
X1249190D03*
X1242430Y1616788D03*
X1237474D03*
X1242430Y1611796D03*
Y1604876D03*
X1237474Y1611796D03*
Y1604876D03*
X1249534Y1611796D03*
Y1604876D03*
Y1616788D03*
X1238252Y1614292D03*
X1241652D03*
X1238252Y1602380D03*
X1241652D03*
X1241142Y1675383D03*
Y1679920D03*
X1249016Y1679320D03*
X1241142Y1684454D03*
Y1689556D03*
Y1694093D03*
Y1698627D03*
X1249016Y1688391D03*
Y1693493D03*
Y1698030D03*
Y1683857D03*
X1241142Y1703729D03*
Y1708266D03*
Y1712800D03*
X1249016Y1707666D03*
Y1712203D03*
Y1702564D03*
X1241142Y1726974D03*
Y1722440D03*
Y1717903D03*
X1249016Y1730911D03*
Y1726377D03*
Y1721840D03*
Y1716737D03*
X1261250Y1575686D03*
X1256294D03*
X1261250Y1580678D03*
X1256294D03*
X1254490Y1599884D03*
X1261594D03*
X1261250Y1587598D03*
X1256294D03*
X1261250Y1592590D03*
X1256294D03*
X1254490Y1611796D03*
Y1604876D03*
Y1616788D03*
X1261594D03*
Y1611796D03*
Y1604876D03*
X1262372Y1614292D03*
X1250312D03*
X1265772D03*
X1253712D03*
X1262372Y1602380D03*
X1250312D03*
X1265772D03*
X1253712D03*
X1256890Y1675383D03*
Y1679920D03*
X1264764Y1679320D03*
X1256890Y1684454D03*
Y1689556D03*
Y1694093D03*
Y1698627D03*
X1264764Y1688391D03*
Y1693493D03*
Y1698030D03*
Y1683857D03*
X1256890Y1703729D03*
Y1708266D03*
Y1712800D03*
X1264764Y1707666D03*
Y1712203D03*
Y1702564D03*
X1256890Y1726974D03*
Y1722440D03*
Y1717903D03*
X1264764Y1730911D03*
Y1726377D03*
Y1721840D03*
Y1716737D03*
X1273310Y1580678D03*
Y1575592D03*
X1268354D03*
Y1580678D03*
X1280414Y1575686D03*
Y1580678D03*
X1266550Y1599884D03*
X1273654Y1599790D03*
X1278610D03*
X1273310Y1592590D03*
X1268354D03*
X1273310Y1587598D03*
X1268354D03*
X1280414D03*
Y1592590D03*
X1266550Y1616788D03*
Y1611796D03*
Y1604876D03*
X1273654Y1611796D03*
Y1604876D03*
X1278610Y1611796D03*
Y1604876D03*
X1273654Y1616788D03*
X1278610D03*
X1274432Y1614292D03*
X1277832D03*
X1274432Y1602380D03*
X1277832D03*
X1272638Y1675383D03*
Y1679920D03*
X1280512Y1679320D03*
X1272638Y1684454D03*
Y1689556D03*
Y1694093D03*
Y1698627D03*
X1280512Y1688391D03*
Y1693493D03*
Y1698030D03*
Y1683857D03*
X1272638Y1703729D03*
Y1708266D03*
Y1712800D03*
X1280512Y1707666D03*
Y1712203D03*
Y1702564D03*
X1272638Y1726974D03*
Y1722440D03*
Y1717903D03*
X1280512Y1730911D03*
Y1726377D03*
Y1721840D03*
Y1716737D03*
X1285370Y1575686D03*
Y1580678D03*
X1297430D03*
X1292474D03*
Y1575686D03*
X1297430D03*
X1285714Y1599884D03*
X1290670D03*
X1297774D03*
X1285370Y1587598D03*
Y1592590D03*
X1297430D03*
X1292474D03*
X1297430Y1587598D03*
X1292474D03*
X1290670Y1616788D03*
X1285714D03*
Y1611796D03*
X1290670D03*
X1285714Y1604876D03*
X1290670D03*
X1297774Y1611796D03*
Y1604876D03*
Y1616788D03*
X1298552Y1614292D03*
X1286492D03*
X1289892D03*
X1298552Y1602380D03*
X1286492D03*
X1289892D03*
X1296260Y1679320D03*
X1288386Y1675383D03*
Y1679920D03*
X1296260Y1688391D03*
Y1693493D03*
Y1698030D03*
Y1683857D03*
X1288386Y1684454D03*
Y1689556D03*
Y1694093D03*
Y1698627D03*
X1296260Y1707666D03*
Y1712203D03*
Y1702564D03*
X1288386Y1703729D03*
Y1708266D03*
Y1712800D03*
X1296260Y1730911D03*
Y1726377D03*
Y1721840D03*
Y1716737D03*
X1288386Y1726974D03*
Y1722440D03*
Y1717903D03*
X1309490Y1575686D03*
X1304534D03*
X1309490Y1580678D03*
X1304534D03*
X1302730Y1599884D03*
X1309834D03*
X1314790D03*
X1309490Y1587598D03*
X1304534D03*
X1309490Y1592590D03*
X1304534D03*
X1302730Y1611796D03*
Y1604876D03*
Y1616788D03*
X1309834D03*
Y1611796D03*
Y1604876D03*
X1314790Y1616788D03*
Y1611796D03*
Y1604876D03*
X1310612Y1614292D03*
X1314012D03*
X1301952D03*
X1310612Y1602380D03*
X1314012D03*
X1301952D03*
X1308071Y1675383D03*
Y1679920D03*
Y1684454D03*
Y1689556D03*
Y1694093D03*
Y1698627D03*
Y1703729D03*
Y1708266D03*
Y1712800D03*
Y1726974D03*
Y1722440D03*
Y1717903D03*
X1321550Y1580678D03*
X1316594D03*
X1321550Y1575686D03*
X1316594D03*
X1328654D03*
Y1580678D03*
X1321894Y1599884D03*
X1326850D03*
X1321550Y1592590D03*
X1316594D03*
X1321550Y1587598D03*
X1316594D03*
X1328654D03*
Y1592590D03*
X1321894Y1611796D03*
Y1604876D03*
X1326850Y1611796D03*
Y1604876D03*
X1321894Y1616788D03*
X1326850D03*
X1322672Y1614292D03*
X1326072D03*
X1322672Y1602380D03*
X1326072D03*
X1323819Y1675383D03*
Y1679920D03*
X1315945Y1679320D03*
X1323819Y1684454D03*
Y1689556D03*
Y1694093D03*
Y1698627D03*
X1315945Y1688391D03*
Y1693493D03*
Y1698030D03*
Y1683857D03*
X1323819Y1703729D03*
Y1708266D03*
Y1712800D03*
X1315945Y1707666D03*
Y1712203D03*
Y1702564D03*
X1323819Y1726974D03*
Y1722440D03*
Y1717903D03*
X1315945Y1730911D03*
Y1726377D03*
Y1721840D03*
Y1716737D03*
X1333610Y1575686D03*
Y1580678D03*
X1345670D03*
X1340714D03*
X1345670Y1575686D03*
X1340714D03*
X1338910Y1599884D03*
X1333954D03*
X1346014D03*
X1333610Y1587598D03*
Y1592590D03*
X1345670D03*
X1340714D03*
X1345670Y1587598D03*
X1340714D03*
X1338910Y1616788D03*
Y1611796D03*
Y1604876D03*
X1333954Y1616788D03*
Y1611796D03*
Y1604876D03*
X1346014Y1611796D03*
Y1604876D03*
Y1616788D03*
X1346792Y1614292D03*
X1334732D03*
X1338132D03*
X1346792Y1602380D03*
X1334732D03*
X1338132D03*
X1339567Y1675383D03*
Y1679920D03*
X1331693Y1679320D03*
X1347441D03*
X1339567Y1684454D03*
Y1689556D03*
Y1694093D03*
Y1698627D03*
X1331693Y1688391D03*
Y1693493D03*
Y1698030D03*
Y1683857D03*
X1347441Y1688391D03*
Y1693493D03*
Y1698030D03*
Y1683857D03*
X1339567Y1703729D03*
Y1708266D03*
Y1712800D03*
X1331693Y1707666D03*
Y1712203D03*
Y1702564D03*
X1347441Y1707666D03*
Y1712203D03*
Y1702564D03*
X1339567Y1726974D03*
Y1722440D03*
Y1717903D03*
X1331693Y1730911D03*
Y1726377D03*
Y1721840D03*
Y1716737D03*
X1347441Y1730911D03*
Y1726377D03*
Y1721840D03*
Y1716737D03*
X1357730Y1575686D03*
X1352774D03*
X1357730Y1580678D03*
X1352774D03*
X1350970Y1599884D03*
X1363030D03*
X1358074D03*
X1357730Y1587598D03*
X1352774D03*
X1357730Y1592590D03*
X1352774D03*
X1350970Y1611796D03*
Y1604876D03*
Y1616788D03*
X1363030D03*
Y1611796D03*
Y1604876D03*
X1358074Y1616788D03*
Y1611796D03*
Y1604876D03*
X1358852Y1614292D03*
X1362252D03*
X1350192D03*
X1358852Y1602380D03*
X1362252D03*
X1350192D03*
X1363189Y1679320D03*
X1355315Y1675383D03*
Y1679920D03*
X1363189Y1688391D03*
Y1693493D03*
Y1698030D03*
Y1683857D03*
X1355315Y1684454D03*
Y1689556D03*
Y1694093D03*
Y1698627D03*
X1363189Y1707666D03*
Y1712203D03*
Y1702564D03*
X1355315Y1703729D03*
Y1708266D03*
Y1712800D03*
X1363189Y1730911D03*
Y1726377D03*
Y1721840D03*
Y1716737D03*
X1355315Y1726974D03*
Y1722440D03*
Y1717903D03*
X1369790Y1580678D03*
X1364834D03*
X1369790Y1575592D03*
X1364834D03*
X1376894Y1575686D03*
Y1580678D03*
X1375090Y1599790D03*
X1370134D03*
X1369790Y1592590D03*
X1364834D03*
X1369790Y1587598D03*
X1364834D03*
X1376894D03*
Y1592590D03*
X1375090Y1611796D03*
Y1604876D03*
Y1616788D03*
X1370134Y1611796D03*
Y1604876D03*
Y1616788D03*
X1370912Y1614292D03*
X1374312D03*
X1370912Y1602380D03*
X1374312D03*
X1381850Y1575686D03*
Y1580678D03*
X1387150Y1599884D03*
X1382194D03*
X1381850Y1587598D03*
Y1592590D03*
X1387150Y1616788D03*
X1382194D03*
X1387150Y1611796D03*
Y1604876D03*
X1382194Y1611796D03*
Y1604876D03*
X1382972Y1614292D03*
X1386372D03*
X1382972Y1602380D03*
X1386372D03*
X1461517Y1575686D03*
Y1580678D03*
Y1587598D03*
Y1592590D03*
X1473577Y1580678D03*
Y1575686D03*
X1466473D03*
Y1580678D03*
X1477755Y1578182D03*
X1462295D03*
X1474355D03*
X1465695D03*
X1471773Y1599884D03*
X1466817D03*
X1473577Y1592590D03*
Y1587598D03*
X1466473D03*
Y1592590D03*
X1477755Y1590094D03*
X1462295D03*
X1474355D03*
X1465695D03*
X1466817Y1611796D03*
X1471773D03*
X1466817Y1604876D03*
X1471773D03*
Y1616788D03*
X1466817D03*
X1490593Y1580678D03*
Y1575686D03*
X1485637D03*
Y1580678D03*
X1478533D03*
Y1575686D03*
X1489815Y1578182D03*
X1486415D03*
X1490937Y1599884D03*
X1478877D03*
X1483833D03*
X1490593Y1587598D03*
X1485637D03*
Y1592590D03*
X1490593D03*
X1478533D03*
Y1587598D03*
X1489815Y1590094D03*
X1486415D03*
X1490937Y1604876D03*
Y1611796D03*
Y1616788D03*
X1483833D03*
X1478877D03*
Y1611796D03*
X1483833D03*
X1478877Y1604876D03*
X1483833D03*
X1509757Y1575686D03*
Y1580678D03*
X1502653D03*
X1497697D03*
X1502653Y1575686D03*
X1497697D03*
X1501875Y1578182D03*
X1498475D03*
X1502997Y1599884D03*
X1507953D03*
X1495893D03*
X1509757Y1587598D03*
Y1592590D03*
X1502653D03*
X1497697D03*
X1502653Y1587598D03*
X1497697D03*
X1501875Y1590094D03*
X1498475D03*
X1502997Y1616788D03*
X1507953D03*
X1502997Y1604876D03*
Y1611796D03*
X1507953Y1604876D03*
Y1611796D03*
X1495893Y1604876D03*
Y1611796D03*
Y1616788D03*
X1505315Y1675383D03*
Y1679920D03*
Y1684454D03*
Y1689556D03*
Y1694093D03*
Y1698627D03*
Y1703729D03*
Y1708266D03*
Y1712800D03*
Y1726974D03*
Y1722440D03*
Y1717903D03*
X1521817Y1580678D03*
Y1575686D03*
X1514713D03*
Y1580678D03*
X1525995Y1578182D03*
X1513935D03*
X1522595D03*
X1510535D03*
X1520013Y1599884D03*
X1515057D03*
X1521817Y1592590D03*
Y1587598D03*
X1514713D03*
Y1592590D03*
X1525995Y1590094D03*
X1513935D03*
X1522595D03*
X1510535D03*
X1520013Y1604876D03*
X1515057D03*
X1520013Y1611796D03*
X1515057D03*
Y1616788D03*
X1520013D03*
X1521063Y1675383D03*
Y1679920D03*
X1513189Y1679320D03*
X1521063Y1684454D03*
Y1689556D03*
Y1694093D03*
Y1698627D03*
X1513189Y1688391D03*
Y1693493D03*
Y1698030D03*
Y1683857D03*
X1521063Y1703729D03*
Y1708266D03*
Y1712800D03*
X1513189Y1707666D03*
Y1712203D03*
Y1702564D03*
X1521063Y1726974D03*
Y1722440D03*
Y1717903D03*
X1513189Y1730911D03*
Y1726377D03*
Y1721840D03*
Y1716737D03*
X1533877Y1575592D03*
X1538833D03*
X1533877Y1580678D03*
X1538833D03*
X1526773D03*
Y1575686D03*
X1538055Y1578182D03*
X1534655D03*
X1539177Y1599790D03*
X1527117Y1599884D03*
X1532073D03*
X1533877Y1587598D03*
X1538833D03*
X1533877Y1592590D03*
X1538833D03*
X1526773D03*
Y1587598D03*
X1538055Y1590094D03*
X1534655D03*
X1539177Y1611796D03*
Y1604876D03*
Y1616788D03*
X1527117D03*
Y1604876D03*
Y1611796D03*
X1532073Y1616788D03*
Y1604876D03*
Y1611796D03*
X1536811Y1675383D03*
Y1679920D03*
X1528937Y1679320D03*
X1536811Y1684454D03*
Y1689556D03*
Y1694093D03*
Y1698627D03*
X1528937Y1688391D03*
Y1693493D03*
Y1698030D03*
Y1683857D03*
X1536811Y1703729D03*
Y1708266D03*
Y1712800D03*
X1528937Y1707666D03*
Y1712203D03*
Y1702564D03*
X1536811Y1726974D03*
Y1722440D03*
Y1717903D03*
X1528937Y1730911D03*
Y1726377D03*
Y1721840D03*
Y1716737D03*
X1557997Y1575686D03*
Y1580678D03*
X1550893D03*
X1545937D03*
X1550893Y1575686D03*
X1545937D03*
X1550115Y1578182D03*
X1558775D03*
X1546715D03*
X1556193Y1599884D03*
X1551237D03*
X1544133Y1599790D03*
X1557997Y1587598D03*
Y1592590D03*
X1545937D03*
X1550893D03*
Y1587598D03*
X1545937D03*
X1550115Y1590094D03*
X1558775D03*
X1546715D03*
X1551237Y1616788D03*
X1556193D03*
Y1604876D03*
X1551237D03*
X1556193Y1611796D03*
X1551237D03*
X1544133Y1604876D03*
Y1611796D03*
Y1616788D03*
X1552559Y1675383D03*
Y1679920D03*
X1544685Y1679320D03*
X1552559Y1684454D03*
Y1689556D03*
Y1694093D03*
Y1698627D03*
X1544685Y1688391D03*
Y1693493D03*
Y1698030D03*
Y1683857D03*
X1552559Y1703729D03*
Y1708266D03*
Y1712800D03*
X1544685Y1707666D03*
Y1712203D03*
Y1702564D03*
X1552559Y1726974D03*
Y1722440D03*
Y1717903D03*
X1544685Y1730911D03*
Y1726377D03*
Y1721840D03*
Y1716737D03*
X1570057Y1580678D03*
X1575013D03*
X1570057Y1575686D03*
X1575013D03*
X1562953D03*
Y1580678D03*
X1574235Y1578182D03*
X1562175D03*
X1570835D03*
X1575357Y1599884D03*
X1563297D03*
X1568253D03*
X1570057Y1592590D03*
X1575013D03*
X1570057Y1587598D03*
X1575013D03*
X1562953D03*
Y1592590D03*
X1574235Y1590094D03*
X1562175D03*
X1570835D03*
X1575357Y1616788D03*
Y1604876D03*
Y1611796D03*
X1563297Y1604876D03*
Y1611796D03*
X1568253Y1604876D03*
Y1611796D03*
X1563297Y1616788D03*
X1568253D03*
X1560433Y1679320D03*
X1572244Y1675383D03*
Y1679920D03*
X1560433Y1688391D03*
Y1693493D03*
Y1698030D03*
Y1683857D03*
X1572244Y1684454D03*
Y1689556D03*
Y1694093D03*
Y1698627D03*
X1560433Y1707666D03*
Y1712203D03*
Y1702564D03*
X1572244Y1703729D03*
Y1708266D03*
Y1712800D03*
X1560433Y1730911D03*
Y1726377D03*
Y1721840D03*
Y1716737D03*
X1572244Y1726974D03*
Y1722440D03*
Y1717903D03*
X1582117Y1575686D03*
X1587073D03*
X1582117Y1580678D03*
X1587073D03*
X1586295Y1578182D03*
X1582895D03*
X1587417Y1599884D03*
X1580313D03*
X1582117Y1587598D03*
X1587073D03*
X1582117Y1592590D03*
X1587073D03*
X1586295Y1590094D03*
X1582895D03*
X1587417Y1604876D03*
Y1611796D03*
Y1616788D03*
X1580313D03*
Y1604876D03*
Y1611796D03*
X1587992Y1675383D03*
Y1679920D03*
X1580118Y1679320D03*
X1587992Y1684454D03*
Y1689556D03*
Y1694093D03*
Y1698627D03*
X1580118Y1688391D03*
Y1693493D03*
Y1698030D03*
Y1683857D03*
X1587992Y1703729D03*
Y1708266D03*
Y1712800D03*
X1580118Y1707666D03*
Y1712203D03*
Y1702564D03*
X1587992Y1726974D03*
Y1722440D03*
Y1717903D03*
X1580118Y1730911D03*
Y1726377D03*
Y1721840D03*
Y1716737D03*
X1597041Y770144D03*
X1605741D03*
X1605800Y766478D03*
X1605741Y776837D03*
X1597041D03*
X1605741Y783530D03*
X1597041D03*
X1605741Y793570D03*
X1597041D03*
X1596988Y800263D03*
X1605741D03*
X1595774Y806955D03*
X1606934D03*
X1596218Y813648D03*
X1606735D03*
X1597041Y820341D03*
X1605741D03*
X1597041Y830381D03*
X1605741D03*
Y837074D03*
X1597041D03*
Y843766D03*
X1605741D03*
X1596147Y850459D03*
X1606896D03*
X1596200Y857152D03*
X1606623D03*
X1597041Y867192D03*
X1605741D03*
X1597041Y873885D03*
X1605741D03*
X1597041Y880577D03*
X1605741D03*
X1597041Y887270D03*
X1605741D03*
X1606898Y893963D03*
X1597041D03*
X1605741Y904003D03*
X1597041D03*
Y917389D03*
X1605741D03*
X1597041Y910696D03*
X1605741D03*
X1597041Y924081D03*
X1605741D03*
X1606541Y930697D03*
X1596047Y930774D03*
X1596106Y940814D03*
X1606919D03*
X1605741Y947507D03*
X1597041D03*
X1605741Y954200D03*
X1597041D03*
Y964239D03*
X1605741D03*
X1597041Y977625D03*
X1605741D03*
Y970932D03*
X1597041D03*
Y984318D03*
X1605741D03*
X1597041Y991011D03*
X1605741D03*
X1597041Y1024475D03*
X1605741D03*
X1597041Y1017782D03*
X1605741D03*
X1597041Y1031168D03*
X1605741D03*
X1597041Y1037861D03*
X1605741D03*
X1597041Y1044554D03*
X1605741D03*
Y1051247D03*
X1597041D03*
Y1057940D03*
X1605741D03*
X1597041Y1061286D03*
Y1064633D03*
X1605741D03*
X1606541Y1071326D03*
X1596141D03*
X1597041Y1078018D03*
X1605741D03*
Y1094751D03*
X1597041D03*
Y1088058D03*
X1605741D03*
Y1101444D03*
X1597041D03*
Y1108137D03*
X1605741D03*
X1606541Y1114829D03*
X1596241D03*
X1596511Y1124969D03*
X1606505Y1124674D03*
X1605741Y1138255D03*
X1597041D03*
X1605741Y1144948D03*
X1597041D03*
Y1131562D03*
X1605741D03*
Y1151641D03*
X1597041D03*
X1596653Y1161680D03*
X1605975Y1161581D03*
X1605741Y1168373D03*
X1597041D03*
X1605741Y1175066D03*
X1597041D03*
X1605741Y1181759D03*
X1597041D03*
X1606765Y1188452D03*
X1597041D03*
Y1198491D03*
X1605741D03*
Y1205184D03*
X1597041D03*
Y1211877D03*
X1605741D03*
X1597041Y1218570D03*
X1605741D03*
X1597041Y1225263D03*
X1605741D03*
X1607064Y1235302D03*
X1596178D03*
X1605741Y1241995D03*
X1597041D03*
Y1248688D03*
X1605741D03*
X1606481Y1258649D03*
X1608000Y1261662D03*
X1603788Y1273144D03*
X1601388D03*
X1607897Y1264445D03*
X1606237Y1575686D03*
Y1580678D03*
X1594177D03*
X1599133D03*
X1594177Y1575686D03*
X1599133D03*
X1598355Y1578182D03*
X1607015D03*
X1594955D03*
X1599477Y1599884D03*
X1604433D03*
X1592373D03*
X1606237Y1587598D03*
Y1592590D03*
X1594177D03*
X1599133D03*
X1594177Y1587598D03*
X1599133D03*
X1598355Y1590094D03*
X1607015D03*
X1594955D03*
X1599477Y1616788D03*
X1604433D03*
X1599477Y1604876D03*
Y1611796D03*
X1604433Y1604876D03*
Y1611796D03*
X1592373Y1604876D03*
Y1611796D03*
Y1616788D03*
X1603740Y1675383D03*
Y1679920D03*
X1595866Y1679320D03*
X1603740Y1684454D03*
Y1689556D03*
Y1694093D03*
Y1698627D03*
X1595866Y1688391D03*
Y1693493D03*
Y1698030D03*
Y1683857D03*
X1603740Y1703729D03*
Y1708266D03*
Y1712800D03*
X1595866Y1707666D03*
Y1712203D03*
Y1702564D03*
X1603740Y1726974D03*
Y1722440D03*
Y1717903D03*
X1595866Y1730911D03*
Y1726377D03*
Y1721840D03*
Y1716737D03*
X1613183Y766798D03*
Y773491D03*
Y780184D03*
Y790223D03*
Y796916D03*
Y803609D03*
Y816995D03*
X1612363Y810302D03*
X1613183Y827034D03*
Y833727D03*
Y840420D03*
Y847113D03*
X1621943D03*
X1622060Y863845D03*
X1612408D03*
X1612474Y853955D03*
X1622961Y853806D03*
X1621883Y883924D03*
X1613183D03*
Y870538D03*
X1621883D03*
X1613183Y877231D03*
X1621883D03*
X1613183Y890617D03*
X1621883D03*
X1613183Y900656D03*
X1621883D03*
Y907349D03*
X1613183D03*
Y914042D03*
X1621883D03*
Y920735D03*
X1613183D03*
X1622535Y927526D03*
X1612168Y927428D03*
X1622845Y937467D03*
X1612312D03*
X1621883Y944160D03*
X1613183D03*
X1621883Y950853D03*
X1613183D03*
X1621883Y960892D03*
X1613183D03*
X1613083Y957546D03*
Y954200D03*
X1613183Y974278D03*
X1621883D03*
X1613183Y980971D03*
X1621883D03*
X1613183Y967585D03*
X1621883D03*
X1613183Y987664D03*
X1621883D03*
X1620399Y1000325D03*
X1621883Y1017782D03*
X1613183D03*
Y1027822D03*
X1621883D03*
X1613183Y1034515D03*
X1621883D03*
X1613183Y1041207D03*
X1621883D03*
X1613183Y1047900D03*
X1621883D03*
Y1054593D03*
X1613183D03*
Y1061286D03*
X1621883D03*
Y1067979D03*
X1612983D03*
X1612283Y1074672D03*
X1622683D03*
X1621883Y1084711D03*
X1612383D03*
X1613183Y1091404D03*
X1621883D03*
Y1104790D03*
X1613183D03*
X1621883Y1098097D03*
X1613183D03*
X1621883Y1111483D03*
X1613183D03*
Y1128915D03*
X1621883Y1128215D03*
X1613183Y1121522D03*
X1621883D03*
Y1141601D03*
X1613183D03*
X1622726Y1135108D03*
X1611886Y1134908D03*
X1621883Y1158333D03*
X1613183D03*
X1621883Y1148294D03*
X1613183D03*
X1621883Y1165026D03*
X1613183D03*
Y1171719D03*
X1621883D03*
Y1178412D03*
X1613183D03*
X1621883Y1185105D03*
X1613183D03*
Y1195144D03*
X1621883D03*
Y1201837D03*
X1613183D03*
X1621883Y1208530D03*
X1613183D03*
X1621883Y1215223D03*
X1613183D03*
X1612147Y1221916D03*
X1622712D03*
X1612137Y1231862D03*
X1622681Y1231955D03*
X1621883Y1238648D03*
X1613183D03*
X1610150Y1257172D03*
X1621883Y1245341D03*
X1613183D03*
X1621983Y1258727D03*
X1624600Y1262074D03*
X1613183Y1252034D03*
X1613027Y1248805D03*
X1609056Y1250602D03*
X1623930Y1252242D03*
X1618888Y1273344D03*
X1616088D03*
X1613019Y1261235D03*
X1618297Y1580678D03*
X1623253D03*
X1618297Y1575686D03*
X1623253D03*
X1611193D03*
Y1580678D03*
X1622475Y1578182D03*
X1610415D03*
X1619075D03*
X1623597Y1599884D03*
X1611537D03*
X1616493D03*
X1618297Y1592590D03*
X1623253D03*
X1618297Y1587598D03*
X1623253D03*
X1611193D03*
Y1592590D03*
X1622475Y1590094D03*
X1610415D03*
X1619075D03*
X1623597Y1616788D03*
Y1604876D03*
Y1611796D03*
X1611537Y1604876D03*
Y1611796D03*
X1616493Y1604876D03*
Y1611796D03*
X1611537Y1616788D03*
X1616493D03*
X1619488Y1675383D03*
Y1679920D03*
X1611614Y1679320D03*
X1619488Y1684454D03*
Y1689556D03*
Y1694093D03*
Y1698627D03*
X1611614Y1688391D03*
Y1693493D03*
Y1698030D03*
Y1683857D03*
X1619488Y1703729D03*
Y1708266D03*
Y1712800D03*
X1611614Y1707666D03*
Y1712203D03*
Y1702564D03*
X1619488Y1726974D03*
Y1722440D03*
Y1717903D03*
X1611614Y1730911D03*
Y1726377D03*
Y1721840D03*
Y1716737D03*
X1626741Y766798D03*
X1635441Y850459D03*
X1626741D03*
X1625705Y867192D03*
X1636441D03*
X1635441Y857152D03*
X1626741D03*
Y880577D03*
X1635441D03*
Y873885D03*
X1626741D03*
Y887270D03*
X1635441D03*
X1626741Y893963D03*
X1635441D03*
X1626741Y904003D03*
X1635441D03*
Y910696D03*
X1626741D03*
X1635441Y917389D03*
X1626741D03*
X1636316Y930774D03*
X1625803D03*
X1636646Y924081D03*
X1626741D03*
X1635441Y940814D03*
X1626741D03*
X1635441Y947507D03*
X1626741D03*
X1635441Y954200D03*
X1626741D03*
Y964239D03*
X1635441D03*
Y977625D03*
X1626741D03*
X1635441Y970932D03*
X1626741D03*
X1635441Y984318D03*
X1626741D03*
Y991011D03*
X1635441D03*
Y1024475D03*
X1626741D03*
X1635441Y1017782D03*
X1626741D03*
X1635441Y1031168D03*
X1626741D03*
X1635441Y1037861D03*
X1626741D03*
X1635441Y1044554D03*
X1626741D03*
Y1057940D03*
X1635441D03*
Y1051247D03*
X1626741D03*
X1635441Y1064633D03*
X1626741D03*
X1635441Y1071326D03*
X1626741D03*
X1636241Y1078018D03*
X1625941D03*
Y1088058D03*
X1636241D03*
X1635441Y1094751D03*
X1626741D03*
Y1101444D03*
X1635441D03*
X1626741Y1108137D03*
X1635441D03*
X1626074Y1124640D03*
X1636341Y1124869D03*
X1635441Y1114829D03*
X1626741D03*
X1635441Y1144948D03*
X1626741D03*
X1635441Y1138255D03*
X1626741D03*
X1635441Y1130762D03*
X1626741D03*
Y1161680D03*
X1635441D03*
Y1151641D03*
X1626741D03*
Y1168373D03*
X1635441D03*
X1626741Y1175066D03*
X1635441D03*
X1626741Y1181759D03*
X1635441D03*
X1626741Y1188452D03*
X1635441D03*
X1626741Y1198491D03*
X1635441D03*
X1626741Y1205184D03*
X1635441D03*
Y1211877D03*
X1626741D03*
X1635441Y1218570D03*
X1626741D03*
X1636212Y1225263D03*
X1626055D03*
X1636376Y1235302D03*
X1625843D03*
X1635441Y1241995D03*
X1626741D03*
X1635688Y1257664D03*
X1626741Y1248688D03*
X1635441D03*
X1626741Y1258727D03*
X1629788Y1273344D03*
X1632588D03*
X1625729Y1266766D03*
X1630357Y1575592D03*
X1635313D03*
X1630357Y1580678D03*
X1635313D03*
X1634535Y1578182D03*
X1631135D03*
X1640613Y1599790D03*
X1635657D03*
X1628553Y1599884D03*
X1630357Y1587598D03*
X1635313D03*
X1630357Y1592590D03*
X1635313D03*
X1634535Y1590094D03*
X1631135D03*
X1640613Y1604876D03*
Y1611796D03*
X1635657Y1604876D03*
Y1611796D03*
X1640613Y1616788D03*
X1635657D03*
X1628553D03*
Y1604876D03*
Y1611796D03*
X1627362Y1679320D03*
Y1688391D03*
Y1693493D03*
Y1698030D03*
Y1683857D03*
Y1707666D03*
Y1712203D03*
Y1702564D03*
Y1730911D03*
Y1726377D03*
Y1721840D03*
Y1716737D03*
X1656441Y766798D03*
Y850459D03*
X1651583Y847113D03*
X1642883D03*
X1642058Y863845D03*
X1652742D03*
X1656441Y857152D03*
Y867192D03*
X1652559Y853806D03*
X1642032D03*
X1656441Y873885D03*
Y880577D03*
X1642883Y883924D03*
X1651583D03*
Y870538D03*
X1642883D03*
X1651583Y877231D03*
X1642883D03*
X1656441Y887270D03*
Y893963D03*
X1642883Y890617D03*
X1651583D03*
X1642883Y900656D03*
X1651583D03*
X1656441Y904003D03*
Y910696D03*
X1642883Y907349D03*
X1651583D03*
X1656441Y917389D03*
X1651583Y914042D03*
X1642883D03*
X1656441Y924081D03*
Y930774D03*
X1652630Y927428D03*
X1642038D03*
X1651583Y920735D03*
X1642883D03*
X1656441Y940814D03*
Y947507D03*
X1652501Y937467D03*
X1642065D03*
X1651583Y944160D03*
X1642883D03*
X1656441Y954200D03*
X1642883Y950853D03*
X1651583D03*
Y960892D03*
X1642883D03*
X1656441Y964239D03*
X1642783Y957546D03*
Y954200D03*
X1656441Y977625D03*
Y970932D03*
X1651583Y967585D03*
X1642883D03*
X1651583Y974278D03*
X1642883D03*
X1651583Y980971D03*
X1642883D03*
X1656441Y984318D03*
Y991011D03*
X1651583Y987664D03*
X1642883D03*
X1648205Y998632D03*
X1651583Y1017782D03*
X1642883D03*
X1656441D03*
Y1024475D03*
X1651583Y1027822D03*
X1642883D03*
X1656441Y1031168D03*
Y1044554D03*
Y1037861D03*
X1651583Y1034515D03*
X1642883D03*
X1651583Y1041207D03*
X1642883D03*
X1651583Y1047900D03*
X1642883D03*
Y1061286D03*
X1651583D03*
X1656441Y1051247D03*
Y1057940D03*
X1651583Y1054593D03*
X1642883D03*
X1656441Y1061286D03*
Y1064633D03*
Y1071326D03*
Y1078018D03*
X1652483Y1074672D03*
X1641983D03*
X1651583Y1067979D03*
X1642883D03*
X1656441Y1088058D03*
Y1094751D03*
X1652383Y1084711D03*
X1642083D03*
X1651583Y1091404D03*
X1642883D03*
X1656441Y1101444D03*
Y1108137D03*
X1642883Y1098097D03*
X1651583D03*
X1642883Y1104790D03*
X1651583D03*
X1642883Y1111483D03*
X1651583D03*
X1656441Y1114829D03*
Y1124869D03*
X1642883Y1121522D03*
X1651583D03*
X1642883Y1128215D03*
X1651583D03*
X1656441Y1131562D03*
Y1138255D03*
X1642883Y1134908D03*
X1651583D03*
X1642883Y1141601D03*
X1651583D03*
X1656441Y1144948D03*
Y1151641D03*
Y1161680D03*
X1652383Y1158333D03*
X1642083D03*
X1652794Y1148294D03*
X1641744D03*
X1656441Y1168373D03*
Y1175066D03*
X1642883Y1171719D03*
X1651583D03*
Y1165026D03*
X1642883D03*
X1656441Y1181759D03*
Y1188452D03*
X1651583Y1178412D03*
X1642883D03*
X1651583Y1185105D03*
X1642883D03*
X1656441Y1198491D03*
Y1205184D03*
X1642883Y1195144D03*
X1651583D03*
X1642883Y1201837D03*
X1651583D03*
X1642883Y1208530D03*
X1651583D03*
X1656441Y1211877D03*
X1652590Y1221916D03*
X1641793D03*
X1656441Y1225263D03*
Y1218570D03*
X1651583Y1215223D03*
X1642883D03*
X1656441Y1235302D03*
Y1241995D03*
X1652604Y1231955D03*
X1642054D03*
X1651583Y1238648D03*
X1642883D03*
X1656441Y1248688D03*
X1651583Y1245341D03*
X1642883D03*
Y1255381D03*
Y1258727D03*
Y1252034D03*
X1651679Y1248885D03*
X1653140Y1257862D03*
X1648588Y1273344D03*
X1645788D03*
X1656188Y1264964D03*
X1642788Y1264464D03*
X1642883Y1262074D03*
X1656170Y1260352D03*
X1654600Y1262742D03*
X1647373Y1580678D03*
X1642417D03*
X1647373Y1575686D03*
X1642417D03*
X1646595Y1578182D03*
X1643195D03*
X1647717Y1599884D03*
X1652673D03*
X1647373Y1592590D03*
X1642417D03*
X1647373Y1587598D03*
X1642417D03*
X1646595Y1590094D03*
X1643195D03*
X1647717Y1616788D03*
X1652673D03*
X1647717Y1604876D03*
Y1611796D03*
X1652673Y1604876D03*
Y1611796D03*
X1665141Y850459D03*
X1672583Y847113D03*
X1666038Y857152D03*
X1665141Y867192D03*
X1672583Y853806D03*
Y863845D03*
X1665141Y873885D03*
Y880577D03*
X1672583Y870538D03*
Y877231D03*
Y883924D03*
X1665141Y887270D03*
Y893963D03*
X1672583Y890617D03*
Y900656D03*
X1665141Y904003D03*
Y910696D03*
Y917389D03*
X1672583Y907349D03*
Y914042D03*
X1665141Y924081D03*
X1666246Y930774D03*
X1672583Y920735D03*
Y927428D03*
X1665141Y940814D03*
Y947507D03*
X1672583Y937467D03*
Y944160D03*
X1665141Y954200D03*
Y964239D03*
X1672583Y950853D03*
Y960892D03*
Y957546D03*
Y954200D03*
X1665141Y977625D03*
Y970932D03*
X1672583Y967585D03*
Y974278D03*
Y980971D03*
X1665141Y984318D03*
Y991011D03*
X1672583Y987664D03*
Y994357D03*
X1665141Y1017782D03*
Y1024475D03*
Y1031168D03*
X1672583Y1017782D03*
Y1027822D03*
X1665141Y1044554D03*
Y1037861D03*
X1672583Y1034515D03*
Y1041207D03*
Y1047900D03*
X1665141Y1051247D03*
Y1057940D03*
X1672583Y1061286D03*
Y1054593D03*
X1665141Y1064633D03*
Y1071326D03*
Y1077118D03*
X1672583Y1067979D03*
Y1074672D03*
X1665141Y1088058D03*
Y1094751D03*
X1672583Y1084711D03*
Y1091404D03*
X1665141Y1101444D03*
Y1108137D03*
X1672583Y1098097D03*
Y1104790D03*
Y1111483D03*
X1665141Y1114829D03*
Y1124869D03*
X1672583Y1121522D03*
Y1128215D03*
X1665141Y1131562D03*
Y1138255D03*
Y1144948D03*
X1672583Y1134908D03*
Y1141601D03*
X1666141Y1151641D03*
X1665141Y1161680D03*
X1672583Y1148294D03*
Y1158333D03*
X1665141Y1168373D03*
Y1175066D03*
X1672583Y1165026D03*
Y1171719D03*
X1665141Y1181759D03*
Y1188452D03*
X1672583Y1178412D03*
Y1185105D03*
X1665141Y1198491D03*
Y1205184D03*
X1672583Y1195144D03*
Y1201837D03*
Y1208530D03*
X1665141Y1211877D03*
X1665941Y1225263D03*
X1665141Y1218570D03*
X1672583Y1215223D03*
Y1221916D03*
X1665141Y1235302D03*
Y1241995D03*
X1672583Y1231955D03*
Y1238648D03*
X1665141Y1248688D03*
X1672583Y1245341D03*
X1665688Y1257964D03*
X1672583Y1255381D03*
Y1258727D03*
Y1248688D03*
X1659488Y1273344D03*
X1662288D03*
X1672188Y1263764D03*
X1686041Y766798D03*
X1686141Y850459D03*
X1681283Y847113D03*
X1686141Y857152D03*
Y867192D03*
X1681283Y853806D03*
Y863845D03*
X1686141Y873885D03*
Y880577D03*
X1681283Y870538D03*
Y877231D03*
Y883924D03*
X1686141Y887270D03*
Y893963D03*
X1681283Y890617D03*
Y900656D03*
X1686141Y904003D03*
Y910696D03*
Y917389D03*
X1681283Y907349D03*
Y914042D03*
X1686141Y924081D03*
Y930774D03*
X1681283Y920735D03*
Y927428D03*
X1686141Y940814D03*
Y947507D03*
X1681283Y937467D03*
Y944160D03*
X1686141Y954200D03*
Y964239D03*
X1681283Y950853D03*
Y960892D03*
X1686141Y970932D03*
Y977625D03*
X1681283Y967585D03*
Y974278D03*
Y980971D03*
X1686141Y984318D03*
Y991011D03*
X1681283Y987664D03*
X1686141Y1017782D03*
Y1024475D03*
Y1031168D03*
X1681283Y1017782D03*
Y1027822D03*
X1686141Y1037861D03*
Y1044554D03*
X1681283Y1034515D03*
Y1041207D03*
Y1047900D03*
X1686141Y1051247D03*
Y1057940D03*
X1681283Y1061286D03*
Y1054593D03*
X1686141Y1064633D03*
Y1071326D03*
Y1078018D03*
X1681283Y1067979D03*
Y1074672D03*
X1686141Y1088058D03*
Y1094751D03*
X1681283Y1084711D03*
Y1091404D03*
X1686141Y1101444D03*
Y1108137D03*
X1681283Y1098097D03*
Y1104790D03*
Y1111483D03*
X1686141Y1114829D03*
Y1124869D03*
X1681283Y1121522D03*
Y1128215D03*
X1686141Y1131562D03*
Y1138255D03*
Y1144948D03*
X1681283Y1134908D03*
Y1141601D03*
X1686141Y1151641D03*
Y1161680D03*
X1681283Y1148294D03*
Y1158333D03*
X1686141Y1168373D03*
Y1175066D03*
X1681283Y1165026D03*
Y1171719D03*
X1686141Y1181759D03*
Y1188452D03*
X1681283Y1178412D03*
Y1185105D03*
X1686141Y1198491D03*
Y1205184D03*
X1681283Y1195144D03*
Y1201837D03*
Y1208530D03*
X1686141Y1211877D03*
Y1218570D03*
Y1225263D03*
X1681283Y1215223D03*
Y1221916D03*
Y1231955D03*
Y1238648D03*
X1686141Y1235302D03*
Y1241995D03*
X1681283Y1245341D03*
X1686141Y1248688D03*
Y1258727D03*
X1681179Y1252034D03*
X1683578Y1253780D03*
X1675488Y1273344D03*
X1678288D03*
X1689188D03*
X1686119Y1264985D03*
X1681309Y1262074D03*
X1683500Y1264312D03*
X1702183Y957546D03*
Y954200D03*
Y994357D03*
X1702283Y1057940D03*
X1694841Y1235302D03*
Y1241995D03*
X1702283Y1231955D03*
Y1238648D03*
X1694841Y1248688D03*
X1695188Y1257064D03*
X1702283Y1245341D03*
X1699852Y1245418D03*
X1699089Y1258842D03*
X1702283Y1248688D03*
X1691988Y1273344D03*
X1705188D03*
X1702249Y1265420D03*
X1702283Y1262074D03*
X1699030Y1263912D03*
X1715841Y766798D03*
Y1061286D03*
X1710983Y1231955D03*
Y1238648D03*
X1715841Y1235302D03*
Y1241995D03*
X1710983Y1245341D03*
X1715841Y1248688D03*
X1713620Y1258512D03*
X1711109Y1252034D03*
X1713930Y1262074D03*
X1707514Y1273444D03*
X1718888Y1273344D03*
X1721688D03*
X1715839Y1265420D03*
X1731983Y957546D03*
Y954200D03*
Y994357D03*
X1731683Y1057940D03*
X1724541Y1235302D03*
Y1241995D03*
X1731983Y1231955D03*
Y1238648D03*
X1724541Y1248688D03*
X1724588Y1257164D03*
X1731983Y1245341D03*
X1727041Y1248688D03*
X1731983Y1255381D03*
Y1258727D03*
Y1252034D03*
Y1248688D03*
X1734888Y1273344D03*
X1737688D03*
X1731939Y1265420D03*
X1731983Y1262074D03*
X1745541Y770144D03*
X1754241D03*
X1745541Y766798D03*
Y776837D03*
X1754241D03*
X1745541Y783530D03*
X1754241D03*
X1745541Y793570D03*
X1754241D03*
X1745541Y800263D03*
X1754241D03*
X1745541Y806955D03*
X1754241D03*
X1745541Y813648D03*
X1754241D03*
X1745541Y820341D03*
X1754241D03*
X1745541Y830381D03*
X1754241D03*
Y843766D03*
X1745541D03*
Y837074D03*
X1754241D03*
X1745541Y850459D03*
X1754241D03*
X1745541Y857152D03*
X1754241D03*
Y867192D03*
X1745541D03*
Y873885D03*
X1754241D03*
X1745541Y880577D03*
X1754241D03*
Y893963D03*
X1745541D03*
Y887270D03*
X1754241D03*
Y904003D03*
X1745541D03*
X1754241Y910696D03*
X1745541D03*
X1754241Y917389D03*
X1745541D03*
X1754241Y924081D03*
X1745541D03*
X1754241Y930774D03*
X1745541D03*
X1754241Y940814D03*
X1745541D03*
X1754241Y947507D03*
X1745541D03*
X1754241Y954200D03*
X1745541D03*
X1754241Y964239D03*
X1745541D03*
X1754241Y970932D03*
X1745541D03*
X1754241Y977625D03*
X1745541D03*
X1754241Y984318D03*
X1745541D03*
X1754241Y991011D03*
X1745541D03*
X1754241Y1017782D03*
X1745541D03*
Y1024475D03*
X1754241D03*
X1745541Y1031168D03*
X1754241D03*
Y1044554D03*
X1745541D03*
Y1037861D03*
X1754241D03*
X1745541Y1051247D03*
X1754241D03*
X1745541Y1057940D03*
X1754241D03*
Y1071326D03*
X1745541D03*
Y1064633D03*
X1754241D03*
Y1078018D03*
X1745541D03*
X1754241Y1088058D03*
X1745541D03*
X1754241Y1094751D03*
X1745541D03*
X1754241Y1101444D03*
X1745541D03*
X1754241Y1108137D03*
X1745541D03*
X1754241Y1114829D03*
X1745541D03*
X1754241Y1124869D03*
X1745541D03*
X1754241Y1131562D03*
X1745541D03*
X1754241Y1138255D03*
X1745541D03*
X1754241Y1144948D03*
X1745541D03*
X1754241Y1151641D03*
X1745541D03*
X1754241Y1161680D03*
X1745541D03*
Y1175066D03*
X1754241D03*
Y1168373D03*
X1745541D03*
Y1181759D03*
X1754241D03*
Y1188452D03*
X1745541D03*
X1754241Y1198491D03*
X1745541D03*
X1754241Y1205184D03*
X1745541D03*
X1754241Y1211877D03*
X1745541D03*
X1754241Y1218570D03*
X1745541D03*
X1754241Y1225263D03*
X1745541D03*
X1740683Y1231955D03*
Y1238648D03*
X1754241Y1235302D03*
X1745541D03*
X1754241Y1241995D03*
X1745541D03*
X1740683Y1245341D03*
X1754241Y1248688D03*
X1745541D03*
X1754488Y1257264D03*
X1745541Y1258727D03*
X1743710Y1262074D03*
X1742337Y1252300D03*
X1751388Y1273344D03*
X1748588D03*
X1745541Y1265420D03*
X1749088Y1310474D03*
X1746288D03*
X1770383Y766798D03*
X1761683D03*
X1770383Y773491D03*
X1761683D03*
Y780184D03*
X1770383D03*
X1761683Y790223D03*
X1770383D03*
X1761683Y796916D03*
X1770383D03*
X1761683Y803609D03*
X1770383D03*
X1761683Y810302D03*
X1770383D03*
X1761683Y816995D03*
X1770383D03*
X1761683Y827034D03*
X1770383D03*
X1761683Y833727D03*
X1770383D03*
X1761683Y840420D03*
X1770383D03*
X1761683Y847113D03*
X1770383D03*
X1761683Y853806D03*
X1770383D03*
X1761683Y863845D03*
X1770383D03*
X1761683Y870538D03*
X1770383D03*
X1761683Y877231D03*
X1770383D03*
X1761683Y883924D03*
X1770383D03*
X1761683Y890617D03*
X1770383D03*
X1761683Y900656D03*
X1770383D03*
X1761683Y907349D03*
X1770383D03*
X1761683Y914042D03*
X1770383D03*
Y927428D03*
X1761683D03*
Y920735D03*
X1770383D03*
X1761683Y937467D03*
X1770383D03*
X1761683Y944160D03*
X1770383D03*
X1761683Y950853D03*
X1770383D03*
X1761683Y960892D03*
X1770383D03*
X1761683Y957546D03*
Y954200D03*
Y967585D03*
X1770383D03*
X1761683Y974278D03*
X1770383D03*
X1761683Y980971D03*
X1770383D03*
X1761683Y987664D03*
X1770383D03*
X1761683Y994357D03*
Y1017782D03*
X1770383D03*
X1761683Y1027822D03*
X1770383D03*
X1761683Y1034515D03*
X1770383D03*
X1761683Y1041207D03*
X1770383D03*
X1761683Y1047900D03*
X1770383D03*
X1761683Y1054593D03*
X1770383D03*
X1761683Y1061286D03*
X1770383D03*
X1761683Y1067979D03*
X1770383D03*
X1761683Y1074672D03*
X1770383D03*
X1761683Y1084711D03*
X1770383D03*
X1761683Y1091404D03*
X1770383D03*
Y1098097D03*
X1761683D03*
Y1104790D03*
X1770383D03*
X1761683Y1111483D03*
X1770383D03*
X1761683Y1121522D03*
X1770383D03*
X1761683Y1128215D03*
X1770383D03*
X1761683Y1134908D03*
X1770383D03*
X1761683Y1141601D03*
X1770383D03*
X1761683Y1148294D03*
X1770383D03*
X1761683Y1158333D03*
X1770383D03*
X1761683Y1165026D03*
X1770383D03*
X1761683Y1171719D03*
X1770383D03*
X1761683Y1178412D03*
X1770383D03*
X1761683Y1185105D03*
X1770383D03*
X1761683Y1195144D03*
X1770383D03*
X1761683Y1201837D03*
X1770383D03*
X1761683Y1208530D03*
X1770383D03*
X1761683Y1215223D03*
X1770383D03*
X1761683Y1221916D03*
X1770383D03*
X1761683Y1231955D03*
X1770383D03*
X1761683Y1238648D03*
X1770383D03*
X1761683Y1245341D03*
X1770383D03*
X1756922Y1247632D03*
X1761683Y1255381D03*
Y1258727D03*
X1770299Y1252034D03*
X1761683Y1248688D03*
X1767388Y1273344D03*
X1764588D03*
X1761683Y1262074D03*
Y1265420D03*
X1775241Y770144D03*
X1783941D03*
X1773559Y767345D03*
X1775241Y776837D03*
X1783941D03*
X1775241Y783530D03*
X1783941D03*
X1775241Y780184D03*
Y773491D03*
Y786877D03*
Y793570D03*
X1783941D03*
X1775241Y800263D03*
X1783941D03*
X1775241Y803609D03*
Y796916D03*
Y790223D03*
Y806955D03*
X1783941D03*
X1775241Y813648D03*
X1783941D03*
X1775241Y820341D03*
X1783941D03*
Y830381D03*
X1775241D03*
Y837074D03*
X1783941D03*
X1775241Y843766D03*
X1783941D03*
X1775241Y850459D03*
X1783941D03*
X1775241Y847113D03*
Y857152D03*
X1783941D03*
X1775241Y867192D03*
X1783941D03*
X1775241Y853806D03*
Y860499D03*
Y863845D03*
Y873885D03*
X1783941D03*
X1775241Y880577D03*
X1783941D03*
X1775241Y883924D03*
Y877231D03*
Y870538D03*
Y887270D03*
X1783941D03*
X1775241Y893963D03*
X1783941D03*
X1775241Y890617D03*
Y897310D03*
Y900656D03*
Y904003D03*
X1783941D03*
X1775241Y910696D03*
X1783941D03*
X1775241Y917389D03*
X1783941D03*
X1775241Y914042D03*
Y907349D03*
Y924081D03*
X1783941D03*
X1775241Y930774D03*
X1783941D03*
X1775241Y927428D03*
Y920735D03*
Y934121D03*
Y940814D03*
X1783941D03*
X1775241Y947507D03*
X1783941D03*
X1775241Y944160D03*
Y937467D03*
Y954200D03*
X1783941D03*
X1775241Y964239D03*
X1783941D03*
X1775241Y950853D03*
Y970932D03*
X1783941D03*
X1775241Y977625D03*
X1783941D03*
X1775241Y980971D03*
Y974278D03*
Y984318D03*
X1783941D03*
X1775241Y991011D03*
X1783941D03*
X1775241Y994357D03*
Y987664D03*
Y1017782D03*
X1783941D03*
X1775241Y1024475D03*
X1783941D03*
X1775241Y1031168D03*
X1783941D03*
X1775241Y1027822D03*
Y1021129D03*
Y1037861D03*
X1783941D03*
X1775241Y1044554D03*
X1783941D03*
X1775241Y1047900D03*
Y1041207D03*
Y1034515D03*
Y1051247D03*
X1783941D03*
X1775241Y1057940D03*
X1783941D03*
X1775241Y1061286D03*
Y1054593D03*
Y1064633D03*
X1783941D03*
X1775241Y1071326D03*
X1783941D03*
X1775241Y1078018D03*
X1783941D03*
X1775241Y1074672D03*
Y1067979D03*
Y1088058D03*
X1783941D03*
X1775241Y1094751D03*
X1783941D03*
X1775241Y1091404D03*
Y1081365D03*
Y1084711D03*
Y1101444D03*
X1783941D03*
X1775241Y1108137D03*
X1783941D03*
X1775241Y1098097D03*
Y1111483D03*
Y1104790D03*
Y1114829D03*
X1783941D03*
X1775241Y1124869D03*
X1783941D03*
X1775241Y1128215D03*
Y1118176D03*
Y1121522D03*
Y1131562D03*
X1783941D03*
X1775241Y1138255D03*
X1783941D03*
X1775241Y1144948D03*
X1783941D03*
X1775241Y1141601D03*
Y1134908D03*
X1783941Y1151641D03*
X1775241D03*
Y1161680D03*
X1783941D03*
X1775241Y1148294D03*
Y1154987D03*
Y1158333D03*
Y1168373D03*
X1783941D03*
X1775241Y1175066D03*
X1783941D03*
X1775241Y1171719D03*
Y1165026D03*
Y1181759D03*
X1783941D03*
X1775241Y1188452D03*
X1783941D03*
X1775241Y1185105D03*
Y1178412D03*
Y1191798D03*
Y1198491D03*
X1783941D03*
X1775241Y1205184D03*
X1783941D03*
X1775241Y1208530D03*
Y1201837D03*
Y1195144D03*
Y1211877D03*
X1783941D03*
X1775241Y1218570D03*
X1783941D03*
X1775241Y1225263D03*
X1783941D03*
X1775241Y1235302D03*
X1783941D03*
X1775241Y1241995D03*
X1783941D03*
X1784188Y1257664D03*
X1775241Y1248688D03*
X1783941D03*
X1775241Y1258727D03*
X1788219Y1259312D03*
X1773390Y1262074D03*
X1773480Y1253692D03*
X1781088Y1273344D03*
X1778288D03*
X1775241Y1265420D03*
X1788360Y1264522D03*
X1791383Y766798D03*
X1800083D03*
X1791383Y770144D03*
Y773491D03*
X1800083D03*
X1791383Y780184D03*
X1800083D03*
X1791383Y776837D03*
Y786877D03*
Y783530D03*
Y790223D03*
X1800083D03*
X1791383Y796916D03*
X1800083D03*
X1791383Y803609D03*
X1800083D03*
X1791383Y800263D03*
Y793570D03*
Y810302D03*
X1800083D03*
X1791383Y816995D03*
X1800083D03*
X1791383Y827034D03*
X1800083D03*
Y833727D03*
X1791383D03*
Y840420D03*
X1800083D03*
X1791383Y847113D03*
X1800083D03*
X1791383Y850459D03*
Y843766D03*
Y853806D03*
X1800083D03*
X1791383Y863845D03*
X1800083D03*
X1791383Y867192D03*
Y860499D03*
Y857152D03*
Y870538D03*
X1800083D03*
X1791383Y877231D03*
X1800083D03*
X1791383Y883924D03*
X1800083D03*
X1791383Y873885D03*
Y880577D03*
Y890617D03*
X1800083D03*
X1791383Y900656D03*
X1800083D03*
X1791383Y887270D03*
Y897310D03*
Y893963D03*
Y907349D03*
X1800083D03*
X1791383Y914042D03*
X1800083D03*
X1791383Y917389D03*
Y910696D03*
Y904003D03*
Y920735D03*
X1800083D03*
X1791383Y927428D03*
X1800083D03*
X1791383Y924081D03*
Y934121D03*
Y930774D03*
Y937467D03*
X1800083D03*
X1791383Y944160D03*
X1800083D03*
X1791383Y947507D03*
Y940814D03*
X1800083Y950853D03*
X1791383D03*
Y960892D03*
X1800083D03*
X1791383Y957546D03*
Y954200D03*
Y967585D03*
X1800083D03*
X1791383Y974278D03*
X1800083D03*
X1791383Y980971D03*
X1800083D03*
X1791383Y977625D03*
Y970932D03*
Y987664D03*
X1800083D03*
X1791383Y991011D03*
Y984318D03*
Y994357D03*
Y1017782D03*
X1800083D03*
X1791383Y1027822D03*
X1800083D03*
X1791383Y1021129D03*
Y1024475D03*
Y1031168D03*
Y1034515D03*
X1800083D03*
X1791383Y1041207D03*
X1800083D03*
X1791383Y1047900D03*
X1800083D03*
X1791383Y1044554D03*
Y1037861D03*
Y1054593D03*
X1800083D03*
X1791383Y1061286D03*
X1800083D03*
X1791083Y1051247D03*
X1791383Y1067979D03*
X1800083D03*
X1791383Y1074672D03*
X1800083D03*
X1791383Y1071325D03*
Y1064633D03*
Y1078018D03*
Y1084711D03*
X1800083D03*
X1791383Y1091404D03*
X1800083D03*
X1791383Y1094751D03*
Y1088058D03*
Y1081365D03*
Y1098097D03*
X1800083D03*
X1791383Y1104790D03*
X1800083D03*
X1791383Y1111483D03*
X1800083D03*
X1791383Y1108136D03*
Y1101444D03*
Y1121522D03*
X1800083D03*
X1791383Y1128215D03*
X1800083D03*
X1791383Y1124869D03*
Y1118176D03*
Y1114829D03*
X1800083Y1134908D03*
X1791383D03*
Y1141601D03*
X1800083D03*
X1791383Y1144947D03*
Y1138255D03*
Y1131562D03*
Y1148294D03*
X1800083D03*
X1791383Y1158333D03*
X1800083D03*
X1791383Y1161680D03*
Y1154987D03*
Y1151640D03*
Y1165026D03*
X1800083D03*
X1791383Y1171719D03*
X1800083D03*
X1791383Y1175066D03*
Y1168373D03*
Y1178412D03*
X1800083D03*
X1791383Y1185105D03*
X1800083D03*
X1791383Y1181758D03*
Y1191798D03*
Y1188451D03*
Y1195144D03*
X1800083D03*
X1791383Y1201837D03*
X1800083D03*
X1791383Y1208530D03*
X1800083D03*
X1791383Y1205184D03*
Y1198491D03*
Y1215223D03*
X1800083D03*
X1791383Y1221916D03*
X1800083D03*
X1791383Y1231955D03*
X1800083D03*
X1791383Y1238648D03*
X1800083D03*
X1788373Y1241769D03*
X1791383Y1245341D03*
X1800083D03*
X1800427Y1248125D03*
X1803100Y1262074D03*
X1800019Y1252034D03*
X1791383Y1248688D03*
X1797088Y1273344D03*
X1794288D03*
X1791383Y1265420D03*
Y1262074D03*
X1804941Y770144D03*
X1813641D03*
X1804841Y766798D03*
X1804941Y776837D03*
X1813641D03*
X1804941Y783530D03*
X1813641D03*
X1804941Y793570D03*
X1813641D03*
X1804941Y800263D03*
X1813641D03*
X1804941Y806955D03*
X1813641D03*
X1804941Y813648D03*
X1813641D03*
X1804941Y820341D03*
X1813641D03*
X1804941Y830381D03*
X1813641D03*
X1804941Y843766D03*
X1813641D03*
X1804941Y837074D03*
X1813641D03*
X1804941Y850459D03*
X1813641D03*
X1804941Y857152D03*
X1813641D03*
Y867192D03*
X1804941D03*
Y873885D03*
X1813641D03*
X1804941Y880577D03*
X1813641D03*
X1804941Y887270D03*
X1813641D03*
X1804941Y893963D03*
X1813641D03*
X1804941Y904003D03*
X1813641D03*
X1804941Y910696D03*
X1813641D03*
X1804941Y917389D03*
X1813641D03*
X1804941Y924081D03*
X1813641D03*
X1804941Y930774D03*
X1813641D03*
X1804941Y940814D03*
X1813641D03*
X1804941Y947507D03*
X1813641D03*
X1804941Y954200D03*
X1813641D03*
X1804941Y964239D03*
X1813641D03*
X1804941Y970932D03*
X1813641D03*
X1804941Y977625D03*
X1813641D03*
X1804941Y984318D03*
X1813641D03*
X1804941Y991011D03*
X1813641D03*
X1804941Y1017782D03*
X1813641D03*
X1804941Y1024475D03*
X1813641D03*
X1804941Y1031168D03*
X1813641D03*
X1804941Y1037861D03*
X1813641D03*
X1804941Y1044554D03*
X1813641D03*
Y1057940D03*
X1804941D03*
Y1051247D03*
X1813641D03*
X1804941Y1054593D03*
Y1064633D03*
X1813641D03*
Y1071326D03*
X1804941D03*
X1813641Y1078018D03*
X1804941D03*
X1813641Y1088058D03*
X1804941D03*
X1813641Y1094751D03*
X1804941D03*
X1813641Y1101444D03*
X1804941D03*
X1813641Y1108137D03*
X1804941D03*
X1813641Y1114829D03*
X1804941D03*
X1813641Y1124869D03*
X1804941D03*
X1813641Y1131562D03*
X1804941D03*
X1813641Y1138255D03*
X1804941D03*
X1813641Y1144948D03*
X1804941D03*
X1813641Y1151641D03*
X1804941D03*
X1813641Y1161680D03*
X1804941D03*
X1813641Y1168373D03*
X1804941D03*
X1813641Y1175066D03*
X1804941D03*
X1813641Y1181759D03*
X1804941D03*
X1813641Y1188452D03*
X1804941D03*
X1813641Y1198491D03*
X1804941D03*
X1813641Y1205184D03*
X1804941D03*
X1813641Y1211877D03*
X1804941D03*
X1813641Y1218570D03*
X1804941D03*
X1813641Y1225263D03*
X1804941D03*
X1813641Y1235302D03*
X1804941D03*
X1813641Y1241995D03*
X1804941D03*
X1815063Y1233103D03*
X1813641Y1248688D03*
X1804941D03*
X1819054Y1253986D03*
X1804941Y1258727D03*
X1813814Y1254693D03*
X1818188Y1273044D03*
X1810788Y1273344D03*
X1807988D03*
X1815388Y1273044D03*
X1804941Y1265420D03*
X1829783Y766798D03*
X1821083D03*
X1829783Y773491D03*
X1821083D03*
X1829783Y780184D03*
X1821083D03*
X1829783Y790223D03*
X1821083D03*
X1829783Y796916D03*
X1821083D03*
X1829783Y803609D03*
X1821083D03*
X1829783Y810302D03*
X1821083D03*
X1829783Y816995D03*
X1821083D03*
X1829783Y827034D03*
X1821083D03*
X1829783Y833727D03*
X1821083D03*
Y847113D03*
X1829783D03*
Y840420D03*
X1821083D03*
X1829783Y853806D03*
X1821083D03*
X1829783Y863845D03*
X1821083D03*
X1829783Y870538D03*
X1821083D03*
X1829783Y877231D03*
X1821083D03*
X1829783Y883924D03*
X1821083D03*
X1829783Y890617D03*
X1821083D03*
X1829783Y900656D03*
X1821083D03*
X1829783Y907349D03*
X1821083D03*
X1829783Y914042D03*
X1821083D03*
X1829783Y920735D03*
X1821083D03*
X1829783Y927428D03*
X1821083D03*
X1829783Y937467D03*
X1821083D03*
X1829783Y944160D03*
X1821083D03*
X1829783Y950853D03*
X1821083D03*
X1829783Y960892D03*
X1821083D03*
X1820983Y957546D03*
Y954200D03*
X1829783Y967585D03*
X1821083D03*
X1829783Y974278D03*
X1821083D03*
X1829783Y980971D03*
X1821083D03*
X1829783Y987664D03*
X1821083D03*
X1820983Y994357D03*
X1829783Y1017782D03*
X1821083D03*
X1829783Y1027822D03*
X1821083D03*
Y1021129D03*
Y1024475D03*
X1829783Y1034515D03*
X1821083D03*
X1829783Y1041207D03*
X1821083D03*
X1829783Y1047900D03*
X1821083D03*
X1829783Y1054593D03*
X1821083D03*
X1829783Y1061286D03*
X1821083D03*
Y1051247D03*
X1829783Y1067979D03*
X1821083D03*
Y1074672D03*
X1829783D03*
X1821083Y1084711D03*
X1829783D03*
X1821083Y1091404D03*
X1829783D03*
X1821083Y1098097D03*
X1829783D03*
X1821083Y1104790D03*
X1829783D03*
X1821083Y1111483D03*
X1829783D03*
X1821083Y1121522D03*
X1829783D03*
X1821083Y1128215D03*
X1829783D03*
X1821083Y1134908D03*
X1829783D03*
X1821083Y1141601D03*
X1829783D03*
X1821083Y1148294D03*
X1829783D03*
X1821083Y1158333D03*
X1829783D03*
X1821083Y1165026D03*
X1829783D03*
X1821083Y1171719D03*
X1829783D03*
X1821083Y1178412D03*
X1829783D03*
X1821083Y1185105D03*
X1829783D03*
X1821083Y1195144D03*
X1829783D03*
X1821083Y1201837D03*
X1829783D03*
X1821083Y1208530D03*
X1829783D03*
X1821083Y1215223D03*
X1829783D03*
X1821083Y1221916D03*
X1829783D03*
X1821083Y1231955D03*
X1829783D03*
X1821083Y1238648D03*
X1829783D03*
Y1245341D03*
X1821083D03*
X1830379Y1250358D03*
X1829920Y1258322D03*
X1821139Y1248155D03*
X1821083Y1262074D03*
Y1265420D03*
X1829940Y1263662D03*
G54D28*
X159474Y1320753D03*
X183847Y1320778D03*
X208247D03*
X275289Y575702D03*
Y599861D03*
Y624015D03*
Y648169D03*
X278126Y676260D03*
Y700414D03*
X395771Y1242785D03*
X420171D03*
X444493D03*
X468893D03*
X493293D03*
X673093Y1320778D03*
X697466Y1320803D03*
X721866D03*
X1100800Y251488D03*
X1100700Y275788D03*
X1131100Y1357088D03*
X1155500D03*
X1179900D03*
X1371912Y1242785D03*
X1396312D03*
X1420634D03*
X1445034D03*
X1469434D03*
X1577000Y591888D03*
Y616388D03*
Y640888D03*
Y665288D03*
Y689788D03*
Y714288D03*
X1634259Y1354374D03*
X1658632Y1354399D03*
X1683032D03*
G54D48*
X705760Y-26500D03*
Y-16500D03*
D03*
Y-6500D03*
X730760Y-26500D03*
Y-16500D03*
D03*
Y-6500D03*
X822720Y3500D03*
Y13500D03*
D03*
Y23500D03*
X847720Y3500D03*
Y13500D03*
D03*
Y23500D03*
X973180Y-26500D03*
Y-16500D03*
D03*
Y-6500D03*
Y3500D03*
Y13500D03*
Y23500D03*
Y13500D03*
X998180Y-26500D03*
Y-16500D03*
D03*
Y-6500D03*
Y3500D03*
Y13500D03*
Y23500D03*
Y13500D03*
X1015152Y-26511D03*
Y-36511D03*
Y-26511D03*
Y-16511D03*
D03*
Y-6511D03*
D03*
Y3489D03*
D03*
Y13489D03*
D03*
Y23489D03*
X1040152Y-26511D03*
Y-36511D03*
Y-26511D03*
Y-16511D03*
D03*
Y-6511D03*
D03*
Y3489D03*
D03*
Y13489D03*
D03*
Y23489D03*
X1282572Y-36511D03*
Y-26511D03*
D03*
Y-16511D03*
D03*
Y-6511D03*
Y3489D03*
Y-6511D03*
Y3489D03*
Y13489D03*
Y23489D03*
Y13489D03*
X1307572Y-36511D03*
Y-26511D03*
D03*
Y-16511D03*
D03*
Y-6511D03*
Y3489D03*
Y-6511D03*
Y3489D03*
Y13489D03*
Y23489D03*
Y13489D03*
X1324471Y-26511D03*
Y-36511D03*
Y-26511D03*
Y-16511D03*
D03*
Y-6511D03*
D03*
Y3489D03*
D03*
Y13489D03*
D03*
Y23489D03*
X1349471Y-26511D03*
Y-36511D03*
Y-26511D03*
Y-16511D03*
D03*
Y-6511D03*
D03*
Y3489D03*
D03*
Y13489D03*
D03*
Y23489D03*
X1474931Y-36511D03*
Y-26511D03*
D03*
Y-16511D03*
D03*
Y-6511D03*
Y3489D03*
Y-6511D03*
Y3489D03*
Y13489D03*
Y23489D03*
Y13489D03*
X1499931Y-36511D03*
Y-26511D03*
D03*
Y-16511D03*
D03*
Y-6511D03*
Y3489D03*
Y-6511D03*
Y3489D03*
Y13489D03*
Y23489D03*
Y13489D03*
X1565236Y184783D03*
Y264035D03*
G54D21*
X57646Y12480D03*
X137272D03*
X186622D03*
X266858D03*
X315598D03*
X502528Y33268D03*
X582154D03*
X631504D03*
X711740D03*
X760480D03*
X1156378Y133866D03*
X1532055Y12480D03*
X1611681D03*
X1661031D03*
X1741267D03*
X1790007D03*
G54D25*
X73865Y763164D03*
X79451Y699517D03*
X104875Y490980D03*
X102384Y505374D03*
X108909Y654926D03*
X102909Y648926D03*
Y642926D03*
Y655102D03*
X108909Y642926D03*
X114909Y654926D03*
Y648926D03*
Y642926D03*
X149557Y494353D03*
X149472Y506810D03*
X149512Y514810D03*
X151277Y1339183D03*
X153877D03*
X156417Y1336343D03*
X151217Y1336393D03*
X153817D03*
X156417Y1333843D03*
X151217Y1333893D03*
X153817D03*
X151277Y1346883D03*
X153877D03*
X151277Y1349383D03*
X153877D03*
X156477Y1344383D03*
X151277D03*
X153877D03*
X156477Y1341883D03*
X151277D03*
X153877D03*
X157490Y1421454D03*
X154990D03*
X157530Y1432124D03*
X155030D03*
X157530Y1424124D03*
X155030D03*
X157530Y1429124D03*
X155030Y1426624D03*
Y1429124D03*
X157530Y1426624D03*
Y1435124D03*
X155030D03*
X157530Y1437754D03*
X155030D03*
X170877Y1333783D03*
Y1336383D03*
X170907Y1339233D03*
X170877Y1341883D03*
X160490Y1421454D03*
X160530Y1432124D03*
Y1424124D03*
Y1429124D03*
Y1426624D03*
Y1435124D03*
Y1437754D03*
X165500Y1440362D03*
X189377Y1333783D03*
Y1336383D03*
X191977D03*
X191947Y1339263D03*
X189347D03*
X189377Y1349383D03*
X191977D03*
X189377Y1346883D03*
X191977D03*
Y1344383D03*
X189377D03*
X191977Y1341883D03*
X189377D03*
X194858Y684348D03*
X208977Y1336383D03*
Y1333783D03*
X194577Y1336383D03*
X209007Y1339263D03*
X194547D03*
X208977Y1341883D03*
X194577Y1344383D03*
Y1341883D03*
X285357Y105003D03*
X288557D03*
X280857Y107303D03*
X285857Y115603D03*
X282857D03*
X280857Y109903D03*
X284482Y566022D03*
X286582Y637809D03*
Y634283D03*
X301183Y107103D03*
Y110003D03*
Y112803D03*
X311057Y107103D03*
Y110003D03*
Y112803D03*
X320578Y1290197D03*
X323028Y1297967D03*
X320428D03*
Y1295467D03*
X323028D03*
Y1292967D03*
X320428D03*
X339148Y1269717D03*
X339088Y1272287D03*
X339028Y1274887D03*
X325688Y1290167D03*
X325718Y1287587D03*
X328078Y1288747D03*
X323178Y1290197D03*
X323208Y1287617D03*
X328168Y1280967D03*
X325748Y1284987D03*
X328108Y1286147D03*
X328138Y1283567D03*
X328018Y1291317D03*
X339035Y1280218D03*
X339040Y1277594D03*
X328065Y1299248D03*
X325538Y1297937D03*
Y1292937D03*
Y1295437D03*
X328058Y1293917D03*
X328070Y1296624D03*
X331515Y1326704D03*
X344258Y1267117D03*
X341748Y1267147D03*
X355036Y1272433D03*
Y1269933D03*
X355378Y1262027D03*
X355318Y1264597D03*
X355258Y1267197D03*
X355036Y1274933D03*
X341605Y1280248D03*
X344115Y1280218D03*
X355048Y1277440D03*
X355025Y1280248D03*
X352713Y1399336D03*
X355513Y1402306D03*
X352513D03*
X349513D03*
X355325Y1405386D03*
X349463Y1405286D03*
X352463D03*
X355325Y1408386D03*
X352401Y1414432D03*
X355325Y1414386D03*
Y1417386D03*
X352401Y1411432D03*
X355325Y1411386D03*
X352401Y1408432D03*
X349123Y1411376D03*
X349323Y1408406D03*
X349073Y1414356D03*
X352231Y1417332D03*
X348903Y1417256D03*
X363525Y158702D03*
X371578Y1248967D03*
X371458Y1254137D03*
X371330Y1256687D03*
X371518Y1251537D03*
X371278Y1259257D03*
X360198Y1269777D03*
X357546Y1272403D03*
Y1269903D03*
X360138Y1272347D03*
X357828Y1264567D03*
X357888Y1261997D03*
X360378Y1264627D03*
X360438Y1262057D03*
X357768Y1267167D03*
X360318Y1267227D03*
X357546Y1274903D03*
X360128Y1274957D03*
X371218Y1261857D03*
X371225Y1267188D03*
X371230Y1264564D03*
X357558Y1277410D03*
X357535Y1280218D03*
X360120Y1277654D03*
X355713Y1399336D03*
X361703Y1399386D03*
X364703D03*
X367703D03*
X370703D03*
X358703Y1402386D03*
X361703D03*
X364703D03*
X367703D03*
X370703D03*
X358713Y1399336D03*
X358573Y1405336D03*
X361573D03*
X364573D03*
X367573D03*
X370573D03*
X358703Y1414606D03*
X361703D03*
X364703D03*
X361703Y1417386D03*
X358703D03*
X364703D03*
X367703D03*
Y1414606D03*
X358217Y1411405D03*
X370517Y1414615D03*
X370717Y1417405D03*
X357917Y1408205D03*
X376638Y1248997D03*
X374088Y1248937D03*
X374028Y1251507D03*
X376518Y1254167D03*
X376578Y1251567D03*
X373968Y1254107D03*
X387478Y1248967D03*
X387358Y1254137D03*
X387117Y1256851D03*
X387418Y1251537D03*
X387117Y1259351D03*
X376285Y1267218D03*
X373735Y1267158D03*
X387117Y1261851D03*
X387129Y1264358D03*
X387125Y1267188D03*
X376825Y1399386D03*
X379825D03*
X373703D03*
X379825Y1402386D03*
X376825D03*
X373703D03*
X376825Y1405386D03*
X379825D03*
X373573Y1405336D03*
X374027Y1411365D03*
X373703Y1414606D03*
X376825Y1414386D03*
X379825D03*
X376825Y1417386D03*
Y1411386D03*
X379825D03*
X373703Y1417386D03*
X376825Y1408386D03*
X379825D03*
X374307Y1408135D03*
X403738Y1249027D03*
X403618Y1254197D03*
X403498Y1256747D03*
X403678Y1251597D03*
X392538Y1248997D03*
X389928Y1251507D03*
X389988Y1248937D03*
X389868Y1254107D03*
X392298Y1256717D03*
X392418Y1254167D03*
X389627Y1256821D03*
X392478Y1251567D03*
X392238Y1259287D03*
X389627Y1259321D03*
X403438Y1259317D03*
X392220Y1264594D03*
X392228Y1261897D03*
X389627Y1261821D03*
X389639Y1264328D03*
X389635Y1267158D03*
X392185Y1267218D03*
X403385Y1267248D03*
X403378Y1261917D03*
X403390Y1264624D03*
X406248Y1248997D03*
X408798Y1249057D03*
X406128Y1254167D03*
X408678Y1254227D03*
X406188Y1251567D03*
X419638Y1248967D03*
X419295Y1256851D03*
X419518Y1254137D03*
X419578Y1251537D03*
X419295Y1259351D03*
X408738Y1251627D03*
X419295Y1261851D03*
X419307Y1264358D03*
X419285Y1267188D03*
X405895Y1267218D03*
X408445Y1267278D03*
X422148Y1248937D03*
X424698Y1248997D03*
X422088Y1251507D03*
X421805Y1256821D03*
X422028Y1254107D03*
X424458Y1256717D03*
X424578Y1254167D03*
X424638Y1251567D03*
X421805Y1259321D03*
X424398Y1259287D03*
X436068Y1248967D03*
X435828Y1256687D03*
X435948Y1254137D03*
X436008Y1251537D03*
X435768Y1259257D03*
X421805Y1261821D03*
X421817Y1264328D03*
X421795Y1267158D03*
X424345Y1267218D03*
X424380Y1264594D03*
X424388Y1261897D03*
X435715Y1267188D03*
X435720Y1264564D03*
X435708Y1261857D03*
X448276Y1170069D03*
X445776D03*
X443276D03*
X441128Y1248997D03*
X438578Y1248937D03*
X438518Y1251507D03*
X441008Y1254167D03*
X438458Y1254107D03*
X441068Y1251567D03*
X451642Y1256851D03*
X451878Y1254107D03*
X451642Y1259351D03*
X451938Y1251507D03*
X451998Y1248937D03*
X438225Y1267158D03*
X440775Y1267218D03*
X451642Y1261851D03*
X451654Y1264358D03*
X451645Y1267158D03*
X465236Y296973D03*
X456818Y1256687D03*
X454388Y1254077D03*
X454152Y1256821D03*
X456998Y1251537D03*
X456758Y1259257D03*
X454152Y1259321D03*
X468258Y1249107D03*
X468018Y1256827D03*
X468138Y1254277D03*
X468198Y1251677D03*
X467958Y1259397D03*
X457058Y1248967D03*
X454508Y1248907D03*
X454448Y1251477D03*
X456938Y1254137D03*
X456705Y1267188D03*
X454155Y1267128D03*
X456748Y1261867D03*
X456740Y1264564D03*
X454152Y1261821D03*
X454164Y1264328D03*
X467905Y1267328D03*
X467910Y1264704D03*
X467898Y1261997D03*
X458441Y1414893D03*
X456619Y1431189D03*
X473318Y1249137D03*
X470768Y1249077D03*
X473198Y1254307D03*
X470648Y1254247D03*
X473258Y1251707D03*
X470708Y1251647D03*
X484098Y1248997D03*
X483819Y1256851D03*
X483978Y1254167D03*
X484038Y1251567D03*
X483819Y1259351D03*
X472965Y1267358D03*
X470415Y1267298D03*
X483819Y1261851D03*
X483831Y1264358D03*
X483745Y1267218D03*
X498636Y296273D03*
X486861Y305398D03*
X486608Y1248967D03*
X489158Y1249027D03*
X486329Y1256821D03*
X486488Y1254137D03*
X488918Y1256747D03*
X489038Y1254197D03*
X486548Y1251537D03*
X489098Y1251597D03*
X486329Y1259321D03*
X488858Y1259317D03*
X500228Y1259237D03*
X486329Y1261821D03*
X486341Y1264328D03*
X488840Y1264624D03*
X488848Y1261927D03*
X488805Y1267248D03*
X486255Y1267188D03*
X500138Y1269637D03*
X500150Y1272344D03*
X500198Y1267037D03*
Y1264467D03*
X500168Y1261807D03*
X500150Y1275224D03*
X505398Y1259377D03*
X502858Y1259257D03*
X502718Y1271417D03*
X505218Y1271447D03*
X505290Y1267254D03*
X505338Y1261947D03*
X505278Y1264547D03*
X502750Y1267134D03*
X502798Y1261827D03*
X502738Y1264427D03*
X502718Y1274114D03*
X505218Y1274144D03*
X515898Y1271447D03*
X515950Y1274144D03*
X502718Y1276994D03*
X505218Y1277024D03*
X515950D03*
X521561Y505969D03*
Y500469D03*
X521118Y1273097D03*
X518488Y1271477D03*
X521058Y1275667D03*
X518490Y1274144D03*
X521058Y1278277D03*
X521020Y1280974D03*
X518490Y1277024D03*
X530398Y1288557D03*
X530548Y1283377D03*
X530428Y1285947D03*
X530410Y1291254D03*
X532558Y1289967D03*
X532618Y1287367D03*
X532678Y1284797D03*
X530450Y1294134D03*
X532570Y1295554D03*
Y1292674D03*
X524892Y1341462D03*
X522818Y1342930D03*
X537648Y1290037D03*
X535058Y1290007D03*
X535148Y1287397D03*
X535110Y1292704D03*
Y1295584D03*
X537650Y1292704D03*
X540210D03*
X537650Y1295584D03*
X540210D03*
X670037Y1336396D03*
X664987D03*
X667487D03*
X664987Y1338896D03*
X667487D03*
X670037D03*
Y1333896D03*
X664987D03*
X667487D03*
X664987Y1343896D03*
Y1341396D03*
X667487D03*
Y1343896D03*
X670037Y1341396D03*
Y1343896D03*
X674149Y1434149D03*
X671149D03*
X668649D03*
X674149Y1426149D03*
Y1431149D03*
Y1428649D03*
X671149Y1426149D03*
X668649D03*
X671149Y1431149D03*
X668649Y1428649D03*
Y1431149D03*
X671149Y1428649D03*
X677319Y1428359D03*
Y1433359D03*
Y1430859D03*
X671112Y1639962D03*
X681899Y1434049D03*
Y1426049D03*
Y1431049D03*
Y1428549D03*
X697122Y1632667D03*
X683592Y1634844D03*
X697197Y1644667D03*
X712733Y117488D03*
Y114588D03*
X708137Y1336396D03*
Y1338896D03*
X703087Y1336396D03*
X705587D03*
Y1338896D03*
X703087D03*
X708137Y1333896D03*
X705587D03*
X703087D03*
X708137Y1341396D03*
Y1343896D03*
X705587Y1341396D03*
X703087D03*
Y1343896D03*
X705587D03*
X715933Y117488D03*
Y114588D03*
X728733Y132088D03*
Y129288D03*
X720433Y135088D03*
X717433D03*
X728733Y126388D03*
X719933Y124488D03*
X723133D03*
X745725Y167537D03*
X744800Y1664840D03*
X862320Y431462D03*
X989910Y-27961D03*
X989925Y-25446D03*
X983632Y-26655D03*
X989925Y-21572D03*
X983632Y-16626D03*
X989910Y-17932D03*
X989925Y-15417D03*
Y-11543D03*
X989910Y-7903D03*
X989925Y-5388D03*
X983632Y-6597D03*
X989925Y4641D03*
X989910Y2126D03*
X983632Y3432D03*
X989925Y14670D03*
X989910Y12155D03*
X989925Y8515D03*
X983632Y13461D03*
X989925Y19044D03*
X983632Y23990D03*
X978012Y276436D03*
X975512Y282096D03*
X978012D03*
X975512Y279266D03*
X978012D03*
X979940Y292262D03*
Y289762D03*
X975512Y294996D03*
X978012D03*
X979940Y284762D03*
Y287262D03*
X1077973Y246362D03*
X1083973D03*
X1080973D03*
X1077883Y260842D03*
X1076823Y265438D03*
X1083823D03*
X1083883Y260842D03*
X1080883D03*
X1080323Y265438D03*
X1082853Y269492D03*
X1079853D03*
X1075400Y273762D03*
X1078400D03*
X1081400D03*
X1084400D03*
X1087400D03*
X1076018Y289400D03*
X1079018D03*
X1082018D03*
X1085018D03*
X1088018D03*
X1118309Y111687D03*
X1115860Y113883D03*
X1122278Y107549D03*
X1120420Y109829D03*
X1127179Y1372700D03*
X1124679D03*
Y1370200D03*
X1127179D03*
X1129729Y1372700D03*
Y1370200D03*
Y1375200D03*
X1127179D03*
X1124679D03*
X1129729Y1377700D03*
Y1380200D03*
Y1382700D03*
X1127179D03*
X1124679D03*
X1127179Y1380200D03*
Y1377700D03*
X1124679D03*
Y1380200D03*
X1141591Y1462853D03*
Y1465353D03*
Y1468353D03*
Y1471353D03*
Y1460353D03*
X1165279Y1372700D03*
X1162779D03*
X1167829D03*
X1162779Y1370200D03*
X1165279D03*
X1167829D03*
X1162779Y1375200D03*
X1165279D03*
X1167829D03*
Y1377700D03*
Y1380200D03*
Y1382700D03*
X1165279D03*
X1162779D03*
X1165279Y1380200D03*
X1162779D03*
Y1377700D03*
X1165279D03*
X1201110Y1681767D03*
X1279788Y1304042D03*
X1293024Y-36695D03*
Y-26666D03*
Y-16637D03*
Y-6608D03*
Y3421D03*
Y13450D03*
Y23979D03*
X1296719Y1290197D03*
X1299169Y1295467D03*
Y1297967D03*
X1296569D03*
Y1295467D03*
Y1292967D03*
X1299169D03*
X1296581Y1300474D03*
X1299181D03*
X1296576Y1303298D03*
X1299176D03*
X1299317Y-35486D03*
Y-31612D03*
X1299302Y-38001D03*
Y-27972D03*
X1299317Y-25457D03*
Y-21583D03*
X1299302Y-17943D03*
X1299317Y-15428D03*
Y-11554D03*
X1299302Y-7914D03*
X1299317Y-5399D03*
Y4630D03*
X1299302Y2115D03*
X1299317Y-1525D03*
Y14659D03*
X1299302Y12144D03*
X1299317Y8504D03*
Y19033D03*
X1315169Y1274887D03*
X1315289Y1269717D03*
X1315229Y1272287D03*
X1304149Y1291317D03*
X1301889Y1284987D03*
X1301829Y1290167D03*
X1301859Y1287587D03*
X1304299Y1280967D03*
X1304269Y1283567D03*
X1304239Y1286147D03*
X1304209Y1288747D03*
X1315176Y1280218D03*
X1315181Y1277594D03*
X1299319Y1290197D03*
X1299349Y1287617D03*
X1301686Y1303268D03*
X1304196Y1299248D03*
X1304189Y1293917D03*
X1304201Y1296624D03*
X1301679Y1292937D03*
Y1295437D03*
Y1297937D03*
X1301691Y1300444D03*
X1307656Y1326704D03*
X1331519Y1262027D03*
X1331459Y1264597D03*
X1331399Y1267197D03*
X1317889Y1267147D03*
X1320399Y1267117D03*
X1331177Y1269933D03*
Y1272433D03*
Y1274933D03*
X1331166Y1280248D03*
X1317746D03*
X1320256Y1280218D03*
X1331189Y1277440D03*
X1331304Y1401986D03*
Y1404986D03*
X1327926D03*
X1322228Y1419890D03*
X1322186Y1411326D03*
Y1414326D03*
Y1417326D03*
X1325084Y1420066D03*
X1325042Y1408502D03*
Y1411502D03*
Y1417502D03*
Y1414502D03*
X1331344Y1414456D03*
X1330804Y1411536D03*
Y1408536D03*
X1331386Y1420020D03*
X1328008D03*
X1331344Y1417456D03*
X1327966Y1408456D03*
Y1411456D03*
Y1417456D03*
Y1414456D03*
X1322312Y1425018D03*
X1325168Y1425194D03*
X1328092Y1425148D03*
X1331470D03*
X1347419Y1259257D03*
X1347379Y1256687D03*
X1336269Y1274957D03*
X1333969Y1264567D03*
X1334029Y1261997D03*
X1333909Y1267167D03*
X1336339Y1269777D03*
X1336279Y1272347D03*
X1347359Y1261857D03*
X1347371Y1264564D03*
X1336519Y1264627D03*
X1336579Y1262057D03*
X1347366Y1267188D03*
X1336459Y1267227D03*
X1333687Y1269903D03*
Y1272403D03*
Y1274903D03*
X1333676Y1280218D03*
X1336261Y1277654D03*
X1333699Y1277410D03*
X1346304Y1401986D03*
X1343304D03*
X1340304D03*
X1337304D03*
X1334304D03*
Y1404986D03*
X1346304D03*
X1343304D03*
X1340304D03*
X1337304D03*
X1337344Y1414456D03*
X1346344D03*
X1343344D03*
X1340344D03*
X1346534Y1411496D03*
Y1408496D03*
X1334344Y1414456D03*
X1346344Y1417456D03*
X1340344D03*
X1337344D03*
X1334386Y1420020D03*
X1334344Y1417456D03*
X1346386Y1420020D03*
X1343386D03*
X1340386D03*
X1337386D03*
X1343344Y1417456D03*
X1337428Y1422584D03*
X1340428D03*
X1343428D03*
X1334428D03*
X1337328Y1425164D03*
X1340328D03*
X1343328D03*
X1346178Y1425254D03*
X1346278Y1422674D03*
X1334470Y1425148D03*
X1363258Y1256851D03*
Y1259351D03*
X1349876Y1267158D03*
X1352426Y1267218D03*
X1363266Y1267188D03*
X1363258Y1261851D03*
X1363270Y1264358D03*
X1349426Y1401986D03*
Y1404986D03*
X1349508Y1420020D03*
X1349466Y1411456D03*
Y1408456D03*
Y1417456D03*
Y1414456D03*
X1349278Y1422674D03*
X1379579Y1259317D03*
X1368379Y1259287D03*
X1379639Y1256747D03*
X1368439Y1256717D03*
X1365768Y1256821D03*
Y1259321D03*
X1365776Y1267158D03*
X1368326Y1267218D03*
X1379519Y1261917D03*
X1379531Y1264624D03*
X1379526Y1267248D03*
X1368361Y1264594D03*
X1368369Y1261897D03*
X1365768Y1261821D03*
X1365780Y1264328D03*
X1396081Y1153369D03*
X1395436Y1256851D03*
Y1259351D03*
X1384586Y1267278D03*
X1395426Y1267188D03*
X1382036Y1267218D03*
X1395436Y1261851D03*
X1395448Y1264358D03*
X1398831Y1153369D03*
X1411909Y1259257D03*
X1400599Y1256717D03*
X1411969Y1256687D03*
X1397946Y1256821D03*
Y1259321D03*
X1400539Y1259287D03*
X1400521Y1264594D03*
X1400529Y1261897D03*
X1397936Y1267158D03*
X1400486Y1267218D03*
X1411849Y1261857D03*
X1411861Y1264564D03*
X1411856Y1267188D03*
X1397946Y1261821D03*
X1397958Y1264328D03*
X1424119Y1161520D03*
X1426619D03*
X1424119Y1153369D03*
X1426619D03*
Y1169570D03*
X1424119D03*
X1427783Y1256851D03*
Y1259351D03*
X1414366Y1267158D03*
X1416916Y1267218D03*
X1427786Y1267158D03*
X1427783Y1261851D03*
X1427795Y1264358D03*
X1444099Y1259397D03*
X1432899Y1259257D03*
X1444159Y1256827D03*
X1432959Y1256687D03*
X1430293Y1256821D03*
Y1259321D03*
X1444051Y1264704D03*
X1444039Y1261997D03*
X1444046Y1267328D03*
X1432889Y1261867D03*
X1432881Y1264564D03*
X1432846Y1267188D03*
X1430296Y1267128D03*
X1430293Y1261821D03*
X1430305Y1264328D03*
X1433750Y1429208D03*
X1447299Y1153369D03*
X1449799D03*
X1459960Y1259351D03*
Y1256851D03*
X1449106Y1267358D03*
X1459886Y1267218D03*
X1446556Y1267298D03*
X1459960Y1261851D03*
X1459972Y1264358D03*
X1464999Y1259317D03*
X1476369Y1259237D03*
X1465059Y1256747D03*
X1462470Y1259321D03*
Y1256821D03*
X1476291Y1275224D03*
X1464946Y1267248D03*
X1464989Y1261927D03*
X1464981Y1264624D03*
X1476339Y1264467D03*
Y1267037D03*
X1476309Y1261807D03*
X1476279Y1269637D03*
X1476291Y1272344D03*
X1462396Y1267188D03*
X1462470Y1261821D03*
X1462482Y1264328D03*
X1491661Y-27972D03*
X1491676Y-25457D03*
X1485383Y-26666D03*
X1491661Y-38001D03*
X1491676Y-35486D03*
Y-31612D03*
X1485383Y-36695D03*
X1491661Y-17943D03*
X1491676Y-15428D03*
Y-11554D03*
X1485383Y-16637D03*
X1491676Y-21583D03*
X1485383Y3421D03*
X1491661Y2115D03*
X1491676Y4630D03*
X1491661Y-7914D03*
X1491676Y-5399D03*
Y-1525D03*
X1485383Y-6608D03*
X1491676Y14659D03*
X1491661Y12144D03*
X1485383Y13450D03*
X1491676Y8504D03*
Y19033D03*
X1485383Y23979D03*
X1481539Y1259377D03*
X1478999Y1259257D03*
X1481479Y1261947D03*
X1481419Y1264547D03*
X1481431Y1267254D03*
X1478939Y1261827D03*
X1478879Y1264427D03*
X1478891Y1267134D03*
X1481359Y1271447D03*
X1492039D03*
X1481359Y1274144D03*
X1492091D03*
X1478859Y1271417D03*
Y1274114D03*
X1481359Y1277024D03*
X1492091D03*
X1478859Y1276994D03*
X1497199Y1275667D03*
X1497259Y1273097D03*
X1494629Y1271477D03*
X1494631Y1274144D03*
X1506569Y1285947D03*
X1508819Y1284797D03*
X1506539Y1288557D03*
X1508759Y1287367D03*
X1508699Y1289967D03*
X1494631Y1277024D03*
X1506551Y1291254D03*
X1497199Y1278277D03*
X1497161Y1280974D03*
X1506689Y1283377D03*
X1506591Y1294134D03*
X1508711Y1295554D03*
Y1292674D03*
X1501033Y1341462D03*
X1498959Y1342930D03*
X1513789Y1290037D03*
X1511289Y1287397D03*
X1511199Y1290007D03*
X1513791Y1292704D03*
X1516351D03*
X1513791Y1295584D03*
X1516351D03*
X1511251Y1292704D03*
Y1295584D03*
X1588314Y592553D03*
X1585714D03*
X1583114D03*
X1590914D03*
X1588254Y595103D03*
X1588284Y597613D03*
X1585654Y595103D03*
X1585684Y597613D03*
X1583084D03*
X1583054Y595103D03*
X1588284Y608655D03*
X1585684D03*
X1583084D03*
X1590854Y595103D03*
X1590884Y597613D03*
Y608655D03*
X1588254Y613715D03*
X1588224Y611205D03*
X1585654Y613715D03*
X1585624Y611205D03*
X1583024D03*
X1583054Y613715D03*
X1590854D03*
X1590824Y611205D03*
X1593514Y592553D03*
X1593484Y597613D03*
X1593454Y595103D03*
X1593484Y608655D03*
X1593424Y611205D03*
X1593454Y613715D03*
X1619980Y615201D03*
X1635315Y1465745D03*
Y1462745D03*
X1632315Y1468745D03*
X1629815D03*
X1632315Y1465745D03*
X1629815D03*
X1632315Y1462745D03*
X1629815D03*
X1635315Y1468745D03*
Y1460245D03*
X1629815D03*
X1632315D03*
X1629815Y1457745D03*
X1632315D03*
X1635315D03*
X1639645Y1473645D03*
X1649149Y607022D03*
X1653929Y604546D03*
X1649139Y604576D03*
X1653736Y607033D03*
X1649117Y602139D03*
X1653930Y602099D03*
X1643065Y1462645D03*
Y1465645D03*
Y1468645D03*
Y1460145D03*
Y1457645D03*
X1642645Y1473645D03*
X1659458Y671149D03*
X1658085Y673511D03*
X1659458Y705149D03*
X1658085Y707511D03*
X1700852Y639381D03*
X1698232Y639440D03*
X1700852Y647341D03*
Y649941D03*
Y652541D03*
Y644741D03*
X1698232Y644800D03*
Y647400D03*
Y650000D03*
Y652600D03*
X1700852Y641981D03*
X1698232Y642040D03*
X1752078Y216728D03*
Y221728D03*
Y219228D03*
X1757978Y116727D03*
X1760978D03*
X1763678Y106127D03*
X1769278Y108027D03*
Y110927D03*
Y113727D03*
X1755978Y108427D03*
Y111027D03*
X1760478Y106127D03*
X1755078Y216928D03*
Y219428D03*
Y221928D03*
X1784178Y108227D03*
Y111127D03*
Y113927D03*
X1778778Y216928D03*
Y219428D03*
Y221928D03*
X1778165Y1307422D03*
Y1304422D03*
X1784165Y1307422D03*
X1781165D03*
X1778165Y1310422D03*
X1784165D03*
X1781165D03*
X1825762Y167662D03*
X1846691Y166450D03*
G54D27*
X69809Y1333918D03*
Y1331418D03*
Y1336418D03*
X72809Y1333918D03*
Y1331418D03*
Y1336418D03*
X75809Y1333918D03*
Y1331418D03*
Y1336418D03*
X72909Y1339938D03*
X79009Y1340238D03*
X75909Y1339938D03*
X73027Y1347925D03*
X73059Y1345138D03*
X72987Y1342535D03*
X75909Y1342438D03*
X79009Y1342738D03*
Y1345238D03*
X78977Y1348025D03*
X75859Y1348138D03*
Y1345138D03*
X87565Y670441D03*
X94473Y698926D03*
X94209Y1337738D03*
X81809Y1340238D03*
X84809D03*
X87809D03*
X90809D03*
X94209D03*
X84809Y1345238D03*
X81809Y1342738D03*
X84809D03*
X81809Y1348238D03*
Y1345238D03*
X84809Y1348238D03*
X87809D03*
Y1345238D03*
Y1342738D03*
X94209D03*
Y1348238D03*
Y1345238D03*
X90809Y1348238D03*
Y1345238D03*
Y1342738D03*
X96809Y1340238D03*
Y1345238D03*
Y1348238D03*
Y1342738D03*
X127313Y649765D03*
X114021Y669409D03*
X118021D03*
X127738Y659226D03*
X130067Y650213D03*
X134205Y643603D03*
X128193Y662015D03*
X128275Y665515D03*
X176393Y575189D03*
X173793D03*
X176393Y572689D03*
X173793D03*
X171293D03*
Y575189D03*
X173793Y577790D03*
X171293D03*
X176393D03*
X186793Y575189D03*
X184193D03*
X186793Y572689D03*
X184193D03*
X181593Y575189D03*
X178993D03*
X181593Y572689D03*
X178993D03*
X189293Y575189D03*
X186793Y577790D03*
X184193D03*
X189293D03*
X181593D03*
X178993D03*
X190800Y675662D03*
X256695Y461117D03*
X256885Y574805D03*
X254385D03*
X256855Y571995D03*
X251885Y574805D03*
X249800Y563262D03*
X254355Y589235D03*
X256855D03*
X251855D03*
X256855Y605995D03*
X251885Y608805D03*
X257643Y594220D03*
X255043D03*
Y596820D03*
X257643D03*
X256885Y608805D03*
X254385D03*
X256855Y603495D03*
X251855Y623265D03*
X254355D03*
X256855D03*
Y639995D03*
Y637495D03*
X257643Y628220D03*
X255043D03*
Y630820D03*
X257643D03*
X256885Y642805D03*
X254385D03*
X251855Y657265D03*
X251885Y642805D03*
X254355Y657265D03*
X256855D03*
X257643Y662220D03*
X255043D03*
Y664820D03*
X257643D03*
X264055Y574505D03*
X264025Y571995D03*
X261555Y574505D03*
X261525Y571995D03*
X266555Y574505D03*
X266525Y571995D03*
X269055Y574505D03*
X269025Y571995D03*
X261465Y592115D03*
X261525Y589565D03*
X264025D03*
X263965Y592115D03*
X266525Y589565D03*
X266465Y592115D03*
X269025Y589565D03*
X268965Y592115D03*
X264025Y605995D03*
X261525D03*
X264055Y608505D03*
X261555D03*
X261435Y597175D03*
X261495Y594625D03*
X263995D03*
X263935Y597175D03*
X266525Y605995D03*
X266555Y608505D03*
X266435Y597175D03*
X266495Y594625D03*
X261525Y603495D03*
X264025D03*
X266525D03*
X269025Y605995D03*
X269055Y608505D03*
X268935Y597175D03*
X268995Y594625D03*
X269025Y603495D03*
X261495Y621055D03*
X263995D03*
X261525Y623565D03*
X264025D03*
X263995Y611055D03*
X261495D03*
X266495Y621055D03*
X266525Y623565D03*
X266495Y611055D03*
X268995Y621055D03*
X269025Y623565D03*
X268995Y611055D03*
X261525Y639995D03*
X264025D03*
X261525Y637495D03*
X266525Y639995D03*
X269025D03*
X264025Y637495D03*
X266525D03*
X269025D03*
X263965Y626115D03*
X261465D03*
X266465D03*
X268965D03*
X261495Y655055D03*
X263995D03*
X261525Y657565D03*
X264025D03*
X263995Y645055D03*
X264055Y642505D03*
X261495Y645055D03*
X261555Y642505D03*
X266495Y655055D03*
X266525Y657565D03*
X266495Y645055D03*
X266555Y642505D03*
X268995Y655055D03*
X269025Y657565D03*
X268995Y645055D03*
X269055Y642505D03*
X261465Y660115D03*
X263965D03*
X266465D03*
X268965D03*
X317981Y237724D03*
X323420Y207549D03*
X326168Y207580D03*
X334485Y216809D03*
X337000Y216862D03*
X334500Y219362D03*
X337000D03*
X342000Y252612D03*
X349636Y1399601D03*
X346426Y1414401D03*
X346256Y1417301D03*
X367306Y252811D03*
X379112Y290386D03*
X404215Y291140D03*
X429702Y290763D03*
X451520Y475837D03*
X465421Y428078D03*
X502070Y427937D03*
X488169Y475696D03*
X519520Y484027D03*
X646815Y517974D03*
X648296Y528255D03*
X683320Y490662D03*
X702462Y1673258D03*
X725537Y-23978D03*
Y-19022D03*
Y-13978D03*
Y-9022D03*
X714203Y1639776D03*
X730282Y1580391D03*
X741382Y1585251D03*
Y1580121D03*
X735882Y1580391D03*
X730282Y1590651D03*
Y1585521D03*
X735882Y1590651D03*
X732504Y1600321D03*
Y1597321D03*
X744504D03*
Y1600321D03*
X741504Y1597321D03*
Y1600321D03*
X735504Y1597321D03*
Y1600321D03*
X738504Y1597321D03*
Y1600321D03*
X744504Y1609521D03*
Y1612521D03*
X741504Y1609521D03*
X738504D03*
X735504D03*
X741504Y1612521D03*
X738504D03*
X735504D03*
X732504Y1603321D03*
Y1606321D03*
X744504Y1603321D03*
Y1606321D03*
X741504Y1603321D03*
Y1606321D03*
X738504Y1603321D03*
X735504D03*
X738504Y1606321D03*
X735504D03*
X742655Y1682362D03*
Y1678362D03*
X747504Y1600321D03*
Y1609521D03*
Y1612521D03*
X750504D03*
Y1609521D03*
X747504Y1603321D03*
Y1606321D03*
X755859Y1686090D03*
X755183Y1709850D03*
X776052Y1611893D03*
X763359Y1729520D03*
X788079Y1580393D03*
X782479D03*
X793579D03*
X788079Y1590653D03*
X782479D03*
Y1585523D03*
X793579Y1590653D03*
Y1585523D03*
X785052Y1600693D03*
Y1597693D03*
X782052D03*
Y1600693D03*
X794052D03*
X788052D03*
X791052D03*
X794052Y1597693D03*
X788052D03*
X791052D03*
X785052Y1607793D03*
X782052D03*
X779052D03*
X785052Y1611893D03*
X782052D03*
X779052D03*
X794052Y1607793D03*
X791052D03*
X788052D03*
X797052Y1611893D03*
X794052D03*
X788052D03*
X791052D03*
X785052Y1603693D03*
X782052D03*
X794052D03*
X788052D03*
X791052D03*
X797052Y1607793D03*
X824479Y1580393D03*
Y1590653D03*
Y1585523D03*
X824052Y1597693D03*
Y1600693D03*
X827052D03*
Y1597693D03*
X824052Y1611893D03*
Y1607793D03*
Y1603693D03*
X827052Y1611893D03*
Y1607793D03*
Y1603693D03*
X821052Y1611893D03*
Y1607793D03*
X818052Y1611893D03*
X842497Y6022D03*
Y16022D03*
Y20978D03*
Y10978D03*
X830079Y1580393D03*
X835579D03*
X833052Y1597693D03*
X836052D03*
X830079Y1590653D03*
X835579D03*
X833052Y1600693D03*
X836052D03*
X835579Y1585523D03*
X830052Y1600693D03*
Y1597693D03*
X833052Y1603693D03*
X836052D03*
X839052Y1611893D03*
X833052Y1607793D03*
Y1611893D03*
X836052Y1607793D03*
Y1611893D03*
X830052D03*
Y1607793D03*
Y1603693D03*
X839052Y1607793D03*
X866479Y1580393D03*
X872079D03*
X866052Y1597693D03*
X869052D03*
X866479Y1590653D03*
X869052Y1600693D03*
X866052D03*
X872052Y1597693D03*
X872079Y1590653D03*
X872052Y1600693D03*
X866479Y1585523D03*
X875052Y1597693D03*
Y1600693D03*
X869052Y1603693D03*
X866052D03*
X872052D03*
X869052Y1607793D03*
Y1611893D03*
X866052Y1607793D03*
X863052Y1611893D03*
X866052D03*
X872052Y1607793D03*
Y1611893D03*
X875052Y1603693D03*
Y1607793D03*
Y1611893D03*
X863052Y1607793D03*
X860052Y1611893D03*
X877579Y1580393D03*
Y1585523D03*
X878052Y1597693D03*
Y1600693D03*
X877579Y1590653D03*
X878052Y1603693D03*
Y1607793D03*
X881052Y1611893D03*
X878052D03*
X881052Y1607793D03*
X908479Y1580393D03*
Y1590653D03*
Y1585523D03*
X908052Y1600693D03*
Y1597693D03*
Y1611893D03*
X905052D03*
X902052D03*
X908052Y1607793D03*
X905052D03*
X908052Y1603693D03*
X919579Y1580393D03*
X914079D03*
X919579Y1590653D03*
X914079D03*
X919579Y1585523D03*
X917052Y1600693D03*
Y1597693D03*
X914052Y1600693D03*
Y1597693D03*
X911052Y1600693D03*
Y1597693D03*
X920052Y1600693D03*
Y1597693D03*
X917052Y1611893D03*
X914052D03*
X911052D03*
X917052Y1607793D03*
X914052D03*
X911052D03*
X920052Y1611893D03*
X923052D03*
Y1607793D03*
X920052D03*
X917052Y1603693D03*
X914052D03*
X911052D03*
X920052D03*
X968022Y1620730D03*
X965022D03*
X971022D03*
X965022Y1632730D03*
X968022Y1629730D03*
X965022D03*
X968022Y1626730D03*
X965022D03*
Y1623730D03*
X968022D03*
X971022Y1626730D03*
Y1623730D03*
Y1629730D03*
Y1632730D03*
X968022D03*
X985431Y181058D03*
X981795Y216623D03*
X990195Y216823D03*
X996662Y1620870D03*
X999662D03*
X1002662D03*
Y1626870D03*
Y1623870D03*
X996662Y1629870D03*
X999662Y1626870D03*
X996662D03*
Y1623870D03*
X999662D03*
X996662Y1632870D03*
X1034929Y-33989D03*
Y-29033D03*
Y-13989D03*
Y-9033D03*
Y-23989D03*
Y-19033D03*
Y-3989D03*
Y967D03*
X1034252Y1623870D03*
Y1626870D03*
X1031252Y1623870D03*
Y1626870D03*
X1028252Y1623870D03*
Y1626870D03*
X1031252Y1620870D03*
X1034252D03*
X1028252D03*
X1065721Y1633043D03*
X1068721D03*
Y1624043D03*
Y1627043D03*
Y1630043D03*
X1065721Y1624043D03*
Y1627043D03*
Y1630043D03*
X1062721Y1633043D03*
Y1624043D03*
Y1627043D03*
Y1630043D03*
X1059721Y1633043D03*
Y1624043D03*
Y1627043D03*
Y1630043D03*
X1068721Y1621043D03*
X1065721D03*
X1062721D03*
X1059721D03*
X1099901Y1633203D03*
Y1624203D03*
Y1627203D03*
Y1630203D03*
Y1621203D03*
X1093901Y1633203D03*
X1096901D03*
Y1624203D03*
Y1627203D03*
Y1630203D03*
X1093901Y1624203D03*
Y1627203D03*
Y1630203D03*
X1090901Y1633203D03*
X1087901D03*
X1090901Y1624203D03*
X1087901D03*
Y1627203D03*
X1090901D03*
X1087901Y1630203D03*
X1090901D03*
X1096901Y1621203D03*
X1093901D03*
X1087901D03*
X1090901D03*
X1111918Y234718D03*
X1109088Y234668D03*
X1111918Y237718D03*
Y240718D03*
X1109088Y237668D03*
Y240668D03*
X1344248Y-33989D03*
Y-29033D03*
Y-13989D03*
Y-9033D03*
Y-23989D03*
Y-19033D03*
Y-3989D03*
Y967D03*
X1619980Y590685D03*
X1620170Y623762D03*
X1622770D03*
X1620170Y626362D03*
X1622770D03*
X1620170Y657762D03*
X1622770D03*
X1622109Y652469D03*
X1619509D03*
X1620170Y660362D03*
X1622770D03*
X1622109Y686469D03*
X1619509D03*
X1622770Y691762D03*
Y694362D03*
X1620170Y691762D03*
Y694362D03*
X1619509Y720469D03*
X1622109D03*
X1637667Y587844D03*
Y590444D03*
X1629867D03*
Y587844D03*
X1632467Y590444D03*
Y587844D03*
X1635067Y590444D03*
Y587844D03*
X1626606Y616576D03*
X1629206D03*
X1631806D03*
X1634406D03*
X1637006D03*
X1639606D03*
X1630570Y623762D03*
X1627970D03*
X1625370D03*
X1636412Y638451D03*
X1636417Y630007D03*
X1640061Y639497D03*
X1636412Y641051D03*
X1630570Y626362D03*
X1627970D03*
X1625370D03*
X1630198Y638651D03*
Y636051D03*
Y641251D03*
X1633305Y638651D03*
Y641251D03*
X1630198Y632851D03*
X1630214Y629907D03*
X1633321D03*
X1640061Y644457D03*
Y641977D03*
X1630570Y657762D03*
X1627970D03*
X1625370D03*
X1629909Y652469D03*
X1632509D03*
X1624709D03*
X1627309D03*
X1630198Y643851D03*
X1633305Y646451D03*
Y643851D03*
X1630198Y646451D03*
X1636412Y672451D03*
X1636417Y664007D03*
X1640061Y673497D03*
X1630570Y660362D03*
X1627970D03*
X1625370D03*
X1630198Y672651D03*
Y670051D03*
X1633305Y672651D03*
X1630198Y666851D03*
X1630214Y663907D03*
X1633321D03*
X1629909Y686469D03*
X1632509D03*
X1624709D03*
X1627309D03*
X1640061Y678457D03*
Y675977D03*
X1636412Y675051D03*
X1630198Y677851D03*
Y675251D03*
X1633305Y680451D03*
Y675251D03*
Y677851D03*
X1630198Y680451D03*
X1636417Y698007D03*
X1636412Y706451D03*
X1630214Y697907D03*
X1633321D03*
X1630198Y704051D03*
Y706651D03*
X1633305D03*
X1630198Y700851D03*
X1625370Y691762D03*
Y694362D03*
X1630570D03*
Y691762D03*
X1627970D03*
Y694362D03*
X1640061Y707497D03*
Y712457D03*
Y709977D03*
X1636412Y709051D03*
X1632509Y720469D03*
X1627309D03*
X1629909D03*
X1624709D03*
X1633305Y711851D03*
Y709251D03*
X1630198D03*
Y711851D03*
X1633305Y714451D03*
X1630198D03*
X1642873Y604206D03*
Y607206D03*
X1645625Y600495D03*
Y603295D03*
X1642873Y601206D03*
Y598206D03*
X1645625Y597795D03*
Y594995D03*
X1642873Y595006D03*
X1642340Y618546D03*
X1642873Y610206D03*
X1645661Y639497D03*
X1656550Y653086D03*
X1645661Y644457D03*
Y641977D03*
Y673497D03*
X1656550Y687086D03*
X1645661Y678457D03*
Y675977D03*
Y707497D03*
Y709977D03*
Y712457D03*
X1659914Y683681D03*
Y717681D03*
X1737500Y217962D03*
Y214962D03*
Y211962D03*
Y208962D03*
Y226962D03*
Y223962D03*
Y220962D03*
X1740500Y217962D03*
Y214962D03*
Y211962D03*
Y208962D03*
X1747600Y209062D03*
X1744600D03*
X1751800Y206762D03*
X1752078Y226728D03*
Y224228D03*
X1740500Y226962D03*
Y223962D03*
Y220962D03*
X1761500Y214062D03*
X1765000D03*
X1768500D03*
X1755078Y224428D03*
X1763829Y1337548D03*
X1766829D03*
Y1340448D03*
X1769829Y1337548D03*
Y1340448D03*
X1772000Y214062D03*
X1781829Y1324448D03*
X1784829D03*
X1778829D03*
X1781829Y1333148D03*
Y1330248D03*
Y1327348D03*
X1784829Y1333148D03*
Y1330248D03*
Y1327348D03*
X1781829Y1337548D03*
Y1340448D03*
X1784829Y1337548D03*
Y1340448D03*
X1778829Y1333148D03*
Y1330248D03*
Y1327348D03*
Y1337548D03*
X1772829D03*
X1775829D03*
X1778829Y1340448D03*
X1775829D03*
X1772829D03*
X1829514Y1498198D03*
Y1500807D03*
X1832114Y1498198D03*
Y1500807D03*
X1824995Y1502201D03*
G54D22*
X60303Y20354D03*
X312921Y24291D03*
X505185Y41142D03*
X757803Y45079D03*
X922441Y237697D03*
X929331Y160413D03*
X1534712Y20354D03*
X1787330Y24291D03*
G54D41*
X338211Y1118243D03*
Y1131060D03*
X348879Y860993D03*
X349311Y1105426D03*
X351162Y1127856D03*
X353011Y1118243D03*
X354861Y1121447D03*
X347461Y1134264D03*
X354861D03*
X356278Y848176D03*
X371078D03*
X363678D03*
X356278Y860993D03*
X371078D03*
X363678D03*
X371078Y873810D03*
X356278D03*
X363678D03*
Y886627D03*
X371078D03*
X367811Y1105426D03*
X369661Y1102221D03*
X358562D03*
X360412Y1105426D03*
X369662Y1121447D03*
X362261D03*
X369662Y1134264D03*
X362262D03*
X385878Y848176D03*
X378478D03*
Y873810D03*
Y886627D03*
X380762Y1095813D03*
X382611Y1099017D03*
X384462Y1121447D03*
X377062D03*
X384462Y1134264D03*
X377062D03*
X400678Y848176D03*
Y860993D03*
X402529Y947509D03*
X398829Y953917D03*
X402529D03*
X400680Y950713D03*
X401111Y1022114D03*
X402960Y1018910D03*
X402962Y1025318D03*
X399262D03*
Y1044544D03*
X402962D03*
X401111Y1041340D03*
X399262Y1082995D03*
X391862Y1102221D03*
X393711Y1105426D03*
X391862Y1121447D03*
Y1134264D03*
X399262D03*
X408078Y848176D03*
X415478D03*
Y860993D03*
X408078D03*
X415478Y873810D03*
X404785Y971100D03*
X407085D03*
X409385D03*
X411685D03*
X420205D03*
X412385Y1000080D03*
X410085D03*
X420215Y1000040D03*
X404811Y1041340D03*
X415911Y1079791D03*
X404811Y1092608D03*
X417762Y1095813D03*
X415912Y1124651D03*
X419612D03*
Y1118243D03*
X417761Y1121447D03*
Y1127856D03*
X406662Y1134264D03*
X415912Y1137469D03*
Y1131060D03*
X414061Y1140973D03*
X419612Y1137469D03*
Y1131060D03*
X417761Y1134264D03*
Y1140973D03*
X422878Y848176D03*
X430278Y860993D03*
X422878D03*
Y873810D03*
X427875Y941930D03*
Y944230D03*
X430280Y944305D03*
X432129Y947510D03*
X427875Y956373D03*
Y954073D03*
X430280Y957123D03*
X432129Y960327D03*
Y953918D03*
X430280Y950714D03*
X435830Y960327D03*
Y953918D03*
X432129Y966736D03*
X430280Y963531D03*
X435830Y966736D03*
X430268Y976348D03*
X432129Y973144D03*
X430280Y969940D03*
X427875Y971267D03*
X422685Y971100D03*
X427875Y968967D03*
X435830Y973144D03*
X430280Y982757D03*
X432129Y979553D03*
X427875Y983111D03*
X435830Y979553D03*
X427875Y985411D03*
Y997521D03*
X430712Y1009298D03*
X427875Y1012152D03*
X430712Y1002889D03*
X427875Y999821D03*
X422685Y1000060D03*
X436263Y1006094D03*
Y999685D03*
X432562Y1006094D03*
Y999685D03*
X427875Y1014452D03*
X436263Y1012502D03*
X432562D03*
X430712Y1022115D03*
Y1015706D03*
X427875Y1026704D03*
X430712Y1028524D03*
X436263Y1018911D03*
X432562D03*
Y1025319D03*
X436263D03*
X427875Y1029004D03*
Y1031304D03*
X436263Y1031728D03*
X432562D03*
X423285Y1036884D03*
X430711Y1041340D03*
X430712Y1034932D03*
X427875Y1033604D03*
X423285Y1032284D03*
Y1034584D03*
X436262Y1038137D03*
X436261Y1044544D03*
X432562Y1038137D03*
X434412Y1041340D03*
X432561Y1044544D03*
X434412Y1047749D03*
X436262Y1057361D03*
Y1050952D03*
Y1063770D03*
X423311Y1079791D03*
X436262Y1070178D03*
Y1076587D03*
Y1082995D03*
Y1089404D03*
X436261Y1095813D03*
X421462Y1102221D03*
X423311Y1099017D03*
X428861Y1108630D03*
X427012Y1105426D03*
X425162Y1108630D03*
X430711Y1105426D03*
Y1099017D03*
X428861Y1102221D03*
X436262Y1108630D03*
Y1102221D03*
X432561Y1108630D03*
Y1102221D03*
X434412Y1099017D03*
X430711Y1111834D03*
X427012D03*
X430711Y1124651D03*
X428861Y1121447D03*
X427012Y1124651D03*
X425162Y1121447D03*
X421461D03*
X430711Y1118243D03*
X428861Y1115039D03*
X427012Y1118243D03*
X425162Y1115039D03*
X436262Y1121447D03*
Y1115039D03*
X432561Y1121447D03*
Y1115039D03*
X428861Y1127856D03*
X425162D03*
X421461D03*
X436262D03*
X432561D03*
X430711Y1137769D03*
X427012Y1137569D03*
X430711Y1131060D03*
X428861Y1134264D03*
X427012Y1131060D03*
X425162Y1134264D03*
X421461D03*
X428861Y1140973D03*
X425161D03*
X421461D03*
X436261Y1134264D03*
X432561D03*
X445078Y860993D03*
X452479D03*
X450630Y941101D03*
X448780Y944305D03*
X443229Y947510D03*
X450630D03*
X445079Y957123D03*
X437680D03*
X441380D03*
X439529Y960327D03*
X443229D03*
Y953918D03*
X439529D03*
X437680Y950714D03*
X441380D03*
X445079D03*
X448780Y957123D03*
X450630Y953918D03*
Y960327D03*
X448780Y950714D03*
X445079Y963531D03*
X437680D03*
X441380D03*
X439529Y966736D03*
X443229D03*
X448780Y963531D03*
X450630Y966736D03*
X445079Y976348D03*
Y969940D03*
X439529Y973144D03*
X443229D03*
X437680Y976348D03*
X441380D03*
X437680Y969940D03*
X441380D03*
X450630Y973144D03*
X448780Y976348D03*
Y969940D03*
X445079Y982757D03*
X437680D03*
X441380D03*
X439529Y979553D03*
X443229D03*
X448780Y982757D03*
X450630Y979553D03*
X439962Y1006094D03*
X443662D03*
X445511Y1009298D03*
X438113D03*
X441813D03*
X445512Y1002889D03*
X438113D03*
X441813D03*
X439962Y999685D03*
X443662D03*
X451062Y1006094D03*
X449213Y1009298D03*
Y1002889D03*
X451062Y999685D03*
X439962Y1012502D03*
X443662D03*
X451062D03*
X445511Y1022115D03*
X438113D03*
X441813D03*
X445512Y1015706D03*
X438113D03*
X439962Y1018911D03*
X441813Y1015706D03*
X443662Y1018911D03*
Y1025319D03*
X439962D03*
X445511Y1028524D03*
X441813D03*
X438113D03*
X449213Y1022115D03*
X451062Y1018911D03*
X449213Y1015706D03*
X451062Y1025319D03*
X449213Y1028524D03*
X439962Y1031728D03*
X443662D03*
X451062D03*
X439962Y1038137D03*
X443662D03*
X438112Y1041340D03*
X439961Y1044544D03*
X441812Y1041340D03*
X443661Y1044544D03*
X447361D03*
X445511Y1041340D03*
X445512Y1034932D03*
X438113D03*
X441813D03*
X451062Y1038137D03*
X449211Y1041340D03*
X449213Y1034932D03*
X445510Y1047749D03*
X441812D03*
X438112D03*
Y1060565D03*
Y1054157D03*
X439961Y1057361D03*
X441812Y1054157D03*
Y1060565D03*
X443661Y1057361D03*
X445511Y1060565D03*
Y1054157D03*
X439961Y1050952D03*
X443661D03*
X439961Y1063770D03*
X443661D03*
X439961Y1076587D03*
Y1070178D03*
X441812Y1073383D03*
X438112D03*
X443661Y1070178D03*
Y1076587D03*
X445511Y1073383D03*
X441812Y1066974D03*
X438112D03*
X445511D03*
X441812Y1079791D03*
X438112D03*
X445511D03*
X443661Y1082995D03*
X439961D03*
X441812Y1086200D03*
X445511D03*
X439961Y1089404D03*
X441812Y1092608D03*
X438112D03*
X443661Y1089404D03*
X445511Y1092608D03*
X447361Y1089404D03*
X438112Y1086200D03*
X449211Y1092608D03*
X439961Y1095813D03*
X443661D03*
X447361D03*
X441812Y1105426D03*
X438112D03*
X439961Y1108630D03*
X443661D03*
X445511Y1105426D03*
X439961Y1102221D03*
X441812Y1099017D03*
X438112D03*
X443661Y1102221D03*
X445511Y1099017D03*
X452912Y1105426D03*
X451061Y1108630D03*
X449212Y1105426D03*
X451061Y1102221D03*
X449212Y1099017D03*
X441812Y1111834D03*
X438112D03*
X445511D03*
X452912D03*
X449212D03*
X438112Y1124651D03*
X439961Y1121447D03*
X441812Y1124651D03*
X445511D03*
X443661Y1121447D03*
X438112Y1118243D03*
X441812D03*
X439961Y1115039D03*
X445511Y1118243D03*
X443661Y1115039D03*
X452912Y1124651D03*
Y1118243D03*
X451061Y1121447D03*
X449212Y1124651D03*
Y1118243D03*
X451061Y1115039D03*
X439961Y1127856D03*
X443661D03*
X451061D03*
X441812Y1137769D03*
X438112D03*
X445511D03*
X443661Y1134264D03*
X441812Y1131060D03*
X439961Y1134264D03*
X438112Y1131060D03*
X445511D03*
X452912Y1137769D03*
Y1131060D03*
X449212Y1137769D03*
Y1131060D03*
X451061Y1134264D03*
X459878Y848176D03*
X467278D03*
X459878Y860993D03*
X467278D03*
Y873810D03*
X459878D03*
Y886627D03*
X467278D03*
X459878Y899445D03*
X467712Y1054157D03*
Y1060565D03*
X465862Y1082995D03*
X462162D03*
X467711Y1099017D03*
X462162Y1102221D03*
X458461Y1108630D03*
X456612Y1105426D03*
X454761Y1108630D03*
Y1102221D03*
X460312Y1111834D03*
X456611D03*
X464012Y1124651D03*
X462161Y1121447D03*
X460312Y1124651D03*
X456611D03*
X454761Y1121447D03*
X464011Y1118243D03*
X462161Y1115039D03*
X460312Y1118243D03*
X456611D03*
X454761Y1115039D03*
X462161Y1127856D03*
X454761D03*
X465861D03*
X464012Y1137469D03*
X460312D03*
X456612D03*
X464012Y1131060D03*
X462161Y1134264D03*
X460312Y1131060D03*
X456611D03*
X454761Y1134264D03*
X462161Y1140973D03*
X458461D03*
X454761D03*
X467712Y1137469D03*
X465861Y1134264D03*
X467712Y1131060D03*
X465861Y1140973D03*
X474678Y848176D03*
X482078D03*
X474678Y860993D03*
X482078D03*
X474678Y873810D03*
X482078D03*
X474678Y886627D03*
X482078D03*
Y905853D03*
X480229Y947509D03*
X478378Y950713D03*
X480229Y953917D03*
X478378Y957122D03*
X476285Y973826D03*
Y971526D03*
X480661Y1018910D03*
X478811Y1022114D03*
Y1028523D03*
Y1015705D03*
X476325Y1031795D03*
Y1027195D03*
Y1029495D03*
X470724Y1028827D03*
X476962Y1044544D03*
X478811Y1047749D03*
X473261Y1057361D03*
X471412Y1060565D03*
X475112Y1054157D03*
X469562Y1063770D03*
X469561Y1057361D03*
X473262Y1063770D03*
X469561Y1050952D03*
X473262D03*
X482511Y1054157D03*
X480662Y1063770D03*
X480661Y1057361D03*
X478812Y1060565D03*
X476962Y1063770D03*
Y1057361D03*
X478812Y1054157D03*
X476961Y1050952D03*
X473262Y1095813D03*
X469562Y1082995D03*
X480662Y1089404D03*
Y1102221D03*
X473262Y1121447D03*
X480662D03*
Y1134264D03*
X469561D03*
X489478Y848176D03*
X496878D03*
X489478Y860993D03*
X496878D03*
Y873810D03*
X489478D03*
Y886627D03*
X496878D03*
X488062Y1095813D03*
Y1115039D03*
Y1121447D03*
X495462Y1134264D03*
X488062D03*
X511678Y848176D03*
X504278D03*
X511678Y860993D03*
X504278D03*
X511678Y873810D03*
X504278D03*
X511678Y886627D03*
X504278D03*
X510262Y1102221D03*
X502862Y1115039D03*
X510262Y1121447D03*
X502862D03*
X517662D03*
X510262Y1134264D03*
X502862D03*
X517662D03*
X519078Y848176D03*
X526479Y860993D03*
X519078D03*
X526479Y873810D03*
X519078D03*
X526479Y886627D03*
X519078D03*
X533879D03*
X528762Y1102221D03*
X525062D03*
X523212Y1099017D03*
X530611Y1105426D03*
X526911Y1118243D03*
X525062Y1121447D03*
X534311Y1118243D03*
X525062Y1134264D03*
X528761Y1140973D03*
X532461D03*
X541711Y1118243D03*
X748399Y1051247D03*
X1309832Y209249D03*
X1314353Y1131060D03*
X1325853Y174099D03*
X1331102Y179724D03*
Y182874D03*
Y186024D03*
X1324802Y179724D03*
Y186024D03*
Y182874D03*
Y195474D03*
X1327952D03*
X1318502D03*
X1321652D03*
X1327952Y201774D03*
X1321652D03*
X1331102Y189174D03*
X1329062Y212949D03*
X1325852Y211099D03*
X1325021Y860993D03*
X1325453Y1105426D03*
X1327304Y1127856D03*
X1329153Y1118243D03*
X1331003Y1121447D03*
Y1134264D03*
X1323603D03*
X1332268Y170399D03*
X1332262Y211099D03*
X1347220Y848176D03*
X1339820D03*
X1332420D03*
X1339820Y860993D03*
X1347220D03*
X1332420D03*
X1339820Y873810D03*
X1332420D03*
X1347220D03*
Y886627D03*
X1339820D03*
X1334704Y1102221D03*
X1345803D03*
X1343953Y1105426D03*
X1336554D03*
X1345804Y1121447D03*
X1338403D03*
X1338404Y1134264D03*
X1345804D03*
X1362020Y848176D03*
X1354620D03*
Y873810D03*
Y886627D03*
X1356904Y1095813D03*
X1358753Y1099017D03*
X1360604Y1121447D03*
X1353204D03*
Y1134264D03*
X1360604D03*
X1376820Y848176D03*
X1369420D03*
X1376820Y860993D03*
X1378671Y947509D03*
Y953917D03*
X1374971D03*
X1376822Y950713D03*
X1375404Y1025318D03*
X1377253Y1022114D03*
X1379102Y1018910D03*
X1379104Y1025318D03*
X1375404Y1044544D03*
X1377253Y1041340D03*
X1379104Y1044544D03*
X1375404Y1082995D03*
X1368004Y1102221D03*
X1369853Y1105426D03*
X1368004Y1121447D03*
Y1134264D03*
X1375404D03*
X1374847Y1153069D03*
X1391620Y848176D03*
X1384220D03*
Y860993D03*
X1391620D03*
Y873810D03*
X1392534Y942097D03*
X1394834D03*
X1380926Y971099D03*
X1383226D03*
X1387826D03*
X1385526D03*
X1396346D03*
X1386226Y1000079D03*
X1396356Y1000039D03*
X1388526Y1000079D03*
X1380953Y1041340D03*
X1392053Y1079791D03*
X1380953Y1092608D03*
X1393904Y1095813D03*
X1392054Y1124651D03*
X1393903Y1121447D03*
Y1127856D03*
X1395754Y1118243D03*
Y1124651D03*
X1382804Y1134264D03*
X1390203Y1140973D03*
X1392054Y1131060D03*
Y1137469D03*
X1393903Y1134264D03*
Y1140973D03*
X1395754Y1131060D03*
Y1137469D03*
X1399020Y848176D03*
X1406420Y860993D03*
X1399020D03*
Y873810D03*
X1406421Y944304D03*
X1408271Y941100D03*
X1411971D03*
X1404016Y944229D03*
Y941929D03*
X1408270Y947509D03*
X1411971D03*
X1406421Y950713D03*
Y957122D03*
X1408270Y953917D03*
Y960326D03*
X1411971Y953917D03*
Y960326D03*
X1404016Y954072D03*
Y956372D03*
X1406421Y963530D03*
X1408270Y966735D03*
X1411971D03*
X1406421Y969939D03*
X1406409Y976347D03*
X1408270Y973143D03*
X1411971D03*
X1404016Y971266D03*
Y968966D03*
X1398826Y971099D03*
X1406421Y982756D03*
X1408270Y979552D03*
X1411971D03*
X1404016Y983110D03*
Y985410D03*
Y997520D03*
X1412404Y999684D03*
Y1006093D03*
Y1012501D03*
X1406853Y1002888D03*
Y1009297D03*
X1408703Y999684D03*
Y1006093D03*
Y1012501D03*
X1404016Y1012151D03*
Y999820D03*
X1398826Y1000059D03*
X1404016Y1014451D03*
X1406853Y1028523D03*
X1412404Y1018910D03*
X1406853Y1015705D03*
Y1022114D03*
X1408703Y1018910D03*
X1412404Y1025318D03*
X1408703D03*
X1404016Y1026703D03*
X1412404Y1031727D03*
X1408703D03*
X1404016Y1029003D03*
Y1031303D03*
X1412403Y1038136D03*
Y1044544D03*
X1406853Y1034931D03*
Y1041340D03*
X1408703Y1038136D03*
Y1044544D03*
X1410554Y1041340D03*
X1404016Y1033603D03*
X1399426Y1036883D03*
Y1034583D03*
Y1032283D03*
X1410554Y1047749D03*
X1412404Y1050952D03*
Y1057361D03*
Y1063770D03*
Y1070178D03*
Y1076587D03*
Y1082995D03*
Y1089404D03*
X1412403Y1095813D03*
X1397604Y1102221D03*
X1399453Y1099017D03*
X1412404Y1102221D03*
Y1108630D03*
X1401304D03*
X1403154Y1105426D03*
Y1111834D03*
X1405003Y1102221D03*
Y1108630D03*
X1406853Y1099017D03*
Y1105426D03*
Y1111834D03*
X1408703Y1102221D03*
Y1108630D03*
X1410554Y1099017D03*
X1412404Y1115039D03*
Y1121447D03*
Y1127856D03*
X1397603Y1121447D03*
Y1127856D03*
X1401304Y1115039D03*
Y1121447D03*
Y1127856D03*
X1403154Y1118243D03*
Y1124651D03*
X1405003Y1115039D03*
Y1121447D03*
Y1127856D03*
X1406853Y1118243D03*
Y1124651D03*
X1408703Y1115039D03*
Y1121447D03*
Y1127856D03*
X1412403Y1134264D03*
X1397603D03*
Y1140973D03*
X1401304Y1134264D03*
X1401303Y1140973D03*
X1403154Y1131060D03*
Y1137569D03*
X1405003Y1134264D03*
Y1140973D03*
X1406853Y1131060D03*
Y1137769D03*
X1408703Y1134264D03*
X1421220Y860993D03*
X1428621D03*
X1413821Y944304D03*
X1415671Y941100D03*
X1417521Y944304D03*
X1419371Y941100D03*
X1421220Y944304D03*
X1424921D03*
X1426771Y941100D03*
X1415670Y947509D03*
X1419370D03*
X1426771D03*
X1413821Y950713D03*
Y957122D03*
X1415670Y953917D03*
Y960326D03*
X1417521Y950713D03*
Y957122D03*
X1419370Y953917D03*
Y960326D03*
X1421220Y950713D03*
Y957122D03*
X1424921Y950713D03*
Y957122D03*
X1426771Y953917D03*
Y960326D03*
X1413821Y963530D03*
X1415670Y966735D03*
X1417521Y963530D03*
X1419370Y966735D03*
X1421220Y963530D03*
X1424921D03*
X1426771Y966735D03*
X1413821Y969939D03*
Y976347D03*
X1415670Y973143D03*
X1417521Y969939D03*
Y976347D03*
X1419370Y973143D03*
X1421220Y969939D03*
Y976347D03*
X1424921Y969939D03*
Y976347D03*
X1426771Y973143D03*
X1413821Y982756D03*
X1415670Y979552D03*
X1417521Y982756D03*
X1419370Y979552D03*
X1421220Y982756D03*
X1424921D03*
X1426771Y979552D03*
X1414254Y1002888D03*
Y1009297D03*
X1416103Y999684D03*
Y1006093D03*
Y1012501D03*
X1417954Y1002888D03*
Y1009297D03*
X1419803Y999684D03*
Y1006093D03*
Y1012501D03*
X1421653Y1002888D03*
Y1009297D03*
X1425354Y1002888D03*
Y1009297D03*
X1427203Y999684D03*
Y1006093D03*
Y1012501D03*
X1421653Y1028523D03*
X1414254D03*
X1417954D03*
X1425354D03*
X1414254Y1015705D03*
Y1022114D03*
X1416103Y1018910D03*
X1417954Y1015705D03*
Y1022114D03*
X1419803Y1018910D03*
X1421653Y1015705D03*
Y1022114D03*
X1425354Y1015705D03*
Y1022114D03*
X1427203Y1018910D03*
X1416103Y1025318D03*
X1419803D03*
X1427203D03*
X1416103Y1031727D03*
X1419803D03*
X1427203D03*
X1414254Y1034931D03*
Y1041340D03*
X1416103Y1038136D03*
Y1044544D03*
X1417954Y1034931D03*
Y1041340D03*
X1419803Y1038136D03*
Y1044544D03*
X1421653Y1034931D03*
Y1041340D03*
X1423503Y1044544D03*
X1425354Y1034931D03*
X1425353Y1041340D03*
X1427203Y1038136D03*
X1421653Y1047749D03*
X1414254D03*
X1417954D03*
X1414254Y1054157D03*
X1416103Y1050952D03*
X1417954Y1054157D03*
X1419803Y1050952D03*
X1421653Y1054157D03*
X1414254Y1060565D03*
X1416103Y1057361D03*
X1417954Y1060565D03*
X1419803Y1057361D03*
X1421653Y1060565D03*
X1416103Y1063770D03*
X1419803D03*
X1414254Y1066974D03*
Y1073383D03*
X1416103Y1070178D03*
Y1076587D03*
X1417954Y1066974D03*
Y1073383D03*
X1419803Y1070178D03*
Y1076587D03*
X1421653Y1066974D03*
Y1073383D03*
X1414254Y1079791D03*
X1417954D03*
X1421653D03*
X1416103Y1082995D03*
X1419803D03*
X1414254Y1086200D03*
Y1092608D03*
X1416103Y1089404D03*
Y1095813D03*
X1417954Y1086200D03*
Y1092608D03*
X1419803Y1089404D03*
Y1095813D03*
X1421653Y1086200D03*
Y1092608D03*
X1423503Y1089404D03*
Y1095813D03*
X1425353Y1092608D03*
X1414254Y1099017D03*
Y1105426D03*
Y1111834D03*
X1416103Y1102221D03*
Y1108630D03*
X1417954Y1099017D03*
Y1105426D03*
Y1111834D03*
X1419803Y1102221D03*
Y1108630D03*
X1421653Y1099017D03*
Y1105426D03*
Y1111834D03*
X1425354Y1099017D03*
Y1105426D03*
Y1111834D03*
X1427203Y1102221D03*
Y1108630D03*
X1429054Y1105426D03*
Y1111834D03*
X1414254Y1118243D03*
Y1124651D03*
X1416103Y1115039D03*
Y1121447D03*
Y1127856D03*
X1417954Y1118243D03*
Y1124651D03*
X1419803Y1115039D03*
Y1121447D03*
Y1127856D03*
X1421653Y1118243D03*
Y1124651D03*
X1425354Y1118243D03*
Y1124651D03*
X1427203Y1115039D03*
Y1121447D03*
Y1127856D03*
X1429054Y1118243D03*
Y1124651D03*
X1414254Y1131060D03*
Y1137769D03*
X1416103Y1134264D03*
X1417954Y1131060D03*
Y1137769D03*
X1419803Y1134264D03*
X1421653Y1131060D03*
Y1137769D03*
X1425354Y1131060D03*
Y1137769D03*
X1427203Y1134264D03*
X1429054Y1131060D03*
Y1137769D03*
X1443420Y848176D03*
X1436020D03*
X1443420Y860993D03*
X1436020D03*
Y873810D03*
X1443420D03*
X1436020Y899445D03*
Y886627D03*
X1443420D03*
X1443854Y1054157D03*
Y1060565D03*
X1438304Y1082995D03*
X1442004D03*
X1438304Y1102221D03*
X1443853Y1099017D03*
X1430903Y1102221D03*
Y1108630D03*
X1432754Y1105426D03*
X1432753Y1111834D03*
X1434603Y1108630D03*
X1436454Y1111834D03*
X1430903Y1115039D03*
Y1121447D03*
Y1127856D03*
X1432753Y1118243D03*
Y1124651D03*
X1436454Y1118243D03*
Y1124651D03*
X1438303Y1115039D03*
Y1121447D03*
Y1127856D03*
X1440153Y1118243D03*
X1440154Y1124651D03*
X1442003Y1127856D03*
X1443854Y1131060D03*
Y1137469D03*
X1430903Y1134264D03*
Y1140973D03*
X1432753Y1131060D03*
X1432754Y1137469D03*
X1434603Y1140973D03*
X1436454Y1131060D03*
Y1137469D03*
X1438303Y1134264D03*
Y1140973D03*
X1440154Y1131060D03*
Y1137469D03*
X1442003Y1134264D03*
Y1140973D03*
X1450820Y848176D03*
X1458220D03*
X1450820Y860993D03*
X1458220D03*
Y873810D03*
X1450820D03*
X1458220Y886627D03*
X1450820D03*
X1458220Y905853D03*
X1456371Y947509D03*
Y953917D03*
X1454520Y957122D03*
Y950713D03*
X1452426Y973825D03*
Y971525D03*
X1454953Y1028523D03*
Y1022114D03*
X1456803Y1018910D03*
X1454953Y1015705D03*
X1446934Y1028889D03*
X1452466Y1031794D03*
Y1029494D03*
Y1027194D03*
X1454953Y1047749D03*
X1453104Y1044544D03*
X1456804Y1063770D03*
X1458653Y1054157D03*
X1454954D03*
X1453104Y1057361D03*
Y1063770D03*
X1454954Y1060565D03*
X1456803Y1057361D03*
X1453103Y1050952D03*
X1445703Y1057361D03*
X1445704Y1063770D03*
X1447554Y1060565D03*
X1449403Y1057361D03*
X1449404Y1063770D03*
X1451254Y1054157D03*
X1445703Y1050952D03*
X1449404D03*
X1445704Y1082995D03*
X1456804Y1089404D03*
X1449404Y1095813D03*
X1456804Y1102221D03*
Y1121447D03*
X1449404D03*
X1456804Y1134264D03*
X1445703D03*
X1465620Y848176D03*
X1473020D03*
X1465620Y860993D03*
X1473020D03*
Y873810D03*
X1465620D03*
X1473020Y886627D03*
X1465620D03*
X1464204Y1095813D03*
Y1115039D03*
Y1121447D03*
X1471604Y1134264D03*
X1464204D03*
X1487820Y848176D03*
X1480420D03*
X1487820Y860993D03*
X1480420D03*
X1487820Y873810D03*
X1480420D03*
Y886627D03*
X1487820D03*
X1486404Y1102221D03*
X1479004Y1115039D03*
Y1121447D03*
X1493804D03*
X1486404D03*
X1479004Y1134264D03*
X1493804D03*
X1486404D03*
X1495220Y848176D03*
Y860993D03*
X1502621D03*
X1495220Y873810D03*
X1502621D03*
X1495220Y886627D03*
X1502621D03*
X1510021D03*
X1506753Y1105426D03*
X1504904Y1102221D03*
X1501204D03*
X1499354Y1099017D03*
X1503053Y1118243D03*
X1510453D03*
X1501204Y1121447D03*
Y1134264D03*
X1508603Y1140973D03*
X1504903D03*
X1517853Y1118243D03*
X1724541Y1051247D03*
G54D49*
X717313Y-27626D03*
Y-21471D03*
Y-17597D03*
X717298Y-15082D03*
X717313Y-11442D03*
X717298Y-25111D03*
X717313Y-7568D03*
X717298Y-5053D03*
X834273Y2374D03*
X834258Y4889D03*
X834273Y22432D03*
Y8529D03*
Y12403D03*
X834258Y14918D03*
X834273Y18558D03*
X834258Y24947D03*
X1026705Y-27695D03*
Y-38224D03*
X1023437Y-38210D03*
X1026690Y-35709D03*
X1023422Y-35695D03*
X1026705Y-32069D03*
Y-17666D03*
X1026690Y-15151D03*
X1026705Y-11511D03*
X1026690Y-25180D03*
X1026705Y-21540D03*
X1026690Y4907D03*
X1026705Y2392D03*
X1026690Y-5122D03*
X1026705Y-7637D03*
Y-1482D03*
Y22450D03*
Y18576D03*
Y8547D03*
X1026690Y14936D03*
X1026705Y12421D03*
X1026690Y24965D03*
X1336024Y-27695D03*
Y-32069D03*
X1332741Y-35695D03*
X1336009Y-35709D03*
X1332756Y-38210D03*
X1336024Y-38224D03*
Y-11511D03*
X1336009Y-15151D03*
X1336024Y-17666D03*
Y-21540D03*
X1336009Y-25180D03*
X1336024Y2392D03*
X1336009Y4907D03*
X1336024Y-1482D03*
Y-7637D03*
X1336009Y-5122D03*
X1336024Y18576D03*
Y22450D03*
Y12421D03*
X1336009Y14936D03*
X1336024Y8547D03*
X1336009Y24965D03*
G54D66*
X1879155Y468898D03*
Y716798D03*
X1889155Y468898D03*
Y716798D03*
X1900275Y840758D03*
X1910275D03*
X1921395Y-19332D03*
X1931395D03*
X1942395Y593048D03*
X1952395D03*
X1963362Y-19190D03*
X1973362D03*
X1984482Y593020D03*
X1994482D03*
X2005452Y-19180D03*
X2015452D03*
X2026452Y593200D03*
X2047419Y-19038D03*
X2036452Y593200D03*
X2057419Y-19038D03*
X2068539Y593172D03*
X2078539D03*
G54D58*
X918780Y1684890D03*
Y1694890D03*
Y1714890D03*
X928780Y1684890D03*
X938780D03*
X928780Y1694890D03*
X938780D03*
X928780Y1704890D03*
X938780D03*
X928780Y1714890D03*
X938780D03*
G54D65*
X1879155Y354948D03*
Y458898D03*
Y478898D03*
Y582848D03*
Y602848D03*
Y706798D03*
Y726798D03*
Y830748D03*
X1900275Y-9342D03*
X1889155Y354948D03*
Y458898D03*
Y478898D03*
X1900275Y582858D03*
X1889155Y582848D03*
Y602848D03*
Y706798D03*
X1900275Y726808D03*
X1889155Y726798D03*
X1900275Y830758D03*
X1889155Y830748D03*
X1900275Y850758D03*
Y954708D03*
X1910275Y-9342D03*
Y582858D03*
Y726808D03*
Y830758D03*
Y850758D03*
Y954708D03*
X1921395Y-9332D03*
X1931395D03*
Y582868D03*
X1921395D03*
X1931395Y602868D03*
X1921395D03*
Y1195068D03*
X1931395D03*
X1942395Y-9152D03*
Y583048D03*
Y603048D03*
Y1195248D03*
X1963362Y-9190D03*
X1952395Y-9152D03*
X1963362Y583010D03*
X1952395Y583048D03*
X1963362Y603010D03*
X1952395Y603048D03*
X1963362Y1195210D03*
X1952395Y1195248D03*
X1973362Y-9190D03*
Y583010D03*
Y603010D03*
Y1195210D03*
X1994482Y-9180D03*
X1984482D03*
Y583020D03*
X1994482D03*
X1984482Y603020D03*
X1994482D03*
Y1195220D03*
X1984482D03*
X2005452Y-9180D03*
X2015452D03*
Y583020D03*
X2005452D03*
X2015452Y603020D03*
X2005452D03*
Y1195220D03*
X2015452D03*
X2026452Y-9000D03*
Y583200D03*
Y603200D03*
Y1195400D03*
X2047419Y-9038D03*
X2036452Y-9000D03*
X2047419Y583162D03*
X2036452Y583200D03*
X2047419Y603162D03*
X2036452Y603200D03*
X2047419Y1195362D03*
X2036452Y1195400D03*
X2057419Y-9038D03*
Y583162D03*
Y603162D03*
Y1195362D03*
X2068539Y603172D03*
X2078539D03*
Y1195372D03*
X2068539D03*
G54D67*
X1879155Y468898D03*
Y716798D03*
X1889155Y468898D03*
X1900275Y592858D03*
X1889155Y716798D03*
X1900275Y840758D03*
X1910275Y592858D03*
Y840758D03*
X1921395Y1205068D03*
X1931395D03*
X1942395Y593048D03*
X1952395D03*
X1963362Y1205210D03*
X1984482Y593020D03*
X1973362Y1205210D03*
X1994482Y593020D03*
X2005452Y1205220D03*
X2015452D03*
X2026452Y593200D03*
X2036452D03*
X2047419Y1205362D03*
X2057419D03*
G54D46*
X676508Y224606D03*
G54D19*
X36399Y960892D03*
Y957546D03*
Y967585D03*
X52541Y964239D03*
X66099Y816995D03*
Y810302D03*
Y833727D03*
Y823688D03*
Y827034D03*
Y840420D03*
Y960892D03*
Y957546D03*
Y967585D03*
Y1221916D03*
Y1215223D03*
Y1238648D03*
Y1228609D03*
Y1231955D03*
Y1245341D03*
X82241Y813648D03*
Y806955D03*
Y820341D03*
Y830381D03*
Y823688D03*
Y837074D03*
Y964239D03*
Y1218570D03*
Y1211877D03*
Y1225263D03*
Y1241995D03*
Y1235302D03*
Y1228609D03*
X95799Y960892D03*
Y957546D03*
Y967585D03*
Y1054593D03*
X125499Y780184D03*
Y773491D03*
Y786877D03*
Y803609D03*
Y796916D03*
Y790223D03*
Y816995D03*
Y810302D03*
Y833727D03*
Y823688D03*
Y827034D03*
Y847113D03*
Y840420D03*
Y853806D03*
Y860499D03*
Y863845D03*
Y883924D03*
Y877231D03*
Y870538D03*
Y890617D03*
Y897310D03*
Y900656D03*
Y914042D03*
Y907349D03*
Y927428D03*
Y920735D03*
Y934121D03*
Y944160D03*
Y937467D03*
Y960892D03*
Y950853D03*
X111941Y964239D03*
X125499Y957546D03*
Y980971D03*
Y974278D03*
Y967585D03*
Y994357D03*
Y987664D03*
X111941Y1021129D03*
Y1024475D03*
X125499Y1027822D03*
Y1021129D03*
Y1047900D03*
Y1041207D03*
Y1034515D03*
X111941Y1051247D03*
X125499Y1054593D03*
Y1074672D03*
Y1067979D03*
Y1091404D03*
Y1081365D03*
Y1084711D03*
Y1098097D03*
Y1111483D03*
Y1104790D03*
Y1128215D03*
Y1118176D03*
Y1121522D03*
Y1141601D03*
Y1134908D03*
Y1148294D03*
Y1154987D03*
Y1158333D03*
Y1171719D03*
Y1165026D03*
Y1185105D03*
Y1178412D03*
Y1191798D03*
Y1208530D03*
Y1201837D03*
Y1195144D03*
Y1221916D03*
Y1215223D03*
Y1238648D03*
Y1228609D03*
Y1231955D03*
Y1245341D03*
X141641Y770144D03*
Y776837D03*
Y786877D03*
Y783530D03*
Y800263D03*
Y793570D03*
Y813648D03*
Y806955D03*
Y820341D03*
Y830381D03*
Y823688D03*
Y850459D03*
Y843766D03*
Y837074D03*
Y867192D03*
Y860499D03*
Y857152D03*
Y873885D03*
Y880577D03*
Y887270D03*
Y897310D03*
Y893963D03*
Y917389D03*
Y910696D03*
Y904003D03*
Y924081D03*
Y934121D03*
Y930774D03*
Y947507D03*
Y940814D03*
Y964239D03*
Y977625D03*
Y970932D03*
Y991011D03*
Y984318D03*
Y1021129D03*
Y1024475D03*
Y1031168D03*
Y1044554D03*
Y1037861D03*
Y1051247D03*
Y1071326D03*
Y1064633D03*
Y1078018D03*
Y1094751D03*
Y1088058D03*
Y1081365D03*
Y1108137D03*
Y1101444D03*
Y1124869D03*
Y1118176D03*
Y1114829D03*
Y1144948D03*
Y1138255D03*
Y1131562D03*
Y1161680D03*
Y1154987D03*
Y1151641D03*
Y1175066D03*
Y1168373D03*
Y1181759D03*
Y1191798D03*
Y1188452D03*
Y1205184D03*
Y1198491D03*
Y1218570D03*
Y1211877D03*
Y1225263D03*
Y1241995D03*
Y1235302D03*
Y1228609D03*
X155199Y960892D03*
Y957546D03*
Y967585D03*
Y1054593D03*
X171341Y964239D03*
Y1021129D03*
Y1024475D03*
Y1051247D03*
X184899Y780184D03*
Y773491D03*
Y786877D03*
Y803609D03*
Y796916D03*
Y790223D03*
Y816995D03*
Y810302D03*
Y833727D03*
Y823688D03*
Y827034D03*
Y847113D03*
Y840420D03*
Y853806D03*
Y860499D03*
Y863845D03*
Y883924D03*
Y877231D03*
Y870538D03*
Y890617D03*
Y897310D03*
Y900656D03*
Y914042D03*
Y907349D03*
Y927428D03*
Y920735D03*
Y934121D03*
Y944160D03*
Y937467D03*
Y960892D03*
Y950853D03*
Y957546D03*
Y980971D03*
Y974278D03*
Y967585D03*
Y994357D03*
Y987664D03*
Y1027822D03*
Y1021129D03*
Y1047900D03*
Y1041207D03*
Y1034515D03*
Y1054593D03*
Y1074672D03*
Y1067979D03*
Y1091404D03*
Y1081365D03*
Y1084711D03*
Y1098097D03*
Y1111483D03*
Y1104790D03*
Y1128215D03*
Y1118176D03*
Y1121522D03*
Y1141601D03*
Y1134908D03*
Y1148294D03*
Y1154987D03*
Y1158333D03*
Y1171719D03*
Y1165026D03*
Y1185105D03*
Y1178412D03*
Y1191798D03*
Y1208530D03*
Y1201837D03*
Y1195144D03*
Y1221916D03*
Y1215223D03*
Y1238648D03*
Y1228609D03*
Y1231955D03*
Y1245341D03*
X201041Y770144D03*
Y776837D03*
Y786877D03*
Y783530D03*
Y800263D03*
Y793570D03*
Y813648D03*
Y806955D03*
Y820341D03*
Y830381D03*
Y823688D03*
Y850459D03*
Y843766D03*
Y837074D03*
Y867192D03*
Y860499D03*
Y857152D03*
Y873885D03*
Y880577D03*
Y887270D03*
Y897310D03*
Y893963D03*
Y917389D03*
Y910696D03*
Y904003D03*
Y924081D03*
Y934121D03*
Y930774D03*
Y947507D03*
Y940814D03*
Y964239D03*
Y977625D03*
Y970932D03*
Y991011D03*
Y984318D03*
X201141Y1021129D03*
Y1024475D03*
Y1031168D03*
Y1044554D03*
Y1037861D03*
Y1051247D03*
Y1071326D03*
Y1064633D03*
Y1078018D03*
Y1094752D03*
Y1088059D03*
Y1081366D03*
Y1108137D03*
Y1101444D03*
X201041Y1124869D03*
X201141Y1118177D03*
Y1114830D03*
Y1144948D03*
Y1138255D03*
X201041Y1131562D03*
X201141Y1161680D03*
Y1154988D03*
Y1151641D03*
Y1175066D03*
Y1168373D03*
Y1181759D03*
Y1191799D03*
Y1188452D03*
Y1205184D03*
Y1198491D03*
Y1218570D03*
Y1211877D03*
Y1225263D03*
Y1241995D03*
Y1235302D03*
Y1228609D03*
X214599Y960892D03*
Y957546D03*
X244299Y883924D03*
Y890617D03*
Y897310D03*
Y900656D03*
Y914042D03*
Y907349D03*
Y960892D03*
Y957546D03*
Y1185105D03*
Y1178412D03*
Y1191798D03*
Y1208530D03*
Y1201837D03*
Y1195144D03*
X260441Y880577D03*
Y887270D03*
Y897310D03*
Y893963D03*
Y910696D03*
Y904003D03*
Y1175066D03*
Y1181759D03*
Y1191798D03*
Y1188452D03*
Y1205184D03*
Y1198491D03*
X337779Y880219D03*
X335928Y883423D03*
X337779Y893036D03*
X335928Y889832D03*
X334079Y886627D03*
X337779D03*
X350727Y851380D03*
X354427Y844971D03*
X348878Y848176D03*
X352578D03*
X350729Y857789D03*
X352578Y860993D03*
X354429Y857789D03*
X341479Y880219D03*
X343329Y883423D03*
X348878Y899445D03*
Y893036D03*
X350729Y889832D03*
X354429D03*
X341478Y893036D03*
X343328Y889832D03*
X347029Y896240D03*
X354429D03*
X341479Y886627D03*
X350729Y896240D03*
X345179Y886627D03*
X348878Y912262D03*
X350729Y909057D03*
X354429D03*
X350729Y902649D03*
X354429D03*
X347029Y915466D03*
X354429D03*
X350729D03*
X348879Y931488D03*
X350729Y928283D03*
X354429D03*
Y921875D03*
X350729D03*
X348878Y918670D03*
X350729Y941100D03*
X348878Y937896D03*
X354429Y941100D03*
X347029Y934691D03*
X354429D03*
X350729D03*
Y947509D03*
X354429D03*
X348878Y950713D03*
X350729Y960326D03*
X348878Y957122D03*
X354429Y960326D03*
X350729Y966735D03*
X354429D03*
X350729Y953917D03*
X354429D03*
X347030D03*
X350729Y979552D03*
X354429D03*
X348878Y976347D03*
X347029Y973143D03*
X348878Y969939D03*
X347461Y1006093D03*
X349311Y1002888D03*
X351161Y999684D03*
X354861D03*
X351161Y1012501D03*
X349311Y1009297D03*
X354861Y1012501D03*
X351162Y1031727D03*
X349311Y1028523D03*
X354861Y1031727D03*
X349311Y1022114D03*
X351161Y1018910D03*
X354861D03*
X347461Y1025318D03*
X354862D03*
X351162D03*
X349311Y1047749D03*
Y1041340D03*
X351161Y1038136D03*
X354861D03*
X347461Y1044544D03*
X354861D03*
X351161D03*
X349311Y1060565D03*
X351161Y1057361D03*
X354861D03*
X347461Y1063770D03*
X351161D03*
X354861D03*
X351161Y1050952D03*
X354861D03*
Y1070178D03*
X351162D03*
X349311Y1066974D03*
Y1079791D03*
X351161Y1076587D03*
X354861D03*
X351161Y1089404D03*
X349311Y1086200D03*
X354861Y1089404D03*
X347461Y1082995D03*
X354861D03*
X351161D03*
X341911Y1105426D03*
X343762Y1108630D03*
X345611Y1111834D03*
X351161Y1102221D03*
X349312Y1111834D03*
X353011Y1105426D03*
X345611D03*
X341912Y1111834D03*
X354861Y1102221D03*
X353012Y1111834D03*
X351162Y1108630D03*
X353011Y1124651D03*
X354861Y1127856D03*
X347461Y1115039D03*
X349312Y1137469D03*
X351161Y1134264D03*
X356279Y841467D03*
X361827Y844971D03*
X363679Y841467D03*
X369227Y844971D03*
X371079Y841467D03*
X358127Y844971D03*
X359978Y848176D03*
X365527Y844971D03*
X367378Y848176D03*
X356278Y854584D03*
X358129Y857789D03*
X363678Y854584D03*
X365529Y857789D03*
X371078Y854584D03*
X359978Y860993D03*
X361829Y857789D03*
X367378Y860993D03*
X369229Y857789D03*
X356278Y899445D03*
Y893036D03*
X358129Y896240D03*
X363678Y899445D03*
X367378D03*
X371078Y893036D03*
X356278Y912262D03*
X358129Y915466D03*
X363678Y912262D03*
X361829Y909057D03*
X367378Y912262D03*
X369229Y909057D03*
X361829Y902649D03*
X369229D03*
X359978Y905853D03*
X367378D03*
X363678D03*
X371078D03*
X356278Y931488D03*
X363678D03*
X356278Y918670D03*
X361829Y928283D03*
X367378Y931488D03*
X369229Y928283D03*
X361829Y921875D03*
X363678Y918670D03*
X369229Y921875D03*
X367378Y918670D03*
X359978Y925079D03*
X367378D03*
X363678D03*
X371078D03*
X356278Y937896D03*
X358129Y934691D03*
X361829Y941100D03*
X363678Y937896D03*
X369229Y941100D03*
X367378Y937896D03*
X361829Y947509D03*
X369229D03*
X367378Y944304D03*
X359978D03*
X371078D03*
X363678D03*
X356278Y950713D03*
Y957122D03*
X358129Y953917D03*
X361829Y966735D03*
X369229D03*
X359978Y963530D03*
X363678Y950713D03*
X367378D03*
X361829Y960326D03*
X363678Y957122D03*
X369229Y960326D03*
X367378Y957122D03*
X371078Y963530D03*
X359978Y982756D03*
X367378D03*
X363678D03*
X371078D03*
X369229Y979552D03*
X367378Y976347D03*
X361829Y979552D03*
X363678Y976347D03*
X356278D03*
Y969939D03*
X358129Y973143D03*
X363678Y969939D03*
X367378D03*
X358562Y1006093D03*
X356711Y1002888D03*
Y1009297D03*
X362262Y1012501D03*
X369662D03*
X364111Y1009297D03*
X367811D03*
X364111Y1002888D03*
X362262Y999684D03*
X371511Y1002888D03*
X369662Y999684D03*
X356711Y1028523D03*
Y1022114D03*
X362262Y1031727D03*
X364111Y1028523D03*
X369662Y1031727D03*
X367811Y1028523D03*
X358562Y1025318D03*
X360411Y1015705D03*
X371511D03*
X364111Y1022114D03*
X362262Y1018910D03*
X367811Y1022114D03*
X369662Y1018910D03*
X356711Y1047749D03*
Y1041340D03*
X364111D03*
X362262Y1038136D03*
X367811Y1041340D03*
X369662Y1038136D03*
X360411Y1034931D03*
X371511D03*
X364111D03*
X358562Y1044544D03*
X367811Y1034931D03*
X364111Y1047749D03*
X367811D03*
X356711Y1060565D03*
X358562Y1063770D03*
X364111Y1060565D03*
X362262Y1057361D03*
X367811Y1060565D03*
X369662Y1057361D03*
X362262Y1050952D03*
X369662D03*
X360411Y1054157D03*
X371511D03*
X364111D03*
X367811D03*
X356711Y1066974D03*
X367811Y1079791D03*
X369662Y1076587D03*
X362262Y1070178D03*
X364111Y1066974D03*
X369662Y1070178D03*
X367811Y1066974D03*
X356711Y1079791D03*
X364111D03*
X362262Y1076587D03*
X360411Y1073383D03*
X371511D03*
X364111D03*
X367811D03*
X356711Y1086200D03*
X358562Y1082995D03*
X362262Y1095813D03*
X369662D03*
X362262Y1089404D03*
X364111Y1086200D03*
X369662Y1089404D03*
X367811Y1086200D03*
X360411Y1092608D03*
X367811D03*
X364111D03*
X371511D03*
X364111Y1099017D03*
X367811D03*
X358561Y1121447D03*
X360412Y1124651D03*
X364111D03*
X367811D03*
X371511D03*
X356712D03*
X362262Y1127856D03*
X365962Y1121447D03*
X369662Y1127856D03*
X358561Y1134264D03*
X362261Y1140973D03*
X365962Y1134264D03*
X369661Y1140973D03*
X356712Y1137469D03*
X360412D03*
X364112D03*
X367812D03*
X371512D03*
X387727Y844971D03*
X376627D03*
X380327D03*
X384027D03*
X385879Y841467D03*
X372927Y844971D03*
X374778Y848176D03*
X378479Y841467D03*
X382178Y848176D03*
X387729Y857789D03*
X372929D03*
X378478Y854584D03*
X380329Y857789D03*
X384029D03*
X374778Y860993D03*
X376629Y857789D03*
X382178Y860993D03*
X385878Y854584D03*
X374778Y899445D03*
X382178D03*
Y893036D03*
X374778D03*
X385878D03*
X372929Y896240D03*
X380329D03*
X376629D03*
X384029D03*
X376629Y902649D03*
X380329D03*
X374778Y912262D03*
X376629Y909057D03*
X382178Y912262D03*
X380329Y909057D03*
X372929Y915466D03*
X380329D03*
X376629D03*
X384029D03*
X374778Y931488D03*
X376629Y928283D03*
X382178Y931488D03*
X380329Y928283D03*
X376629Y921875D03*
X374778Y918670D03*
X380329Y921875D03*
X382178Y918670D03*
X380329Y941100D03*
X382178Y937896D03*
X376629Y947509D03*
X380329D03*
X376629Y941100D03*
X374778Y937896D03*
X372929Y934691D03*
X380329D03*
X376629D03*
X384029D03*
X376629Y960326D03*
X374778Y957122D03*
X380329Y960326D03*
X382178Y957122D03*
X374778Y950713D03*
X382178D03*
X372929Y953917D03*
X380329D03*
X376629D03*
X384029D03*
X380329Y966735D03*
X376629D03*
X374778Y969939D03*
X382178D03*
X373362Y1006093D03*
X380762D03*
X377062D03*
X384462D03*
X375211Y1002888D03*
X377062Y999684D03*
X382611Y1002888D03*
X380762Y999684D03*
X377062Y1012501D03*
X375211Y1009297D03*
X380762Y1012501D03*
X382611Y1009297D03*
X377062Y1031727D03*
X375211Y1028523D03*
X380762Y1031727D03*
X382611Y1028523D03*
X375211Y1022114D03*
X377062Y1018910D03*
X382611Y1022114D03*
X380762Y1018910D03*
X377062Y1025318D03*
X384462D03*
X373360D03*
X380760D03*
X375211Y1047749D03*
X382611D03*
X375211Y1041340D03*
X377062Y1038136D03*
X382611Y1041340D03*
X380762Y1038136D03*
X373362Y1044544D03*
X380762D03*
X377062D03*
X384462D03*
X375211Y1060565D03*
X377062Y1057361D03*
X382611Y1060565D03*
X380762Y1057361D03*
X377062Y1050952D03*
X380762D03*
X373362Y1063770D03*
X384462D03*
X377062D03*
X380762D03*
Y1070178D03*
X382611Y1066974D03*
X377062Y1070178D03*
X375211Y1066974D03*
Y1079791D03*
X377062Y1076587D03*
X382611Y1079791D03*
X380762Y1076587D03*
X377062Y1089404D03*
X375211Y1086200D03*
X380762Y1089404D03*
X382611Y1086200D03*
X373362Y1082995D03*
X384462D03*
X377062D03*
X380762D03*
X386311Y1105426D03*
X382611Y1111834D03*
X375211Y1105426D03*
X377062Y1108630D03*
X380762Y1102221D03*
X378911Y1111834D03*
X384462Y1108630D03*
X386311Y1111834D03*
X378912Y1105426D03*
X375211Y1111834D03*
X382611Y1105426D03*
X375211Y1124651D03*
X378911D03*
X382611D03*
X386311D03*
X373362Y1121447D03*
X377062Y1127856D03*
X380762Y1121447D03*
X384462Y1127856D03*
X380762Y1115039D03*
X373362Y1134264D03*
X377061Y1140973D03*
X380762Y1134264D03*
X384461Y1140973D03*
X375212Y1137469D03*
X378912D03*
X382612D03*
X386312D03*
X391427Y844971D03*
X395127D03*
X398827D03*
X400679Y841467D03*
X389578Y848176D03*
X393279Y841467D03*
X396978Y848176D03*
X402527Y844971D03*
X393278Y854584D03*
X395129Y857789D03*
X400678Y854584D03*
X402529Y857789D03*
X389578Y860993D03*
X391429Y857789D03*
X396978Y860993D03*
X398829Y857789D03*
Y973143D03*
X400678Y976347D03*
X402529Y979552D03*
Y973143D03*
X390011Y1002888D03*
X388162Y999684D03*
X393711Y1002888D03*
X395562Y999684D03*
X402962Y1082995D03*
X402961Y1089404D03*
X390011Y1124651D03*
X395562Y1121447D03*
X397411Y1124651D03*
X401111D03*
X391862Y1127856D03*
X393711Y1124651D03*
X399262Y1127856D03*
X402962Y1121447D03*
X388162D03*
X391861Y1140973D03*
X395562Y1134264D03*
X399261Y1140973D03*
X402962Y1134264D03*
X388162D03*
X390012Y1137469D03*
X393712D03*
X397412D03*
X401112D03*
X406227Y844971D03*
X409927D03*
X413627D03*
X417327D03*
X404378Y848176D03*
X408079Y841467D03*
X411778Y848176D03*
X415479Y841467D03*
X419178Y848176D03*
X408078Y854584D03*
X409929Y857789D03*
X415478Y854584D03*
X417329Y857789D03*
X404378Y860993D03*
X406229Y857789D03*
X411778Y860993D03*
X413629Y857789D03*
X419178Y860993D03*
X417329Y883423D03*
X415478Y880219D03*
X413629Y883423D03*
X419178Y886627D03*
X408511Y1079791D03*
X406662Y1089404D03*
X410362D03*
X404811Y1086200D03*
X419611D03*
X414062Y1082995D03*
X410362D03*
X406662D03*
X408511Y1092608D03*
X414062Y1089404D03*
X419611Y1092608D03*
X412211Y1086200D03*
X404811Y1124651D03*
X408511D03*
X406662Y1127856D03*
X410362Y1121447D03*
X406661Y1140973D03*
X410362Y1134264D03*
X404812Y1137469D03*
X408512D03*
X421027Y844971D03*
X424727D03*
X428427D03*
X433978Y848176D03*
X435829Y844671D03*
X422879Y841467D03*
X426578Y848176D03*
X430278D03*
X422878Y854584D03*
X424729Y857789D03*
X430278Y854584D03*
X433979Y860993D03*
X421029Y857789D03*
X426578Y860993D03*
X428429Y857789D03*
X432129D03*
X435829D03*
X432129Y883423D03*
X430278Y880219D03*
X424729Y883423D03*
X422878Y880219D03*
X428429Y883423D03*
X421029D03*
X435829D03*
X433978Y886627D03*
X426578D03*
X421462Y1089404D03*
X423311Y1092608D03*
X427011D03*
X430710Y1086200D03*
X425162Y1082995D03*
Y1095813D03*
X430711Y1092608D03*
X423311Y1086200D03*
X428861Y1089404D03*
X427012Y1086200D03*
X450628Y844971D03*
X446927Y844671D03*
X452479Y841467D03*
X448778Y848176D03*
X443227Y844671D03*
X437678Y848176D03*
X437679Y854584D03*
X452478D03*
X450629Y857789D03*
X445078Y854584D03*
X443229Y857789D03*
X448779Y860993D03*
X446929Y857789D03*
X441378Y860993D03*
X452479Y880219D03*
X446929Y883423D03*
X445078Y880219D03*
X439529Y883423D03*
X437678Y880219D03*
X450629Y883423D03*
X443229D03*
X448778Y886627D03*
X441378D03*
X467279Y841467D03*
X463578Y848176D03*
X459879Y841467D03*
X458027Y844971D03*
X454327D03*
X469127D03*
X465427D03*
X461727D03*
X456178Y848176D03*
X467278Y854584D03*
X465429Y857789D03*
X459878Y854584D03*
X458029Y857789D03*
X469129D03*
X463578Y860993D03*
X461729Y857789D03*
X456178Y860993D03*
X454329Y857789D03*
X469129Y883423D03*
X467278Y880219D03*
X461729Y883423D03*
X459878Y880219D03*
X454329Y883423D03*
X465429D03*
X458029D03*
X463578Y886627D03*
X456178D03*
X483927Y844971D03*
X480227D03*
X476527D03*
X470978Y848176D03*
X482079Y841467D03*
X478378Y848176D03*
X474679Y841467D03*
X472827Y844971D03*
X482078Y854584D03*
X480229Y857789D03*
X474678Y854584D03*
X472829Y857789D03*
X483929D03*
X478378Y860993D03*
X476529Y857789D03*
X470978Y860993D03*
Y886627D03*
X484362Y1121447D03*
X480662Y1127856D03*
X476962Y1121447D03*
X473262Y1127856D03*
X469562Y1121447D03*
X482511Y1124651D03*
X478811D03*
X475111D03*
X471411D03*
X484362Y1134264D03*
X482512Y1137469D03*
X476962Y1134264D03*
X475112Y1137469D03*
X480661Y1140973D03*
X478812Y1137469D03*
X473261Y1140973D03*
X493178Y848176D03*
X489478Y841467D03*
X487627Y844971D03*
X500578Y848176D03*
X496878Y841467D03*
X495027Y844971D03*
X491327D03*
X485778Y848176D03*
X498727Y844971D03*
X489478Y854584D03*
X487629Y857789D03*
X500578Y860993D03*
X498729Y857789D03*
X495029D03*
X491329D03*
X485778Y860993D03*
X496878Y854584D03*
X493178Y860993D03*
X500578Y899445D03*
Y912262D03*
X498729Y909057D03*
Y902649D03*
X500578Y905853D03*
X496878D03*
X500578Y931488D03*
X498729Y921875D03*
X500578Y918670D03*
X498729Y928283D03*
X496878Y925079D03*
X500578D03*
X498729Y947509D03*
Y941100D03*
X500578Y937896D03*
X496878Y944304D03*
X500578D03*
Y950713D03*
Y957122D03*
X498729Y960326D03*
X487629Y979552D03*
X485778Y976347D03*
X491329Y979552D03*
X493178Y976347D03*
X500578Y982756D03*
X496878D03*
X498729Y979552D03*
X500578Y976347D03*
X501011Y1002888D03*
X499162Y999684D03*
Y1012501D03*
X501011Y1009297D03*
X497311Y1015705D03*
X499162Y1031727D03*
X501011Y1028523D03*
Y1022114D03*
X499162Y1018910D03*
X501011Y1041340D03*
X499162Y1038136D03*
X501011Y1047749D03*
Y1034931D03*
X497311D03*
X501011Y1060565D03*
X499162Y1057361D03*
Y1050952D03*
X501011Y1054157D03*
X497311D03*
X499162Y1070178D03*
X501011Y1066974D03*
Y1079791D03*
X499162Y1076587D03*
X497311Y1073383D03*
X501011D03*
X499162Y1089404D03*
X501011Y1086200D03*
X497311Y1092608D03*
X501011D03*
X488062Y1127856D03*
X499162Y1121447D03*
X495462Y1127856D03*
X491762Y1121447D03*
X489911Y1124651D03*
X486211D03*
X501011D03*
X497311D03*
X493611D03*
X493612Y1137469D03*
X488061Y1140973D03*
X501012Y1137469D03*
X495461Y1140973D03*
X491762Y1134264D03*
X489912Y1137469D03*
X486212D03*
X499162Y1134264D03*
X497312Y1137469D03*
X517227Y844971D03*
X511679Y841467D03*
X509827Y844971D03*
X504279Y841467D03*
X515378Y848176D03*
X513527Y844971D03*
X507978Y848176D03*
X506127Y844971D03*
X502427D03*
X517229Y857789D03*
X513529D03*
X509829D03*
X506129D03*
X515378Y860993D03*
X511678Y854584D03*
X507978Y860993D03*
X504278Y854584D03*
X502429Y857789D03*
X511678Y899445D03*
Y893036D03*
X507978D03*
X509829Y896240D03*
X517229D03*
X513529D03*
X504278Y899445D03*
X513529Y902649D03*
X517229D03*
X511678Y912262D03*
X513529Y909057D03*
X517229D03*
X513529Y915466D03*
X509829D03*
X517229D03*
X504278Y912262D03*
X506129Y909057D03*
Y902649D03*
X507978Y905853D03*
X504278D03*
X511678Y931488D03*
X513529Y928283D03*
X517229D03*
X506129D03*
Y921875D03*
X504278Y918670D03*
X513529Y921875D03*
X511678Y918670D03*
X517229Y921875D03*
X504278Y931488D03*
Y925079D03*
X507978D03*
X513529Y941100D03*
X511678Y937896D03*
X517229Y941100D03*
X513529Y934691D03*
X509829D03*
X517229D03*
X513529Y947509D03*
X517229D03*
X506129D03*
Y941100D03*
X504278Y937896D03*
X507978Y944304D03*
X504278D03*
X511678Y950713D03*
X513529Y960326D03*
X511678Y957122D03*
X517229Y960326D03*
Y966735D03*
X513529D03*
X504278Y950713D03*
X513529Y953917D03*
X517229D03*
X509829D03*
X504278Y957122D03*
X506129Y960326D03*
X507978Y982756D03*
X504278D03*
Y976347D03*
X506129Y979552D03*
X513529D03*
X517229D03*
X511678Y976347D03*
X509829Y973143D03*
X511678Y969939D03*
X517662Y1006093D03*
X513962D03*
X510262D03*
X517662Y1012501D03*
X504711Y1002888D03*
X506561Y999684D03*
X513962Y1012501D03*
X512111Y1009297D03*
X506562Y1012501D03*
X504711Y1009297D03*
X517661Y999684D03*
X512111Y1002888D03*
X513962Y999684D03*
Y1031727D03*
X512111Y1028523D03*
X517662Y1031727D03*
X512111Y1022114D03*
X513962Y1018910D03*
X517662D03*
X513962Y1025318D03*
X510262D03*
X517662D03*
X508411Y1015705D03*
X506562Y1031727D03*
X504711Y1028523D03*
Y1022114D03*
X506562Y1018910D03*
X504711Y1041340D03*
X506562Y1038136D03*
X512111Y1047749D03*
Y1041340D03*
X513962Y1038136D03*
X517662D03*
X504711Y1047749D03*
X510262Y1044544D03*
X508411Y1034931D03*
X513962Y1044544D03*
X517662D03*
X504711Y1034931D03*
X512111Y1060565D03*
X513962Y1057361D03*
X517662D03*
X510262Y1063770D03*
X513962D03*
X517662D03*
X513962Y1050952D03*
X517662D03*
X504711Y1060565D03*
X506562Y1057361D03*
Y1050952D03*
X508411Y1054157D03*
X504711D03*
X517662Y1070178D03*
X513962D03*
X512111Y1066974D03*
X504711Y1079791D03*
X506562Y1076587D03*
Y1070178D03*
X504711Y1066974D03*
X512111Y1079791D03*
X513962Y1076587D03*
X517662D03*
X508411Y1073383D03*
X504711D03*
X513962Y1089404D03*
X512111Y1086200D03*
X517662Y1089404D03*
X513962Y1082995D03*
X510262D03*
X517662D03*
X510262Y1095813D03*
X506561D03*
X506562Y1089404D03*
X504711Y1086200D03*
X508411Y1092608D03*
X504711D03*
X517662Y1102221D03*
X515811Y1099017D03*
X517662Y1127856D03*
X513962Y1121447D03*
X510262Y1127856D03*
X506562Y1121447D03*
X502862Y1127856D03*
X515811Y1124651D03*
X512111D03*
X508411D03*
X504711D03*
X517661Y1140973D03*
X513962Y1134264D03*
X512112Y1137469D03*
X506562Y1134264D03*
X504712Y1137469D03*
X515812D03*
X510261Y1140973D03*
X508412Y1137469D03*
X502861Y1140973D03*
X532028Y844671D03*
X526478Y848176D03*
X524627Y844971D03*
X519079Y841467D03*
X533878Y848176D03*
X530178D03*
X522778D03*
X520927Y844971D03*
X532029Y864197D03*
X533879Y854584D03*
X528329Y857789D03*
X522778Y860993D03*
X520929Y857789D03*
X526478Y854584D03*
X524629Y857789D03*
X519078Y854584D03*
X526479Y899445D03*
X530178D03*
X519078D03*
Y893036D03*
X522778D03*
X520929Y896240D03*
X530179Y912262D03*
X532029Y909057D03*
X524629Y902649D03*
X532029D03*
X526479Y912262D03*
X524629Y909057D03*
X526479Y905853D03*
X533879D03*
X522778D03*
X530179D03*
X519078Y912262D03*
X520929Y915466D03*
X526479Y931488D03*
X524629Y928283D03*
X530179Y931488D03*
X532029Y928283D03*
X524629Y921875D03*
X526479Y918670D03*
X532029Y921875D03*
X530179Y918670D03*
X526479Y925079D03*
X533879D03*
X522778D03*
X530179D03*
X519078Y931488D03*
Y918670D03*
X524629Y941100D03*
X526479Y937896D03*
X532029Y941100D03*
X530179Y937896D03*
X524629Y947509D03*
X532029D03*
X519078Y937896D03*
X533879Y944304D03*
X520929Y934691D03*
X526479Y944304D03*
X530178D03*
X522778D03*
X524629Y966735D03*
X532029D03*
X522778Y963530D03*
X526479Y950713D03*
X530178D03*
X532029Y960326D03*
X530178Y957122D03*
X524629Y960326D03*
X526479Y957122D03*
X533879Y963530D03*
X519078Y950713D03*
Y957122D03*
X520929Y953917D03*
X526479Y969939D03*
X530179D03*
X519078Y976347D03*
Y969939D03*
X520929Y973143D03*
X521362Y1006093D03*
X525062Y1012501D03*
X532461D03*
X526911Y1009297D03*
X530611D03*
X519511D03*
X519513Y1002888D03*
X530611D03*
X532461Y999684D03*
X526911Y1002888D03*
X525062Y999684D03*
X523211Y1015705D03*
X534311D03*
X525062Y1031727D03*
X526911Y1028523D03*
X532461Y1031727D03*
X530611Y1028523D03*
Y1022114D03*
X532461Y1018910D03*
X526911Y1022114D03*
X525062Y1018910D03*
X519511Y1028523D03*
Y1022114D03*
X521362Y1025318D03*
X526911Y1041340D03*
X525062Y1038136D03*
X530611Y1041340D03*
X532461Y1038136D03*
X526911Y1047749D03*
X530611D03*
X526911Y1034931D03*
X534311D03*
X523211D03*
X530611D03*
X519511Y1047749D03*
Y1041340D03*
X521362Y1044544D03*
X519511Y1060565D03*
X526911D03*
X525062Y1057361D03*
X530611Y1060565D03*
X532462Y1057361D03*
X525061Y1050952D03*
X532462Y1050953D03*
X523211Y1054157D03*
X521362Y1063770D03*
X534311Y1054157D03*
X526911D03*
X530611D03*
Y1079791D03*
X532462Y1076587D03*
X525062Y1070178D03*
X526911Y1066974D03*
X532462Y1070178D03*
X530611Y1066974D03*
X526911Y1079791D03*
X525062Y1076587D03*
X523211Y1073383D03*
X534311D03*
X526911D03*
X530611D03*
X519511Y1066974D03*
Y1079791D03*
X521362Y1095813D03*
X532461D03*
X525062D03*
Y1089404D03*
X526911Y1086200D03*
X532462Y1089404D03*
X530611Y1086200D03*
X526911Y1092608D03*
X534310D03*
X523211D03*
X530611D03*
X519511Y1086200D03*
X521362Y1082995D03*
X530611Y1099017D03*
X526911Y1124651D03*
X521362Y1121447D03*
X525062Y1127856D03*
X523211Y1124651D03*
X519511D03*
X532462Y1134264D03*
X525061Y1140973D03*
X523212Y1137469D03*
X534312D03*
X526912D03*
X521362Y1134264D03*
X519512Y1137469D03*
X543129Y851380D03*
X539429D03*
X535729Y864197D03*
X543128D03*
X546828D03*
X535729Y857789D03*
X543130D03*
X539429D03*
X541279Y860993D03*
Y854584D03*
X539429Y883423D03*
X537578Y880219D03*
X543129Y883423D03*
X544979Y880219D03*
X537578Y873810D03*
X539429Y870606D03*
X544979Y873810D03*
X543129Y870606D03*
X539428Y877014D03*
X546828D03*
X535729D03*
X543129D03*
X620799Y883924D03*
Y890617D03*
Y897310D03*
Y900656D03*
Y914042D03*
Y907349D03*
Y960892D03*
Y957546D03*
Y1185105D03*
Y1178412D03*
Y1191798D03*
Y1208530D03*
Y1201837D03*
Y1195144D03*
X636941Y880577D03*
Y887270D03*
Y897310D03*
Y893963D03*
Y910696D03*
Y904003D03*
Y1175066D03*
Y1181759D03*
Y1191798D03*
Y1188451D03*
Y1205184D03*
Y1198491D03*
X650499Y960892D03*
Y957546D03*
X680299Y780184D03*
Y773491D03*
Y786877D03*
Y803609D03*
Y796916D03*
Y790223D03*
Y816995D03*
Y810302D03*
Y833727D03*
Y823688D03*
Y827034D03*
Y847113D03*
Y840420D03*
Y853806D03*
Y860499D03*
Y863845D03*
Y883924D03*
Y877231D03*
Y870538D03*
Y890617D03*
Y897310D03*
Y900656D03*
Y914042D03*
Y907349D03*
Y927428D03*
Y920735D03*
Y934121D03*
Y944160D03*
Y937467D03*
Y960892D03*
Y950853D03*
Y957546D03*
Y980971D03*
Y974278D03*
Y967585D03*
Y994357D03*
Y987664D03*
X679999Y1027822D03*
X680299Y1021129D03*
X679999Y1047900D03*
Y1041207D03*
Y1034514D03*
Y1054593D03*
X680299Y1074672D03*
Y1067979D03*
Y1091404D03*
Y1081365D03*
Y1084711D03*
Y1098097D03*
Y1111483D03*
Y1104790D03*
Y1128215D03*
Y1118176D03*
Y1121522D03*
Y1141601D03*
Y1134908D03*
Y1148294D03*
Y1154987D03*
Y1158333D03*
Y1171719D03*
Y1165026D03*
Y1185105D03*
Y1178412D03*
Y1191798D03*
Y1208530D03*
Y1201837D03*
Y1195144D03*
Y1221916D03*
Y1215223D03*
Y1238648D03*
Y1228609D03*
Y1231955D03*
Y1245341D03*
X696441Y770144D03*
Y776837D03*
Y786877D03*
Y783530D03*
Y800263D03*
Y793570D03*
Y813648D03*
Y806955D03*
Y820341D03*
Y830381D03*
Y823688D03*
Y850459D03*
Y843766D03*
Y837074D03*
Y867192D03*
Y860499D03*
Y857152D03*
Y873885D03*
Y880577D03*
Y887270D03*
Y897310D03*
Y893963D03*
Y917389D03*
Y910696D03*
Y904003D03*
Y924081D03*
Y934121D03*
Y930774D03*
Y947507D03*
Y940814D03*
Y964239D03*
Y977625D03*
Y970932D03*
Y991011D03*
Y984318D03*
Y1021129D03*
Y1024475D03*
Y1031168D03*
X696141Y1044554D03*
Y1037861D03*
X696441Y1051247D03*
Y1071325D03*
Y1064633D03*
Y1078018D03*
Y1094751D03*
Y1088058D03*
Y1081365D03*
Y1108136D03*
Y1101444D03*
Y1124869D03*
Y1118176D03*
Y1114829D03*
Y1144947D03*
Y1138255D03*
Y1131562D03*
Y1161680D03*
Y1154987D03*
Y1151640D03*
Y1175066D03*
Y1168373D03*
Y1181758D03*
Y1191798D03*
Y1188451D03*
Y1205184D03*
Y1198491D03*
Y1218569D03*
Y1211877D03*
Y1225262D03*
Y1241995D03*
Y1235302D03*
Y1228609D03*
X709899Y960892D03*
Y957546D03*
X709999Y967585D03*
Y1054593D03*
X726141Y964239D03*
Y1021129D03*
Y1024475D03*
Y1051247D03*
X739699Y780184D03*
Y773491D03*
Y786877D03*
Y803609D03*
Y796916D03*
Y790223D03*
Y816995D03*
Y810302D03*
Y833727D03*
Y823688D03*
Y827034D03*
Y847113D03*
Y840420D03*
Y853806D03*
Y860499D03*
Y863845D03*
Y883924D03*
Y877231D03*
Y870538D03*
Y890617D03*
Y897310D03*
Y900656D03*
Y914042D03*
Y907349D03*
Y927428D03*
Y920735D03*
Y934121D03*
Y944160D03*
Y937467D03*
Y960892D03*
Y950853D03*
Y957546D03*
Y980971D03*
Y974278D03*
Y967585D03*
Y994357D03*
Y987664D03*
Y1027822D03*
Y1021129D03*
Y1047900D03*
Y1041207D03*
Y1034514D03*
Y1054593D03*
Y1074672D03*
Y1067979D03*
Y1091404D03*
Y1081365D03*
Y1084711D03*
Y1098097D03*
Y1111483D03*
Y1104790D03*
Y1128215D03*
Y1118176D03*
Y1121522D03*
Y1141601D03*
Y1134908D03*
Y1148294D03*
Y1154987D03*
Y1158333D03*
Y1171719D03*
Y1165026D03*
Y1185105D03*
Y1178412D03*
Y1191798D03*
Y1208530D03*
Y1201837D03*
Y1195144D03*
Y1221916D03*
Y1215223D03*
Y1238648D03*
Y1228609D03*
Y1231955D03*
Y1245341D03*
X755841Y770144D03*
Y776837D03*
Y786877D03*
Y783530D03*
Y800263D03*
Y793570D03*
Y813648D03*
Y806955D03*
Y820341D03*
Y830381D03*
Y823688D03*
Y850459D03*
Y843766D03*
Y837074D03*
Y867192D03*
Y860499D03*
Y857152D03*
Y873885D03*
Y880577D03*
Y887270D03*
Y897310D03*
Y893963D03*
Y917389D03*
Y910696D03*
Y904003D03*
Y924081D03*
Y934121D03*
Y930774D03*
Y947507D03*
Y940814D03*
Y964239D03*
Y977625D03*
X755741Y970932D03*
X755841Y991011D03*
Y984318D03*
Y1021129D03*
Y1024475D03*
Y1031168D03*
X755541Y1044554D03*
Y1037861D03*
X755841Y1051247D03*
X755676Y1071326D03*
X755741Y1064633D03*
X755841Y1078018D03*
Y1094751D03*
Y1088058D03*
Y1081365D03*
X755676Y1108137D03*
X755841Y1101444D03*
Y1124869D03*
Y1118176D03*
Y1114829D03*
Y1144947D03*
Y1138255D03*
Y1131562D03*
Y1161680D03*
Y1154987D03*
Y1151640D03*
Y1175066D03*
Y1168373D03*
X755676Y1181759D03*
X755841Y1191798D03*
X755676Y1188452D03*
X755841Y1205184D03*
Y1198491D03*
Y1218569D03*
Y1211877D03*
Y1225262D03*
Y1241995D03*
Y1235302D03*
Y1228609D03*
X769399Y960892D03*
Y957546D03*
Y967585D03*
Y1054593D03*
X785541Y964239D03*
Y1021129D03*
Y1024475D03*
Y1051247D03*
X799099Y816995D03*
Y810302D03*
Y833727D03*
Y823688D03*
Y827034D03*
Y840420D03*
Y960892D03*
Y957546D03*
Y967585D03*
Y1221916D03*
Y1215223D03*
Y1238648D03*
Y1228609D03*
Y1231955D03*
Y1245341D03*
X815241Y813648D03*
Y806955D03*
Y820341D03*
Y830381D03*
Y823688D03*
Y837074D03*
Y964239D03*
Y1218570D03*
Y1211877D03*
Y1225263D03*
Y1241995D03*
Y1235302D03*
Y1228609D03*
X828799Y960892D03*
Y957546D03*
Y967585D03*
X844941Y964239D03*
X1012541Y960892D03*
Y957546D03*
Y967585D03*
X1028683Y964239D03*
X1042241Y816995D03*
Y810302D03*
Y833727D03*
Y823688D03*
Y827034D03*
Y840420D03*
Y960892D03*
Y957546D03*
Y967585D03*
Y1221916D03*
Y1215223D03*
Y1238648D03*
Y1228609D03*
Y1231955D03*
Y1245341D03*
X1058383Y813648D03*
Y806955D03*
Y820341D03*
Y830381D03*
Y823688D03*
Y837074D03*
Y964239D03*
Y1218570D03*
Y1211877D03*
Y1225263D03*
Y1241995D03*
Y1235302D03*
Y1228609D03*
X1071941Y960892D03*
Y957546D03*
Y967585D03*
Y1054593D03*
X1101641Y780184D03*
Y773491D03*
Y786877D03*
Y803609D03*
Y796916D03*
Y790223D03*
Y816995D03*
Y810302D03*
Y833727D03*
Y823688D03*
Y827034D03*
Y847113D03*
Y840420D03*
Y853806D03*
Y860499D03*
Y863845D03*
Y883924D03*
Y877231D03*
Y870538D03*
Y890617D03*
Y897310D03*
Y900656D03*
Y914042D03*
Y907349D03*
Y927428D03*
Y920735D03*
Y934121D03*
Y944160D03*
Y937467D03*
Y960892D03*
Y950853D03*
X1088083Y964239D03*
X1101641Y957546D03*
Y980971D03*
Y974278D03*
Y967585D03*
Y994357D03*
Y987664D03*
X1088083Y1021129D03*
Y1024475D03*
X1101641Y1027822D03*
Y1021129D03*
Y1047900D03*
Y1041207D03*
Y1034515D03*
X1088083Y1051247D03*
X1101641Y1054593D03*
Y1074672D03*
Y1067979D03*
Y1091404D03*
Y1081365D03*
Y1084711D03*
Y1098097D03*
Y1111483D03*
Y1104790D03*
Y1128215D03*
Y1118176D03*
Y1121522D03*
Y1141601D03*
Y1134908D03*
Y1148294D03*
Y1154987D03*
Y1158333D03*
Y1171719D03*
Y1165026D03*
Y1185105D03*
Y1178412D03*
Y1191798D03*
Y1208530D03*
Y1201837D03*
Y1195144D03*
Y1221916D03*
Y1215223D03*
Y1238648D03*
Y1228609D03*
Y1231955D03*
Y1245341D03*
X1117783Y770144D03*
Y776837D03*
Y786877D03*
Y783530D03*
Y800263D03*
Y793570D03*
Y813648D03*
Y806955D03*
Y820341D03*
Y830381D03*
Y823688D03*
Y850459D03*
Y843766D03*
Y837074D03*
Y867192D03*
Y860499D03*
Y857152D03*
Y873885D03*
Y880577D03*
Y887270D03*
Y897310D03*
Y893963D03*
Y917389D03*
Y910696D03*
Y904003D03*
Y924081D03*
Y934121D03*
Y930774D03*
Y947507D03*
Y940814D03*
Y964239D03*
Y977625D03*
Y970932D03*
Y991011D03*
Y984318D03*
Y1021129D03*
Y1024475D03*
Y1031168D03*
Y1044554D03*
Y1037861D03*
Y1051247D03*
Y1071326D03*
Y1064633D03*
Y1078018D03*
Y1094751D03*
Y1088058D03*
Y1081365D03*
Y1108137D03*
Y1101444D03*
Y1124869D03*
Y1118176D03*
Y1114829D03*
Y1144948D03*
Y1138255D03*
Y1131562D03*
Y1161680D03*
Y1154987D03*
Y1151641D03*
Y1175066D03*
Y1168373D03*
Y1181759D03*
Y1191798D03*
Y1188452D03*
Y1205184D03*
Y1198491D03*
Y1218570D03*
Y1211877D03*
Y1225263D03*
Y1241995D03*
Y1235302D03*
Y1228609D03*
X1131341Y960892D03*
Y957546D03*
Y967585D03*
Y1054593D03*
X1147483Y964239D03*
Y1021129D03*
Y1024475D03*
Y1051247D03*
X1161041Y780184D03*
Y773491D03*
Y786877D03*
Y803609D03*
Y796916D03*
Y790223D03*
Y816995D03*
Y810302D03*
Y833727D03*
Y823688D03*
Y827034D03*
Y847113D03*
Y840420D03*
Y853806D03*
Y860499D03*
Y863845D03*
Y883924D03*
Y877231D03*
Y870538D03*
Y890617D03*
Y897310D03*
Y900656D03*
Y914042D03*
Y907349D03*
Y927428D03*
Y920735D03*
Y934121D03*
Y944160D03*
Y937467D03*
Y960892D03*
Y950853D03*
Y957546D03*
Y980971D03*
Y974278D03*
Y967585D03*
Y994357D03*
Y987664D03*
Y1027822D03*
Y1021129D03*
Y1047900D03*
Y1041207D03*
Y1034515D03*
Y1054593D03*
Y1074672D03*
Y1067979D03*
Y1091404D03*
Y1081365D03*
Y1084711D03*
Y1098097D03*
Y1111483D03*
Y1104790D03*
Y1128215D03*
Y1118176D03*
Y1121522D03*
Y1141601D03*
Y1134908D03*
Y1148294D03*
Y1154987D03*
Y1158333D03*
Y1171719D03*
Y1165026D03*
Y1185105D03*
Y1178412D03*
Y1191798D03*
Y1208530D03*
Y1201837D03*
Y1195144D03*
Y1221916D03*
Y1215223D03*
Y1238648D03*
Y1228609D03*
Y1231955D03*
Y1245341D03*
X1177183Y770144D03*
Y776837D03*
Y786877D03*
Y783530D03*
Y800263D03*
Y793570D03*
Y813648D03*
Y806955D03*
Y820341D03*
Y830381D03*
Y823688D03*
Y850459D03*
Y843766D03*
Y837074D03*
Y867192D03*
Y860499D03*
Y857152D03*
Y873885D03*
Y880577D03*
Y887270D03*
Y897310D03*
Y893963D03*
Y917389D03*
Y910696D03*
Y904003D03*
Y924081D03*
Y934121D03*
Y930774D03*
Y947507D03*
Y940814D03*
Y964239D03*
Y977625D03*
Y970932D03*
Y991011D03*
Y984318D03*
X1177283Y1021129D03*
Y1024475D03*
Y1031168D03*
Y1044554D03*
Y1037861D03*
Y1051247D03*
Y1071326D03*
Y1064633D03*
Y1078018D03*
Y1094752D03*
Y1088059D03*
Y1081366D03*
Y1108137D03*
Y1101444D03*
X1177183Y1124869D03*
X1177283Y1118177D03*
Y1114830D03*
Y1144948D03*
Y1138255D03*
X1177183Y1131562D03*
X1177283Y1161680D03*
Y1154988D03*
Y1151641D03*
Y1175066D03*
Y1168373D03*
Y1181759D03*
Y1191799D03*
Y1188452D03*
Y1205184D03*
Y1198491D03*
Y1218570D03*
Y1211877D03*
Y1225263D03*
X1177250Y1241995D03*
X1177283Y1235302D03*
Y1228609D03*
X1190741Y960892D03*
Y957546D03*
X1220441Y883924D03*
Y890617D03*
Y897310D03*
Y900656D03*
Y914042D03*
Y907349D03*
Y960892D03*
Y957546D03*
Y1185105D03*
Y1178412D03*
Y1191798D03*
Y1208530D03*
Y1201837D03*
Y1195144D03*
X1236583Y880577D03*
Y887270D03*
Y897310D03*
Y893963D03*
Y910696D03*
Y904003D03*
Y1175066D03*
Y1181759D03*
Y1191798D03*
Y1188452D03*
Y1205184D03*
Y1198491D03*
X1313921Y880219D03*
X1312070Y883423D03*
X1313921Y893036D03*
X1312070Y889832D03*
X1310221Y886627D03*
X1313921D03*
X1312503Y1121447D03*
X1326869Y851380D03*
X1330569Y844971D03*
X1325020Y848176D03*
X1328720D03*
X1326871Y857789D03*
X1328720Y860993D03*
X1330571Y857789D03*
X1317621Y880219D03*
X1319471Y883423D03*
X1325020Y899445D03*
Y893036D03*
X1326871Y889832D03*
X1330571D03*
X1317620Y893036D03*
X1319470Y889832D03*
X1323171Y896240D03*
X1330571D03*
X1317621Y886627D03*
X1326871Y896240D03*
X1321321Y886627D03*
X1325020Y912262D03*
X1326871Y909057D03*
X1330571D03*
X1326871Y902649D03*
X1330571D03*
X1323171Y915466D03*
X1330571D03*
X1326871D03*
X1325021Y931488D03*
X1326871Y928283D03*
X1330571D03*
Y921875D03*
X1326871D03*
X1325020Y918670D03*
X1326871Y941100D03*
X1325020Y937896D03*
X1330571Y941100D03*
X1323171Y934691D03*
X1330571D03*
X1326871D03*
Y947509D03*
X1330571D03*
X1325020Y950713D03*
X1326871Y960326D03*
X1325020Y957122D03*
X1330571Y960326D03*
X1326871Y966735D03*
X1330571D03*
X1326871Y953917D03*
X1330571D03*
X1323172D03*
X1326871Y979552D03*
X1330571D03*
X1325020Y976347D03*
X1323171Y973143D03*
X1325020Y969939D03*
X1323603Y1006093D03*
X1325453Y1002888D03*
X1327303Y999684D03*
X1331003D03*
X1327303Y1012501D03*
X1325453Y1009297D03*
X1331003Y1012501D03*
X1327304Y1031727D03*
X1325453Y1028523D03*
X1331003Y1031727D03*
X1325453Y1022114D03*
X1327303Y1018910D03*
X1331003D03*
X1323603Y1025318D03*
X1331004D03*
X1327304D03*
X1325453Y1047749D03*
Y1041340D03*
X1327303Y1038136D03*
X1331003D03*
X1323603Y1044544D03*
X1331003D03*
X1327303D03*
X1325453Y1060565D03*
X1327303Y1057361D03*
X1331003D03*
X1323603Y1063770D03*
X1327303D03*
X1331003D03*
X1327303Y1050952D03*
X1331003D03*
Y1070178D03*
X1327304D03*
X1325453Y1066974D03*
Y1079791D03*
X1327303Y1076587D03*
X1331003D03*
X1327303Y1089404D03*
X1325453Y1086200D03*
X1331003Y1089404D03*
X1323603Y1082995D03*
X1331003D03*
X1327303D03*
X1329153Y1124651D03*
X1331003Y1127856D03*
X1323603Y1121447D03*
X1319903Y1127856D03*
X1316203D03*
X1318054Y1118243D03*
X1321753Y1124651D03*
X1323603Y1127856D03*
X1319903Y1121447D03*
X1316203D03*
X1325452Y1137469D03*
X1327303Y1134264D03*
X1318053Y1131060D03*
X1346137Y179649D03*
X1332421Y841467D03*
X1337969Y844971D03*
X1339821Y841467D03*
X1345369Y844971D03*
X1347221Y841467D03*
X1334269Y844971D03*
X1336120Y848176D03*
X1341669Y844971D03*
X1343520Y848176D03*
X1332420Y854584D03*
X1334271Y857789D03*
X1337971D03*
X1341671D03*
X1345371D03*
X1336120Y860993D03*
X1339820Y854584D03*
X1343520Y860993D03*
X1347220Y854584D03*
X1332420Y899445D03*
Y893036D03*
X1334271Y896240D03*
X1339820Y899445D03*
X1343520D03*
X1347220Y893036D03*
X1332420Y912262D03*
X1334271Y915466D03*
X1339820Y912262D03*
X1337971Y909057D03*
X1343520Y912262D03*
X1345371Y909057D03*
X1337971Y902649D03*
X1345371D03*
X1336120Y905853D03*
X1343520D03*
X1339820D03*
X1347220D03*
X1332420Y931488D03*
X1339820D03*
X1332420Y918670D03*
X1337971Y928283D03*
X1343520Y931488D03*
X1345371Y928283D03*
X1337971Y921875D03*
X1339820Y918670D03*
X1345371Y921875D03*
X1343520Y918670D03*
X1336120Y925079D03*
X1343520D03*
X1339820D03*
X1347220D03*
X1332420Y937896D03*
X1334271Y934691D03*
X1337971Y941100D03*
X1339820Y937896D03*
X1345371Y941100D03*
X1343520Y937896D03*
X1337971Y947509D03*
X1345371D03*
X1343520Y944304D03*
X1336120D03*
X1347220D03*
X1339820D03*
X1332420Y950713D03*
Y957122D03*
X1334271Y953917D03*
X1337971Y966735D03*
X1345371D03*
X1336120Y963530D03*
X1339820Y950713D03*
X1343520D03*
X1337971Y960326D03*
X1339820Y957122D03*
X1345371Y960326D03*
X1343520Y957122D03*
X1347220Y963530D03*
X1336120Y982756D03*
X1343520D03*
X1339820D03*
X1347220D03*
X1345371Y979552D03*
X1343520Y976347D03*
X1337971Y979552D03*
X1339820Y976347D03*
X1332420D03*
Y969939D03*
X1334271Y973143D03*
X1339820Y969939D03*
X1343520D03*
X1334704Y1006093D03*
X1332853Y1002888D03*
Y1009297D03*
X1338404Y1012501D03*
X1345804D03*
X1340253Y1009297D03*
X1343953D03*
X1340253Y1002888D03*
X1338404Y999684D03*
X1347653Y1002888D03*
X1345804Y999684D03*
X1332853Y1028523D03*
Y1022114D03*
X1338404Y1031727D03*
X1340253Y1028523D03*
X1345804Y1031727D03*
X1343953Y1028523D03*
X1334704Y1025318D03*
X1336553Y1015705D03*
X1347653D03*
X1340253Y1022114D03*
X1338404Y1018910D03*
X1343953Y1022114D03*
X1345804Y1018910D03*
X1332853Y1047749D03*
Y1041340D03*
X1340253D03*
X1338404Y1038136D03*
X1343953Y1041340D03*
X1345804Y1038136D03*
X1336553Y1034931D03*
X1347653D03*
X1340253D03*
X1334704Y1044544D03*
X1343953Y1034931D03*
X1340253Y1047749D03*
X1343953D03*
X1332853Y1060565D03*
X1334704Y1063770D03*
X1340253Y1060565D03*
X1338404Y1057361D03*
X1343953Y1060565D03*
X1345804Y1057361D03*
X1338404Y1050952D03*
X1345804D03*
X1336553Y1054157D03*
X1347653D03*
X1340253D03*
X1343953D03*
X1332853Y1066974D03*
X1343953Y1079791D03*
X1345804Y1076587D03*
X1338404Y1070178D03*
X1340253Y1066974D03*
X1345804Y1070178D03*
X1343953Y1066974D03*
X1332853Y1079791D03*
X1340253D03*
X1338404Y1076587D03*
X1336553Y1073383D03*
X1347653D03*
X1340253D03*
X1343953D03*
X1332853Y1086200D03*
X1334704Y1082995D03*
X1338404Y1095813D03*
X1345804D03*
X1338404Y1089404D03*
X1340253Y1086200D03*
X1345804Y1089404D03*
X1343953Y1086200D03*
X1336553Y1092608D03*
X1343953D03*
X1340253D03*
X1347653D03*
X1340253Y1099017D03*
X1343953D03*
X1345803Y1108630D03*
X1340254Y1105426D03*
X1336554Y1111834D03*
X1334703Y1108630D03*
X1343954Y1111834D03*
X1342103Y1108630D03*
X1338403D03*
X1334703Y1121447D03*
X1336554Y1124651D03*
X1340253D03*
X1343953D03*
X1347653D03*
X1332854D03*
X1338404Y1127856D03*
X1342104Y1121447D03*
X1345804Y1127856D03*
X1342103Y1115039D03*
X1345803D03*
X1334703D03*
Y1134264D03*
X1338403Y1140973D03*
X1342104Y1134264D03*
X1345803Y1140973D03*
X1332854Y1137469D03*
X1336554D03*
X1340254D03*
X1343954D03*
X1347654D03*
X1352557Y175948D03*
X1349351Y181498D03*
X1355761Y185198D03*
X1349351D03*
X1355761Y174098D03*
Y181498D03*
X1352557Y183348D03*
X1352561Y198148D03*
X1355771Y196298D03*
X1355765Y199999D03*
Y203699D03*
X1363869Y844971D03*
X1352769D03*
X1356469D03*
X1360169D03*
X1362021Y841467D03*
X1349069Y844971D03*
X1350920Y848176D03*
X1354621Y841467D03*
X1358320Y848176D03*
X1349071Y857789D03*
X1354620Y854584D03*
X1356471Y857789D03*
X1360171D03*
X1363871D03*
X1350920Y860993D03*
X1352771Y857789D03*
X1358320Y860993D03*
X1362020Y854584D03*
X1350920Y899445D03*
X1358320D03*
Y893036D03*
X1350920D03*
X1362020D03*
X1349071Y896240D03*
X1356471D03*
X1352771D03*
X1360171D03*
X1352771Y902649D03*
X1356471D03*
X1350920Y912262D03*
X1352771Y909057D03*
X1358320Y912262D03*
X1356471Y909057D03*
X1349071Y915466D03*
X1356471D03*
X1352771D03*
X1360171D03*
X1350920Y931488D03*
X1352771Y928283D03*
X1358320Y931488D03*
X1356471Y928283D03*
X1352771Y921875D03*
X1350920Y918670D03*
X1356471Y921875D03*
X1358320Y918670D03*
X1356471Y941100D03*
X1358320Y937896D03*
X1352771Y947509D03*
X1356471D03*
X1352771Y941100D03*
X1350920Y937896D03*
X1349071Y934691D03*
X1356471D03*
X1352771D03*
X1360171D03*
X1352771Y960326D03*
X1350920Y957122D03*
X1356471Y960326D03*
X1358320Y957122D03*
X1350920Y950713D03*
X1358320D03*
X1349071Y953917D03*
X1356471D03*
X1352771D03*
X1360171D03*
X1356471Y966735D03*
X1352771D03*
X1350920Y969939D03*
X1358320D03*
X1349504Y1006093D03*
X1356904D03*
X1353204D03*
X1360604D03*
X1351353Y1002888D03*
X1353204Y999684D03*
X1358753Y1002888D03*
X1356904Y999684D03*
X1353204Y1012501D03*
X1351353Y1009297D03*
X1356904Y1012501D03*
X1358753Y1009297D03*
X1353204Y1031727D03*
X1351353Y1028523D03*
X1356904Y1031727D03*
X1358753Y1028523D03*
X1351353Y1022114D03*
X1353204Y1018910D03*
X1358753Y1022114D03*
X1356904Y1018910D03*
X1353204Y1025318D03*
X1360604D03*
X1349502D03*
X1356902D03*
X1351353Y1047749D03*
X1358753D03*
X1351353Y1041340D03*
X1353204Y1038136D03*
X1358753Y1041340D03*
X1356904Y1038136D03*
X1349504Y1044544D03*
X1356904D03*
X1353204D03*
X1360604D03*
X1351353Y1060565D03*
X1353204Y1057361D03*
X1358753Y1060565D03*
X1356904Y1057361D03*
X1353204Y1050952D03*
X1356904D03*
X1349504Y1063770D03*
X1360604D03*
X1353204D03*
X1356904D03*
Y1070178D03*
X1358753Y1066974D03*
X1353204Y1070178D03*
X1351353Y1066974D03*
Y1079791D03*
X1353204Y1076587D03*
X1358753Y1079791D03*
X1356904Y1076587D03*
X1353204Y1089404D03*
X1351353Y1086200D03*
X1356904Y1089404D03*
X1358753Y1086200D03*
X1349504Y1082995D03*
X1360604D03*
X1353204D03*
X1356904D03*
X1351353Y1124651D03*
X1355053D03*
X1358753D03*
X1362453D03*
X1349504Y1121447D03*
X1353204Y1127856D03*
X1356904Y1121447D03*
X1360604Y1127856D03*
X1349504Y1134264D03*
X1353203Y1140973D03*
X1356904Y1134264D03*
X1360603Y1140973D03*
X1351354Y1137469D03*
X1355054D03*
X1358754D03*
X1362454D03*
X1367569Y844971D03*
X1369421Y841467D03*
X1373120Y848176D03*
X1376821Y841467D03*
X1365720Y848176D03*
X1371269Y844971D03*
X1374969D03*
X1378669D03*
X1365720Y860993D03*
X1367571Y857789D03*
X1373120Y860993D03*
X1374971Y857789D03*
X1369420Y854584D03*
X1371271Y857789D03*
X1376820Y854584D03*
X1378671Y857789D03*
X1374971Y973143D03*
X1376820Y976347D03*
X1378671Y979552D03*
Y973143D03*
X1366153Y1002888D03*
X1364304Y999684D03*
X1369853Y1002888D03*
X1371704Y999684D03*
X1369853Y1111834D03*
X1368004Y1108630D03*
X1377253Y1099017D03*
X1379104Y1108630D03*
X1373553Y1105426D03*
X1371704Y1108630D03*
X1379104Y1102221D03*
X1377253Y1111834D03*
X1375404Y1108630D03*
X1366153Y1124651D03*
X1371704Y1121447D03*
X1373553Y1124651D03*
X1377253D03*
X1368004Y1127856D03*
X1369853Y1124651D03*
X1375404Y1127856D03*
X1379104Y1121447D03*
X1364304D03*
X1375404Y1115039D03*
X1368004D03*
X1379104D03*
X1368003Y1140973D03*
X1371704Y1134264D03*
X1375403Y1140973D03*
X1379104Y1134264D03*
X1364304D03*
X1366154Y1137469D03*
X1369854D03*
X1373554D03*
X1377254D03*
X1380520Y848176D03*
X1386069Y844971D03*
X1389769D03*
X1393469D03*
X1382369D03*
X1384221Y841467D03*
X1387920Y848176D03*
X1391621Y841467D03*
X1395320Y848176D03*
X1380520Y860993D03*
X1382371Y857789D03*
X1387920Y860993D03*
X1389771Y857789D03*
X1395320Y860993D03*
X1384220Y854584D03*
X1386071Y857789D03*
X1391620Y854584D03*
X1393471Y857789D03*
Y883423D03*
X1391620Y880219D03*
X1389771Y883423D03*
X1386071Y896240D03*
X1389771D03*
X1393471D03*
X1387920Y899445D03*
X1391620Y893036D03*
X1395320Y899445D03*
Y886627D03*
X1380953Y1099017D03*
X1395753Y1105426D03*
X1393904Y1108630D03*
X1390204Y1102221D03*
X1392053Y1111834D03*
X1388353D03*
X1384653Y1105426D03*
Y1099017D03*
X1392053Y1105426D03*
X1395753Y1111834D03*
X1388353Y1105426D03*
X1384653Y1111834D03*
X1386504Y1108630D03*
X1380953Y1124651D03*
X1384653D03*
X1382804Y1127856D03*
X1386504Y1121447D03*
X1390204Y1115039D03*
X1382803Y1140973D03*
X1386504Y1134264D03*
X1380954Y1137469D03*
X1384654D03*
X1397169Y844971D03*
X1399021Y841467D03*
X1402720Y848176D03*
X1406420D03*
X1411969Y844971D03*
X1400869D03*
X1404569D03*
X1410120Y848176D03*
X1397171Y857789D03*
X1402720Y860993D03*
X1404571Y857789D03*
X1410121Y860993D03*
X1411971Y857789D03*
X1399020Y854584D03*
X1400871Y857789D03*
X1406420Y854584D03*
X1408271Y857789D03*
Y883423D03*
X1406420Y880219D03*
X1400871Y883423D03*
X1399020Y880219D03*
X1404571Y883423D03*
X1397171D03*
X1411971D03*
X1397171Y896240D03*
X1402720Y899445D03*
X1404571Y896240D03*
X1410120Y899445D03*
X1399020Y893036D03*
X1400871Y896240D03*
X1406420Y893036D03*
X1408271Y896240D03*
X1411971D03*
X1410120Y886627D03*
X1402720D03*
X1405003Y1076587D03*
X1406853Y1079791D03*
X1413820Y848176D03*
X1424921Y860993D03*
X1421220Y854584D03*
X1417520Y860993D03*
X1428620Y854584D03*
X1426771Y857789D03*
X1423071D03*
X1419371D03*
X1413821Y854584D03*
X1428621Y880219D03*
X1423071Y883423D03*
X1421220Y880219D03*
X1415671Y883423D03*
X1413820Y880219D03*
X1426771Y883423D03*
X1419371D03*
X1413820Y893036D03*
X1421220Y899445D03*
X1419371Y896240D03*
X1424920Y899445D03*
X1426772Y896240D03*
X1417520Y899445D03*
X1421220Y893036D03*
X1423071Y896240D03*
X1428621Y893036D03*
X1424920Y886627D03*
X1417520D03*
X1445271Y857789D03*
X1439720Y860993D03*
X1437871Y857789D03*
X1432320Y860993D03*
X1430471Y857789D03*
X1443420Y854584D03*
X1441571Y857789D03*
X1436020Y854584D03*
X1434171Y857789D03*
X1445271Y883423D03*
X1443420Y880219D03*
X1437871Y883423D03*
X1436020Y880219D03*
X1430471Y883423D03*
X1441571D03*
X1434171D03*
X1430471Y896240D03*
X1436020Y893036D03*
X1437871Y896240D03*
X1441571D03*
X1432320Y899445D03*
X1434171Y896240D03*
X1439720Y899445D03*
X1443420Y893036D03*
X1439720Y886627D03*
X1432320D03*
X1460071Y857789D03*
X1454520Y860993D03*
X1452671Y857789D03*
X1447120Y860993D03*
X1458220Y854584D03*
X1456371Y857789D03*
X1450820Y854584D03*
X1448971Y857789D03*
X1447120Y886627D03*
X1460504Y1121447D03*
X1456804Y1127856D03*
X1453104Y1121447D03*
X1449404Y1127856D03*
X1445704Y1121447D03*
X1458653Y1124651D03*
X1454953D03*
X1451253D03*
X1447553D03*
X1460504Y1134264D03*
X1458654Y1137469D03*
X1453104Y1134264D03*
X1451254Y1137469D03*
X1456803Y1140973D03*
X1454954Y1137469D03*
X1449403Y1140973D03*
X1467471Y857789D03*
X1461920Y860993D03*
X1476720D03*
X1474871Y857789D03*
X1471171D03*
X1465620Y854584D03*
X1463771Y857789D03*
X1473020Y854584D03*
X1469320Y860993D03*
X1476720Y899445D03*
Y912262D03*
X1474871Y909057D03*
Y902649D03*
X1476720Y905853D03*
X1473020D03*
X1476720Y931488D03*
X1474871Y921875D03*
X1476720Y918670D03*
X1474871Y928283D03*
X1473020Y925079D03*
X1476720D03*
X1474871Y947509D03*
Y941100D03*
X1476720Y937896D03*
X1473020Y944304D03*
X1476720D03*
Y950713D03*
Y957122D03*
X1474871Y960326D03*
X1463771Y979552D03*
X1461920Y976347D03*
X1467471Y979552D03*
X1469320Y976347D03*
X1476720Y982756D03*
X1473020D03*
X1474871Y979552D03*
X1476720Y976347D03*
X1477153Y1002888D03*
X1475304Y999684D03*
Y1012501D03*
X1477153Y1009297D03*
X1473453Y1015705D03*
X1475304Y1031727D03*
X1477153Y1028523D03*
Y1022114D03*
X1475304Y1018910D03*
X1477153Y1041340D03*
X1475304Y1038136D03*
X1477153Y1047749D03*
Y1034931D03*
X1473453D03*
X1477153Y1060565D03*
X1475304Y1057361D03*
Y1050952D03*
X1477153Y1054157D03*
X1473453D03*
X1475304Y1070178D03*
X1477153Y1066974D03*
Y1079791D03*
X1475304Y1076587D03*
X1473453Y1073383D03*
X1477153D03*
X1475304Y1089404D03*
X1477153Y1086200D03*
X1473453Y1092608D03*
X1477153D03*
X1464204Y1127856D03*
X1475304Y1121447D03*
X1471604Y1127856D03*
X1467904Y1121447D03*
X1466053Y1124651D03*
X1462353D03*
X1477153D03*
X1473453D03*
X1469753D03*
X1469754Y1137469D03*
X1464203Y1140973D03*
X1477154Y1137469D03*
X1471603Y1140973D03*
X1467904Y1134264D03*
X1466054Y1137469D03*
X1462354D03*
X1475304Y1134264D03*
X1473454Y1137469D03*
X1491520Y860993D03*
X1489671Y857789D03*
X1484120Y860993D03*
X1482271Y857789D03*
X1493371D03*
X1487820Y854584D03*
X1485971Y857789D03*
X1480420Y854584D03*
X1478571Y857789D03*
X1487820Y899445D03*
Y893036D03*
X1484120D03*
X1485971Y896240D03*
X1493371D03*
X1489671D03*
X1480420Y899445D03*
X1489671Y902649D03*
X1493371D03*
X1487820Y912262D03*
X1489671Y909057D03*
X1493371D03*
X1489671Y915466D03*
X1485971D03*
X1493371D03*
X1480420Y912262D03*
X1482271Y909057D03*
Y902649D03*
X1484120Y905853D03*
X1480420D03*
X1487820Y931488D03*
X1489671Y928283D03*
X1493371D03*
X1482271D03*
Y921875D03*
X1480420Y918670D03*
X1489671Y921875D03*
X1487820Y918670D03*
X1493371Y921875D03*
X1480420Y931488D03*
Y925079D03*
X1484120D03*
X1489671Y941100D03*
X1487820Y937896D03*
X1493371Y941100D03*
X1489671Y934691D03*
X1485971D03*
X1493371D03*
X1489671Y947509D03*
X1493371D03*
X1482271D03*
Y941100D03*
X1480420Y937896D03*
X1484120Y944304D03*
X1480420D03*
X1487820Y950713D03*
X1489671Y960326D03*
X1487820Y957122D03*
X1493371Y960326D03*
Y966735D03*
X1489671D03*
X1480420Y950713D03*
X1489671Y953917D03*
X1493371D03*
X1485971D03*
X1480420Y957122D03*
X1482271Y960326D03*
X1484120Y982756D03*
X1480420D03*
Y976347D03*
X1482271Y979552D03*
X1489671D03*
X1493371D03*
X1487820Y976347D03*
X1485971Y973143D03*
X1487820Y969939D03*
X1493804Y1006093D03*
X1490104D03*
X1486404D03*
X1493804Y1012501D03*
X1480853Y1002888D03*
X1482703Y999684D03*
X1490104Y1012501D03*
X1488253Y1009297D03*
X1482704Y1012501D03*
X1480853Y1009297D03*
X1493803Y999684D03*
X1488253Y1002888D03*
X1490104Y999684D03*
Y1031727D03*
X1488253Y1028523D03*
X1493804Y1031727D03*
X1488253Y1022114D03*
X1490104Y1018910D03*
X1493804D03*
X1490104Y1025318D03*
X1486404D03*
X1493804D03*
X1484553Y1015705D03*
X1482704Y1031727D03*
X1480853Y1028523D03*
Y1022114D03*
X1482704Y1018910D03*
X1480853Y1041340D03*
X1482704Y1038136D03*
X1488253Y1047749D03*
Y1041340D03*
X1490104Y1038136D03*
X1493804D03*
X1480853Y1047749D03*
X1486404Y1044544D03*
X1484553Y1034931D03*
X1490104Y1044544D03*
X1493804D03*
X1480853Y1034931D03*
X1488253Y1060565D03*
X1490104Y1057361D03*
X1493804D03*
X1486404Y1063770D03*
X1490104D03*
X1493804D03*
X1490104Y1050952D03*
X1493804D03*
X1480853Y1060565D03*
X1482704Y1057361D03*
Y1050952D03*
X1484553Y1054157D03*
X1480853D03*
X1493804Y1070178D03*
X1490104D03*
X1488253Y1066974D03*
X1480853Y1079791D03*
X1482704Y1076587D03*
Y1070178D03*
X1480853Y1066974D03*
X1488253Y1079791D03*
X1490104Y1076587D03*
X1493804D03*
X1484553Y1073383D03*
X1480853D03*
X1490104Y1089404D03*
X1488253Y1086200D03*
X1493804Y1089404D03*
X1490104Y1082995D03*
X1486404D03*
X1493804D03*
X1486404Y1095813D03*
X1482703D03*
X1482704Y1089404D03*
X1480853Y1086200D03*
X1484553Y1092608D03*
X1480853D03*
X1493804Y1102221D03*
X1491953Y1099017D03*
X1493804Y1127856D03*
X1490104Y1121447D03*
X1486404Y1127856D03*
X1482704Y1121447D03*
X1479004Y1127856D03*
X1491953Y1124651D03*
X1488253D03*
X1484553D03*
X1480853D03*
X1493803Y1140973D03*
X1490104Y1134264D03*
X1488254Y1137469D03*
X1482704Y1134264D03*
X1480854Y1137469D03*
X1491954D03*
X1486403Y1140973D03*
X1484554Y1137469D03*
X1479003Y1140973D03*
X1508171Y864197D03*
X1510021Y854584D03*
X1504471Y857789D03*
X1498920Y860993D03*
X1497071Y857789D03*
X1502620Y854584D03*
X1500771Y857789D03*
X1495220Y854584D03*
X1502621Y899445D03*
X1506320D03*
X1495220D03*
Y893036D03*
X1498920D03*
X1497071Y896240D03*
X1506321Y912262D03*
X1508171Y909057D03*
X1500771Y902649D03*
X1508171D03*
X1502621Y912262D03*
X1500771Y909057D03*
X1502621Y905853D03*
X1510021D03*
X1498920D03*
X1506321D03*
X1495220Y912262D03*
X1497071Y915466D03*
X1502621Y931488D03*
X1500771Y928283D03*
X1506321Y931488D03*
X1508171Y928283D03*
X1500771Y921875D03*
X1502621Y918670D03*
X1508171Y921875D03*
X1506321Y918670D03*
X1502621Y925079D03*
X1510021D03*
X1498920D03*
X1506321D03*
X1495220Y931488D03*
Y918670D03*
X1500771Y941100D03*
X1502621Y937896D03*
X1508171Y941100D03*
X1506321Y937896D03*
X1500771Y947509D03*
X1508171D03*
X1495220Y937896D03*
X1510021Y944304D03*
X1497071Y934691D03*
X1502621Y944304D03*
X1506320D03*
X1498920D03*
X1500771Y966735D03*
X1508171D03*
X1498920Y963530D03*
X1502621Y950713D03*
X1506320D03*
X1508171Y960326D03*
X1506320Y957122D03*
X1500771Y960326D03*
X1502621Y957122D03*
X1510021Y963530D03*
X1495220Y950713D03*
Y957122D03*
X1497071Y953917D03*
X1502621Y969939D03*
X1506321D03*
X1495220Y976347D03*
Y969939D03*
X1497071Y973143D03*
X1497504Y1006093D03*
X1501204Y1012501D03*
X1508603D03*
X1503053Y1009297D03*
X1506753D03*
X1495653D03*
X1495655Y1002888D03*
X1506753D03*
X1508603Y999684D03*
X1503053Y1002888D03*
X1501204Y999684D03*
X1499353Y1015705D03*
X1510453D03*
X1501204Y1031727D03*
X1503053Y1028523D03*
X1508603Y1031727D03*
X1506753Y1028523D03*
Y1022114D03*
X1508603Y1018910D03*
X1503053Y1022114D03*
X1501204Y1018910D03*
X1495653Y1028523D03*
Y1022114D03*
X1497504Y1025318D03*
X1503053Y1041340D03*
X1501204Y1038136D03*
X1506753Y1041340D03*
X1508603Y1038136D03*
X1503053Y1047749D03*
X1506753D03*
X1503053Y1034931D03*
X1510453D03*
X1499353D03*
X1506753D03*
X1495653Y1047749D03*
Y1041340D03*
X1497504Y1044544D03*
X1495653Y1060565D03*
X1503053D03*
X1501204Y1057361D03*
X1506753Y1060565D03*
X1508604Y1057361D03*
X1501203Y1050952D03*
X1508604Y1050953D03*
X1499353Y1054157D03*
X1497504Y1063770D03*
X1510453Y1054157D03*
X1503053D03*
X1506753D03*
Y1079791D03*
X1508604Y1076587D03*
X1501204Y1070178D03*
X1503053Y1066974D03*
X1508604Y1070178D03*
X1506753Y1066974D03*
X1503053Y1079791D03*
X1501204Y1076587D03*
X1499353Y1073383D03*
X1510453D03*
X1503053D03*
X1506753D03*
X1495653Y1066974D03*
Y1079791D03*
X1497504Y1095813D03*
X1508603D03*
X1501204D03*
Y1089404D03*
X1503053Y1086200D03*
X1508604Y1089404D03*
X1506753Y1086200D03*
X1503053Y1092608D03*
X1510452D03*
X1499353D03*
X1506753D03*
X1495653Y1086200D03*
X1497504Y1082995D03*
X1506753Y1099017D03*
X1503053Y1124651D03*
X1497504Y1121447D03*
X1501204Y1127856D03*
X1499353Y1124651D03*
X1495653D03*
X1508604Y1134264D03*
X1501203Y1140973D03*
X1499354Y1137469D03*
X1510454D03*
X1503054D03*
X1497504Y1134264D03*
X1495654Y1137469D03*
X1519271Y851380D03*
X1515571D03*
X1511871Y864197D03*
X1519270D03*
X1522970D03*
X1511871Y857789D03*
X1519271D03*
X1515571D03*
X1517421Y860993D03*
Y854584D03*
X1515571Y883423D03*
X1513720Y880219D03*
X1519271Y883423D03*
X1521121Y880219D03*
X1513720Y873810D03*
X1515571Y870606D03*
X1521121Y873810D03*
X1519271Y870606D03*
X1515570Y877014D03*
X1522970D03*
X1511871D03*
X1519271D03*
X1596941Y883924D03*
Y890617D03*
Y897310D03*
Y900656D03*
Y914042D03*
Y907349D03*
Y960892D03*
Y957546D03*
Y1185105D03*
Y1178412D03*
Y1191798D03*
Y1208530D03*
Y1201837D03*
Y1195144D03*
X1613083Y880577D03*
Y887270D03*
Y897310D03*
Y893963D03*
Y910696D03*
Y904003D03*
Y1175066D03*
Y1181759D03*
Y1191798D03*
Y1188451D03*
Y1205184D03*
Y1198491D03*
X1626641Y960892D03*
Y957546D03*
X1656441Y780184D03*
Y773491D03*
Y786877D03*
Y803609D03*
Y796916D03*
Y790223D03*
Y816995D03*
Y810302D03*
Y833727D03*
Y823688D03*
Y827034D03*
Y847113D03*
Y840420D03*
Y853806D03*
Y860499D03*
Y863845D03*
Y883924D03*
Y877231D03*
Y870538D03*
Y890617D03*
Y897310D03*
Y900656D03*
Y914042D03*
Y907349D03*
Y927428D03*
Y920735D03*
Y934121D03*
Y944160D03*
Y937467D03*
Y960892D03*
Y950853D03*
Y957546D03*
Y980971D03*
Y974278D03*
Y967585D03*
Y994357D03*
Y987664D03*
X1656141Y1027822D03*
X1656441Y1021129D03*
X1656141Y1047900D03*
Y1041207D03*
Y1034514D03*
Y1054593D03*
X1656441Y1074672D03*
Y1067979D03*
Y1091404D03*
Y1081365D03*
Y1084711D03*
Y1098097D03*
Y1111483D03*
Y1104790D03*
Y1128215D03*
Y1118176D03*
Y1121522D03*
Y1141601D03*
Y1134908D03*
Y1148294D03*
Y1154987D03*
Y1158333D03*
Y1171719D03*
Y1165026D03*
Y1185105D03*
Y1178412D03*
Y1191798D03*
Y1208530D03*
Y1201837D03*
Y1195144D03*
Y1221916D03*
Y1215223D03*
Y1238648D03*
Y1228609D03*
Y1231955D03*
Y1245341D03*
X1672583Y770144D03*
Y776837D03*
Y786877D03*
Y783530D03*
Y800263D03*
Y793570D03*
Y813648D03*
Y806955D03*
Y820341D03*
Y830381D03*
Y823688D03*
Y850459D03*
Y843766D03*
Y837074D03*
Y867192D03*
Y860499D03*
Y857152D03*
Y873885D03*
Y880577D03*
Y887270D03*
Y897310D03*
Y893963D03*
Y917389D03*
Y910696D03*
Y904003D03*
Y924081D03*
Y934121D03*
Y930774D03*
Y947507D03*
Y940814D03*
Y964239D03*
Y977625D03*
Y970932D03*
Y991011D03*
Y984318D03*
Y1021129D03*
Y1024475D03*
Y1031168D03*
X1672283Y1044554D03*
Y1037861D03*
X1672583Y1051247D03*
Y1071325D03*
Y1064633D03*
Y1078018D03*
Y1094751D03*
Y1088058D03*
Y1081365D03*
Y1108136D03*
Y1101444D03*
Y1124869D03*
Y1118176D03*
Y1114829D03*
Y1144947D03*
Y1138255D03*
Y1131562D03*
Y1161680D03*
Y1154987D03*
Y1151640D03*
Y1175066D03*
Y1168373D03*
Y1181758D03*
Y1191798D03*
Y1188451D03*
Y1205184D03*
Y1198491D03*
Y1218569D03*
Y1211877D03*
Y1225262D03*
Y1241995D03*
Y1235302D03*
Y1228609D03*
X1686041Y960892D03*
Y957546D03*
X1686141Y967585D03*
Y1054593D03*
X1702283Y964239D03*
Y1021129D03*
Y1024475D03*
Y1051247D03*
X1715841Y780184D03*
Y773491D03*
Y786877D03*
Y803609D03*
Y796916D03*
Y790223D03*
Y816995D03*
Y810302D03*
Y833727D03*
Y823688D03*
Y827034D03*
Y847113D03*
Y840420D03*
Y853806D03*
Y860499D03*
Y863845D03*
Y883924D03*
Y877231D03*
Y870538D03*
Y890617D03*
Y897310D03*
Y900656D03*
Y914042D03*
Y907349D03*
Y927428D03*
Y920735D03*
Y934121D03*
Y944160D03*
Y937467D03*
Y960892D03*
Y950853D03*
Y957546D03*
Y980971D03*
Y974278D03*
Y967585D03*
Y994357D03*
Y987664D03*
Y1027822D03*
Y1021129D03*
Y1047900D03*
Y1041207D03*
Y1034514D03*
Y1054593D03*
Y1074672D03*
Y1067979D03*
Y1091404D03*
Y1081365D03*
Y1084711D03*
Y1098097D03*
Y1111483D03*
Y1104790D03*
Y1128215D03*
Y1118176D03*
Y1121522D03*
Y1141601D03*
Y1134908D03*
Y1148294D03*
Y1154987D03*
Y1158333D03*
Y1171719D03*
Y1165026D03*
Y1185105D03*
Y1178412D03*
Y1191798D03*
Y1208530D03*
Y1201837D03*
Y1195144D03*
Y1221916D03*
Y1215223D03*
Y1238648D03*
Y1228609D03*
Y1231955D03*
Y1245341D03*
X1731983Y770144D03*
Y776837D03*
Y786877D03*
Y783530D03*
Y800263D03*
Y793570D03*
Y813648D03*
Y806955D03*
Y820341D03*
Y830381D03*
Y823688D03*
Y850459D03*
Y843766D03*
Y837074D03*
Y867192D03*
Y860499D03*
Y857152D03*
Y873885D03*
Y880577D03*
Y887270D03*
Y897310D03*
Y893963D03*
Y917389D03*
Y910696D03*
Y904003D03*
Y924081D03*
Y934121D03*
Y930774D03*
Y947507D03*
Y940814D03*
Y964239D03*
Y977625D03*
X1731883Y970932D03*
X1731983Y991011D03*
Y984318D03*
Y1021129D03*
Y1024475D03*
Y1031168D03*
X1731683Y1044554D03*
Y1037861D03*
X1731983Y1051247D03*
X1731818Y1071326D03*
X1731883Y1064633D03*
X1731983Y1078018D03*
Y1094751D03*
Y1088058D03*
Y1081365D03*
X1731818Y1108137D03*
X1731983Y1101444D03*
Y1124869D03*
Y1118176D03*
Y1114829D03*
Y1144947D03*
Y1138255D03*
Y1131562D03*
Y1161680D03*
Y1154987D03*
Y1151640D03*
Y1175066D03*
Y1168373D03*
X1731818Y1181759D03*
X1731983Y1191798D03*
X1731818Y1188452D03*
X1731983Y1205184D03*
Y1198491D03*
Y1218569D03*
Y1211877D03*
Y1225262D03*
Y1241995D03*
Y1235302D03*
Y1228609D03*
X1745541Y960892D03*
Y957546D03*
Y967585D03*
Y1054593D03*
X1761683Y964239D03*
Y1021129D03*
Y1024475D03*
Y1051247D03*
X1775241Y816995D03*
Y810302D03*
Y833727D03*
Y823688D03*
Y827034D03*
Y840420D03*
Y960892D03*
Y957546D03*
Y967585D03*
Y1221916D03*
Y1215223D03*
Y1238648D03*
Y1228609D03*
Y1231955D03*
Y1245341D03*
X1791383Y813648D03*
Y806955D03*
Y820341D03*
Y830381D03*
Y823688D03*
Y837074D03*
Y964239D03*
Y1218570D03*
Y1211877D03*
Y1225263D03*
Y1241995D03*
Y1235302D03*
Y1228609D03*
X1804941Y960892D03*
Y957546D03*
Y967585D03*
X1821083Y964239D03*
G54D45*
X676508Y145866D03*
G54D34*
X238780Y1643661D03*
X230906Y1649173D03*
X238780Y1653110D03*
Y1657834D03*
X230906Y1653897D03*
Y1663346D03*
X238780Y1667283D03*
Y1672007D03*
X230906Y1668070D03*
X238780Y1695629D03*
X230906Y1691692D03*
Y1696417D03*
X238780Y1700354D03*
Y1723976D03*
Y1728700D03*
X230906Y1720039D03*
Y1724763D03*
Y1734212D03*
X254528Y1643661D03*
X246654Y1649173D03*
X254528Y1653110D03*
Y1657834D03*
X246654Y1653897D03*
Y1663346D03*
X254528Y1667283D03*
Y1672007D03*
X246654Y1668070D03*
X254528Y1695629D03*
X246654Y1691692D03*
Y1696417D03*
X254528Y1700354D03*
Y1723976D03*
Y1728700D03*
X246654Y1720039D03*
Y1724763D03*
Y1734212D03*
X270276Y1643661D03*
X262402Y1649173D03*
X270276Y1653110D03*
Y1657834D03*
X262402Y1653897D03*
Y1663346D03*
X270276Y1667283D03*
Y1672007D03*
X262402Y1668070D03*
X270276Y1695629D03*
X262402Y1691692D03*
Y1696417D03*
X270276Y1700354D03*
Y1723976D03*
Y1728700D03*
X262402Y1720039D03*
Y1724763D03*
Y1734212D03*
X286024Y1643661D03*
X278150Y1649173D03*
X286024Y1653110D03*
Y1657834D03*
X278150Y1653897D03*
Y1663346D03*
X286024Y1667283D03*
Y1672007D03*
X278150Y1668070D03*
X286024Y1695629D03*
X278150Y1691692D03*
Y1696417D03*
X286024Y1700354D03*
Y1723976D03*
Y1728700D03*
X278150Y1720039D03*
Y1724763D03*
Y1734212D03*
X305709Y1672007D03*
X297835Y1691692D03*
Y1696417D03*
X305709Y1695629D03*
Y1700354D03*
X297835Y1720039D03*
Y1724763D03*
X305709Y1723976D03*
Y1728700D03*
X297835Y1734212D03*
X321457Y1672007D03*
X313583Y1691692D03*
Y1696417D03*
X321457Y1695629D03*
Y1700354D03*
X313583Y1720039D03*
Y1724763D03*
X321457Y1723976D03*
Y1728700D03*
X313583Y1734212D03*
X337205Y1672007D03*
X329331Y1691692D03*
Y1696417D03*
X337205Y1695629D03*
Y1700354D03*
X329331Y1720039D03*
Y1724763D03*
X337205Y1723976D03*
Y1728700D03*
X329331Y1734212D03*
X352953Y1672007D03*
X345079Y1691692D03*
Y1696417D03*
X352953Y1695629D03*
Y1700354D03*
X345079Y1720039D03*
Y1724763D03*
X352953Y1723976D03*
Y1728700D03*
X345079Y1734212D03*
X495079Y1677519D03*
Y1682244D03*
Y1705866D03*
Y1710590D03*
Y1734212D03*
X502953Y1672007D03*
X510827Y1677519D03*
X502953Y1681456D03*
X510827Y1682244D03*
X502953Y1686180D03*
X510827Y1705866D03*
X502953Y1709803D03*
X510827Y1710590D03*
X502953Y1714527D03*
X510827Y1734212D03*
X518701Y1672007D03*
X534449D03*
X526575Y1677519D03*
X518701Y1681456D03*
X526575Y1682244D03*
X534449Y1681456D03*
X518701Y1686180D03*
X534449D03*
X526575Y1705866D03*
X518701Y1709803D03*
X526575Y1710590D03*
X534449Y1709803D03*
X518701Y1714527D03*
X534449D03*
X526575Y1734212D03*
X550197Y1672007D03*
X542323Y1677519D03*
Y1682244D03*
X550197Y1681456D03*
Y1686180D03*
X542323Y1705866D03*
Y1710590D03*
X550197Y1709803D03*
Y1714527D03*
X542323Y1734212D03*
X562008Y1677519D03*
Y1682244D03*
Y1705866D03*
Y1710590D03*
Y1734212D03*
X569882Y1672007D03*
X577756Y1677519D03*
X569882Y1681456D03*
X577756Y1682244D03*
X569882Y1686180D03*
X577756Y1705866D03*
X569882Y1709803D03*
X577756Y1710590D03*
X569882Y1714527D03*
X577756Y1734212D03*
X585630Y1672007D03*
X593504Y1677519D03*
X585630Y1681456D03*
X593504Y1682244D03*
X585630Y1686180D03*
X593504Y1705866D03*
X585630Y1709803D03*
X593504Y1710590D03*
X585630Y1714527D03*
X593504Y1734212D03*
X601378Y1672007D03*
X609252Y1677519D03*
X601378Y1681456D03*
X609252Y1682244D03*
X601378Y1686180D03*
X609252Y1705866D03*
X601378Y1709803D03*
X609252Y1710590D03*
X601378Y1714527D03*
X609252Y1734212D03*
X617126Y1672007D03*
Y1681456D03*
Y1686180D03*
Y1709803D03*
Y1714527D03*
X1246654Y1672007D03*
X1238780Y1691692D03*
Y1696417D03*
X1246654Y1695629D03*
Y1700354D03*
X1238780Y1720039D03*
Y1724763D03*
X1246654Y1723976D03*
Y1728700D03*
X1238780Y1734212D03*
X1262402Y1672007D03*
X1254528Y1691692D03*
Y1696417D03*
X1262402Y1695629D03*
Y1700354D03*
X1254528Y1720039D03*
Y1724763D03*
X1262402Y1723976D03*
Y1728700D03*
X1254528Y1734212D03*
X1278150Y1672007D03*
X1270276Y1691692D03*
Y1696417D03*
X1278150Y1695629D03*
Y1700354D03*
X1270276Y1720039D03*
Y1724763D03*
X1278150Y1723976D03*
Y1728700D03*
X1270276Y1734212D03*
X1293898Y1672007D03*
X1286024Y1691692D03*
Y1696417D03*
X1293898Y1695629D03*
Y1700354D03*
X1286024Y1720039D03*
Y1724763D03*
X1293898Y1723976D03*
Y1728700D03*
X1286024Y1734212D03*
X1313583Y1672007D03*
X1305709Y1691692D03*
Y1696417D03*
X1313583Y1695629D03*
Y1700354D03*
X1305709Y1720039D03*
Y1724763D03*
X1313583Y1723976D03*
Y1728700D03*
X1305709Y1734212D03*
X1329331Y1672007D03*
X1321457Y1691692D03*
Y1696417D03*
X1329331Y1695629D03*
Y1700354D03*
X1321457Y1720039D03*
Y1724763D03*
X1329331Y1723976D03*
Y1728700D03*
X1321457Y1734212D03*
X1345079Y1672007D03*
X1337205Y1691692D03*
Y1696417D03*
X1345079Y1695629D03*
Y1700354D03*
X1337205Y1720039D03*
Y1724763D03*
X1345079Y1723976D03*
Y1728700D03*
X1337205Y1734212D03*
X1360827Y1672007D03*
X1352953Y1691692D03*
Y1696417D03*
X1360827Y1695629D03*
Y1700354D03*
X1352953Y1720039D03*
Y1724763D03*
X1360827Y1723976D03*
Y1728700D03*
X1352953Y1734212D03*
X1510827Y1672007D03*
X1502953Y1677519D03*
Y1682244D03*
X1510827Y1681456D03*
Y1686180D03*
X1502953Y1705866D03*
Y1710590D03*
X1510827Y1709803D03*
Y1714527D03*
X1502953Y1734212D03*
X1526575Y1672007D03*
X1518701Y1677519D03*
Y1682244D03*
X1526575Y1681456D03*
Y1686180D03*
X1518701Y1705866D03*
Y1710590D03*
X1526575Y1709803D03*
Y1714527D03*
X1518701Y1734212D03*
X1542323Y1672007D03*
X1534449Y1677519D03*
Y1682244D03*
X1542323Y1681456D03*
Y1686180D03*
X1534449Y1705866D03*
Y1710590D03*
X1542323Y1709803D03*
Y1714527D03*
X1534449Y1734212D03*
X1558071Y1672007D03*
X1550197Y1677519D03*
Y1682244D03*
X1558071Y1681456D03*
Y1686180D03*
X1550197Y1705866D03*
Y1710590D03*
X1558071Y1709803D03*
Y1714527D03*
X1550197Y1734212D03*
X1569882Y1677519D03*
Y1682244D03*
Y1705866D03*
Y1710590D03*
Y1734212D03*
X1577756Y1672007D03*
X1585630Y1677519D03*
X1577756Y1681456D03*
X1585630Y1682244D03*
X1577756Y1686180D03*
X1585630Y1705866D03*
X1577756Y1709803D03*
X1585630Y1710590D03*
X1577756Y1714527D03*
X1585630Y1734212D03*
X1593504Y1672007D03*
X1601378Y1677519D03*
X1593504Y1681456D03*
X1601378Y1682244D03*
X1593504Y1686180D03*
X1601378Y1705866D03*
X1593504Y1709803D03*
X1601378Y1710590D03*
X1593504Y1714527D03*
X1601378Y1734212D03*
X1609252Y1672007D03*
X1617126Y1677519D03*
X1609252Y1681456D03*
X1617126Y1682244D03*
X1609252Y1686180D03*
X1617126Y1705866D03*
X1609252Y1709803D03*
X1617126Y1710590D03*
X1609252Y1714527D03*
X1617126Y1734212D03*
X1625000Y1672007D03*
Y1681456D03*
Y1686180D03*
Y1709803D03*
Y1714527D03*
G54D70*
X1886720Y1001463D03*
X1876720D03*
X1875836Y1303980D03*
X1885836D03*
X1886211Y1364167D03*
X1876211D03*
X1876165Y1669023D03*
X1886165D03*
X1897608Y1001506D03*
X1898086Y1305044D03*
X1897682Y1364479D03*
X1897402Y1670072D03*
X1907608Y1001506D03*
X1908086Y1305044D03*
X1907682Y1364479D03*
X1907402Y1670072D03*
X1935200Y1362732D03*
X1925200D03*
X1924695Y1670036D03*
X1934695D03*
X1946178Y1362781D03*
X1945484Y1670313D03*
X1967697Y1362790D03*
X1956178Y1362781D03*
X1966555Y1669946D03*
X1955484Y1670313D03*
X1977697Y1362790D03*
X1976555Y1669946D03*
X1988618Y1363081D03*
X1998618D03*
X1998147Y1669691D03*
X1988147D03*
G54D17*
X45812Y451602D03*
X61157Y69340D03*
X61470Y84622D03*
X62812Y412708D03*
X62813Y415750D03*
X49212Y451602D03*
X64557Y69340D03*
X72157Y75340D03*
X75557D03*
X64870Y84622D03*
X78120Y1515436D03*
Y1518836D03*
X64410Y1599102D03*
Y1602502D03*
X86557Y69340D03*
X83157D03*
X94157Y75340D03*
X90998Y1518937D03*
Y1515537D03*
X108557Y69340D03*
X105157D03*
X97557Y75340D03*
X127157Y69340D03*
X116157Y75340D03*
X119557D03*
X130557Y69340D03*
X138157Y75340D03*
X141557D03*
X152557Y69340D03*
X149157D03*
X175761D03*
X172361D03*
X161361Y75340D03*
X164761D03*
X183361D03*
X186761D03*
X197761Y69340D03*
X194361D03*
X205495Y75340D03*
X208895D03*
X194197Y1614292D03*
X197597D03*
X206257D03*
X194197Y1602380D03*
X197597D03*
X206257D03*
X219895Y69340D03*
X216495D03*
X209657Y1614292D03*
X218317D03*
X221717D03*
X209657Y1602380D03*
X218317D03*
X221717D03*
X227495Y75340D03*
X230895D03*
X230377Y1614292D03*
X233777D03*
X230377Y1602380D03*
X233777D03*
X242437Y1614292D03*
X254497D03*
X245837D03*
X242437Y1602380D03*
X254497D03*
X245837D03*
X266557Y1614292D03*
X257897D03*
X269957D03*
X266557Y1602380D03*
X257897D03*
X269957D03*
X278617Y1614292D03*
X282017D03*
X278617Y1602380D03*
X282017D03*
X290677Y1614292D03*
X302737D03*
X294077D03*
X306137D03*
X290677Y1602380D03*
X302737D03*
X294077D03*
X306137D03*
X314797Y1614292D03*
X318197D03*
X314797Y1602380D03*
X318197D03*
X330257Y1614292D03*
X338917D03*
X326857D03*
X330257Y1602380D03*
X338917D03*
X326857D03*
X350977Y1614292D03*
X342317D03*
X354377D03*
X350977Y1602380D03*
X342317D03*
X354377D03*
X363037Y1614292D03*
X366437D03*
X363037Y1602380D03*
X366437D03*
X375097Y1614292D03*
X378497D03*
X375097Y1602380D03*
X378497D03*
X478351Y1614292D03*
X481751D03*
X478351Y1602380D03*
X481751D03*
X490411Y1614292D03*
X493811D03*
X490411Y1602380D03*
X493811D03*
X514531Y1614292D03*
X502471D03*
X517931D03*
X505871D03*
X514531Y1602380D03*
X502471D03*
X517931D03*
X505871D03*
X519764Y40328D03*
X523164D03*
X519742Y71436D03*
X523142D03*
X526591Y1614292D03*
X529991D03*
X526591Y1602380D03*
X529991D03*
X538651Y1614292D03*
X542051D03*
X538651Y1602380D03*
X542051D03*
X555175Y71436D03*
X558575D03*
X562771Y1614292D03*
X550711D03*
X566171D03*
X554111D03*
X562771Y1602380D03*
X550711D03*
X566171D03*
X554111D03*
X574831Y1614292D03*
X578231D03*
X574831Y1602380D03*
X578231D03*
X598951Y1614292D03*
X586891D03*
X590291D03*
X598951Y1602380D03*
X586891D03*
X590291D03*
X613970Y188752D03*
X611011Y1614292D03*
X614411D03*
X602351D03*
X611011Y1602380D03*
X614411D03*
X602351D03*
X617370Y188752D03*
X630040D03*
X626640D03*
X623071Y1614292D03*
X626471D03*
X623071Y1602380D03*
X626471D03*
X647191Y1614292D03*
X635131D03*
X638531D03*
X647191Y1602380D03*
X635131D03*
X638531D03*
X656439Y47264D03*
X659839D03*
X662651Y1614292D03*
X659251D03*
X650591D03*
X662651Y1602380D03*
X659251D03*
X650591D03*
X723041Y-13200D03*
Y-9800D03*
Y-19800D03*
Y-23200D03*
X840001Y6800D03*
Y20200D03*
Y16800D03*
Y10200D03*
X902350Y208294D03*
X907470Y211980D03*
X902350Y204894D03*
X907470Y215380D03*
X902350Y219068D03*
X907470Y226154D03*
X902350Y222468D03*
X907470Y229554D03*
X953970Y208275D03*
X947496Y215397D03*
X953970Y204875D03*
X947496Y211997D03*
X957156Y227163D03*
X947496Y226135D03*
X957156Y230563D03*
X947496Y229535D03*
X980899Y-13200D03*
Y-9800D03*
Y-19800D03*
Y-23200D03*
Y6800D03*
Y20200D03*
Y16800D03*
Y10200D03*
X1032433Y-29811D03*
Y-33211D03*
Y-23211D03*
Y-19811D03*
Y-13211D03*
Y-9811D03*
Y-3211D03*
Y189D03*
X1156770Y638192D03*
X1153370D03*
X1161860Y642112D03*
X1165260D03*
X1173220Y636052D03*
X1169820D03*
X1183360Y642062D03*
X1186760D03*
X1196772Y1578182D03*
X1200172D03*
X1196772Y1590094D03*
X1200172D03*
X1212232Y1578182D03*
X1208832D03*
X1212232Y1590094D03*
X1208832D03*
X1220892Y1578182D03*
X1232952D03*
X1224292D03*
X1220892Y1590094D03*
X1232952D03*
X1224292D03*
X1245012Y1578182D03*
X1236352D03*
X1248412D03*
X1245012Y1590094D03*
X1236352D03*
X1248412D03*
X1257072Y1578182D03*
X1260472D03*
X1257072Y1590094D03*
X1260472D03*
X1269132Y1578182D03*
X1281192D03*
X1272532D03*
X1269132Y1590094D03*
X1281192D03*
X1272532D03*
X1290291Y-29811D03*
Y-33211D03*
Y-23211D03*
Y-19811D03*
Y-13211D03*
Y-9811D03*
Y-3211D03*
Y189D03*
X1293252Y1578182D03*
X1284592D03*
X1296652D03*
X1293252Y1590094D03*
X1284592D03*
X1296652D03*
X1305312Y1578182D03*
X1308712D03*
X1305312Y1590094D03*
X1308712D03*
X1317372Y1578182D03*
X1320772D03*
X1329432D03*
X1317372Y1590094D03*
X1320772D03*
X1329432D03*
X1341752Y-29811D03*
Y-33211D03*
Y-19811D03*
Y-23211D03*
Y-9811D03*
Y-13211D03*
Y189D03*
Y-3211D03*
X1344684Y280259D03*
X1332832Y1578182D03*
X1341492D03*
X1344892D03*
X1332832Y1590094D03*
X1341492D03*
X1344892D03*
X1348084Y280259D03*
X1358624Y284644D03*
X1355224D03*
X1353552Y1578182D03*
X1356952D03*
X1353552Y1590094D03*
X1356952D03*
X1380522Y260236D03*
Y263636D03*
X1368524Y282744D03*
X1365124D03*
X1378306Y657608D03*
X1374668Y659708D03*
X1378306Y669608D03*
X1374668Y671708D03*
Y683708D03*
X1378306Y681608D03*
X1374668Y695708D03*
X1378306Y693608D03*
Y705608D03*
X1374668Y707708D03*
Y719708D03*
X1378306Y717608D03*
X1365612Y1578182D03*
X1377672D03*
X1369012D03*
X1365612Y1590094D03*
X1377672D03*
X1369012D03*
X1384002Y197668D03*
X1389256D03*
X1380602D03*
X1392656D03*
X1380638Y245694D03*
X1386630Y238651D03*
X1380638Y249094D03*
X1386630Y242051D03*
X1388754Y253803D03*
Y257203D03*
X1386273Y268670D03*
Y272070D03*
X1393206Y664708D03*
X1389568Y662608D03*
X1393206Y679208D03*
X1389568Y677108D03*
X1393206Y693708D03*
X1389568Y691608D03*
Y706108D03*
X1393206Y708208D03*
X1393199Y722708D03*
X1389561Y720608D03*
X1385338Y735098D03*
X1388976Y737198D03*
X1381072Y1578182D03*
Y1590094D03*
X1412284Y171696D03*
X1398006Y197668D03*
X1406786D03*
X1401406D03*
X1410186D03*
X1407420Y220018D03*
X1410820D03*
X1404385Y240929D03*
X1400985D03*
X1415684Y171696D03*
X1436060Y220018D03*
X1432660D03*
X1457176Y656992D03*
X1460814Y654892D03*
Y666892D03*
X1457176Y668992D03*
X1460814Y678892D03*
X1457176Y680992D03*
X1460814Y690892D03*
X1457176Y704992D03*
Y692992D03*
X1460814Y702892D03*
X1457176Y716992D03*
X1460814Y714892D03*
X1472076Y657392D03*
Y671892D03*
X1475714Y659492D03*
Y673992D03*
X1472076Y686392D03*
X1475714Y688492D03*
X1472076Y700892D03*
X1475714Y702992D03*
X1472076Y715392D03*
X1475714Y717492D03*
X1468876Y728392D03*
X1472514Y730492D03*
X1467595Y1614292D03*
X1470995D03*
X1467595Y1602380D03*
X1470995D03*
X1482650Y-29811D03*
Y-33211D03*
Y-19811D03*
Y-23211D03*
Y-9811D03*
Y-13211D03*
Y189D03*
Y-3211D03*
X1491715Y1614292D03*
X1479655D03*
X1483055D03*
X1491715Y1602380D03*
X1479655D03*
X1483055D03*
X1503775Y1614292D03*
X1507175D03*
X1495115D03*
X1503775Y1602380D03*
X1507175D03*
X1495115D03*
X1515835Y1614292D03*
X1519235D03*
X1515835Y1602380D03*
X1519235D03*
X1538996Y69297D03*
X1535596D03*
X1527895Y1614292D03*
X1539955D03*
X1531295D03*
X1527895Y1602380D03*
X1539955D03*
X1531295D03*
X1557596Y69297D03*
X1546596Y75297D03*
X1549996D03*
X1552015Y1614292D03*
X1555415D03*
X1543355D03*
X1552015Y1602380D03*
X1555415D03*
X1543355D03*
X1560996Y69297D03*
X1568596Y75297D03*
X1571996D03*
X1564075Y1614292D03*
X1567475D03*
X1564075Y1602380D03*
X1567475D03*
X1582996Y69297D03*
X1579596D03*
X1590596Y75297D03*
X1588195Y1614292D03*
X1576135D03*
X1591595D03*
X1579535D03*
X1588195Y1602380D03*
X1576135D03*
X1591595D03*
X1579535D03*
X1604996Y69297D03*
X1601596D03*
X1593996Y75297D03*
X1600255Y1614292D03*
X1603655D03*
X1600255Y1602380D03*
X1603655D03*
X1623596Y69297D03*
X1612596Y75297D03*
X1615996D03*
X1612315Y1614292D03*
X1615715D03*
X1612315Y1602380D03*
X1615715D03*
X1626996Y69297D03*
X1635800Y75297D03*
X1639200D03*
X1636435Y1614292D03*
X1624375D03*
X1639835D03*
X1627775D03*
X1636435Y1602380D03*
X1624375D03*
X1639835D03*
X1627775D03*
X1650200Y69297D03*
X1646800D03*
X1651895Y1614292D03*
X1648495D03*
X1651895Y1602380D03*
X1648495D03*
X1672200Y69297D03*
X1668800D03*
X1657800Y75297D03*
X1661200D03*
X1679934D03*
X1683334D03*
X1694334Y69297D03*
X1690934D03*
X1705334Y75297D03*
X1701934D03*
G54D40*
X338042Y849978D03*
X337778Y854584D03*
X335924Y857789D03*
X334079Y880219D03*
X332228Y877014D03*
X335928D03*
X334078Y893036D03*
X335928Y896240D03*
X332229Y902649D03*
X332228Y915466D03*
X335928D03*
X332229Y921875D03*
Y941100D03*
X332228Y934692D03*
X335928D03*
X334079Y957122D03*
X335928Y953917D03*
X332228D03*
X332229Y973143D03*
X334079Y976347D03*
X331284Y978814D03*
X335349Y985939D03*
X338210Y996480D03*
X332661Y1006093D03*
X338211Y1002888D03*
X332661Y1025318D03*
Y1018910D03*
X338211Y1015705D03*
Y1022114D03*
X332661Y1044544D03*
X338211Y1041340D03*
X334511D03*
X338211Y1060565D03*
X333834Y1062790D03*
X329632Y1092168D03*
X336360Y1082995D03*
X338211Y1111834D03*
Y1105426D03*
X335344Y1097289D03*
X338211Y1124651D03*
X336361Y1115039D03*
Y1127856D03*
Y1121447D03*
X345178Y854584D03*
X347028Y844971D03*
X345178Y848176D03*
X350727Y844971D03*
X347027Y851380D03*
X343327D03*
X354429D03*
X341478Y854584D03*
X339628Y857789D03*
X347029Y864197D03*
Y857789D03*
X348878Y854584D03*
X345179Y860993D03*
X343327Y857789D03*
X352579Y854584D03*
X354429Y864197D03*
X350729D03*
X341479Y867401D03*
X348879D03*
X352579D03*
X347029Y870606D03*
X354429Y877014D03*
X339629D03*
X341479Y873810D03*
X345179Y880219D03*
Y873810D03*
X343329Y877014D03*
X352579Y880219D03*
X350729Y877014D03*
X339629Y883423D03*
X347029D03*
X350729D03*
Y870606D03*
X354429D03*
X352578Y873810D03*
X354429Y883423D03*
X347029Y877014D03*
X348878Y880219D03*
X352578Y899445D03*
X339629Y896240D03*
Y889832D03*
X348879Y886627D03*
X347029Y889832D03*
X345179Y893036D03*
X343328Y896240D03*
X352578Y893036D03*
Y886627D03*
X345179Y899445D03*
X348878Y905853D03*
X352578D03*
X341479Y912262D03*
X341478Y905853D03*
X347029Y909057D03*
Y902649D03*
X345179Y912262D03*
X352578D03*
X339629Y915466D03*
X343329D03*
X348878Y925079D03*
X352578D03*
Y918670D03*
X341478Y925079D03*
X347029Y928283D03*
Y921875D03*
X345179Y918670D03*
X341479Y931488D03*
X345179D03*
X352578D03*
X341478Y944304D03*
X352578D03*
X347029Y941100D03*
X348878Y944304D03*
X347029Y947509D03*
X352578Y937896D03*
X339629Y934692D03*
X345179Y937896D03*
X343328Y934692D03*
X348878Y963530D03*
X347029Y960326D03*
X343328D03*
X343329Y966735D03*
X339629D03*
Y953917D03*
X343328D03*
X345179Y957122D03*
X352578D03*
X347029Y966735D03*
X352578Y963530D03*
X341479Y950713D03*
X345179D03*
X352578D03*
X354428Y973143D03*
X339629D03*
X345179Y976347D03*
Y969939D03*
X350729Y973143D03*
X347029Y979552D03*
X352579Y976347D03*
X352578Y969939D03*
X348878Y982756D03*
X352578D03*
X339629Y979552D03*
X343329Y973143D03*
X341911Y1009297D03*
Y1002888D03*
X347461Y999684D03*
X345611Y1009297D03*
X343761Y1006093D03*
X345611Y1002888D03*
X351162Y1006093D03*
X354861D03*
X353011Y1009297D03*
Y1002888D03*
X347461Y1012501D03*
X343761Y999684D03*
X353011Y1028523D03*
Y1015705D03*
X341911Y1022114D03*
Y1015705D03*
X349311D03*
X347461Y1018910D03*
X345611Y1028523D03*
X343761Y1018910D03*
X345611Y1022114D03*
Y1015705D03*
X353011Y1022114D03*
X343761Y1031727D03*
X347461D03*
X353011Y1034931D03*
Y1047749D03*
X341911Y1041340D03*
X343761Y1038136D03*
X349311Y1034931D03*
X347461Y1038136D03*
X345611Y1041340D03*
X343761Y1044544D03*
X353011Y1041340D03*
X345611Y1047749D03*
X349311Y1054157D03*
X353011Y1060565D03*
Y1054157D03*
X343761Y1057361D03*
Y1050952D03*
X347461D03*
Y1057361D03*
X345611Y1060565D03*
X343761Y1063770D03*
X353011Y1073383D03*
X343761Y1076587D03*
Y1070178D03*
X340062Y1076587D03*
X347461D03*
Y1070178D03*
X349312Y1073383D03*
X345611Y1066974D03*
X353011D03*
X345611Y1079791D03*
X341911D03*
X353011D03*
Y1086200D03*
X349310Y1092609D03*
X347461Y1089404D03*
X345610Y1086200D03*
X343760Y1082995D03*
X343707Y1091513D03*
X340060Y1082995D03*
X353011Y1092608D03*
X340061Y1095813D03*
X347461Y1108630D03*
X354861D03*
X353011Y1099017D03*
X340061Y1108630D03*
Y1102221D03*
X349311Y1099017D03*
X347461Y1102221D03*
X343761D03*
X340061Y1115039D03*
X349311Y1124651D03*
X349312Y1118243D03*
X345611D03*
X343761Y1115039D03*
X341911Y1124651D03*
X354861Y1115039D03*
X351161Y1121447D03*
Y1115039D03*
X341912Y1118243D03*
X340061Y1127856D03*
X343761D03*
X347461Y1121447D03*
X340061D03*
X343761D03*
X347461Y1127856D03*
X345611Y1124651D03*
Y1137469D03*
Y1131060D03*
X349311D03*
X343761Y1134264D03*
X353011Y1137469D03*
Y1131060D03*
X341911D03*
X359979Y841467D03*
X367379D03*
X365529Y851380D03*
X361829D03*
X358129D03*
X369229D03*
X365529Y864197D03*
X361829D03*
X359979Y854584D03*
X358129Y864197D03*
X369229D03*
X367379Y854584D03*
X359979Y867401D03*
X367379D03*
X371078D03*
X356278D03*
X363678D03*
X365529Y877014D03*
X361829D03*
X359979Y880219D03*
X358129Y877014D03*
X369229D03*
X367379Y880219D03*
X358129Y870606D03*
X361829D03*
X365529D03*
X359978Y873810D03*
X367378D03*
X369229Y870606D03*
X356278Y880219D03*
X358129Y883423D03*
X363678Y880219D03*
X365529Y883423D03*
X371078Y880219D03*
X361829Y883423D03*
X369229D03*
X356278Y886627D03*
X365529Y896240D03*
Y889832D03*
X361828Y896240D03*
X361829Y889832D03*
X359979Y893036D03*
X358128Y889832D03*
X369229Y896240D03*
Y889832D03*
X359979Y899445D03*
X371078D03*
X363679Y893036D03*
X367379D03*
X359978Y886627D03*
X367378D03*
X356278Y905853D03*
X365529Y909057D03*
Y902649D03*
X359978Y912262D03*
X358128Y909057D03*
X358129Y902649D03*
X371079Y912262D03*
X365529Y915466D03*
X361828D03*
X369229D03*
X356279Y925079D03*
X365529Y928283D03*
Y921875D03*
X359979Y918670D03*
X358128Y928283D03*
X358129Y921875D03*
X371078Y918670D03*
X359978Y931488D03*
X371079D03*
X358128Y947509D03*
X358129Y941100D03*
X356279Y944304D03*
X365529Y947509D03*
Y941100D03*
Y934691D03*
X361828D03*
X359979Y937896D03*
X369229Y934691D03*
X371078Y937896D03*
X356279Y963530D03*
X358129Y960326D03*
X359979Y957122D03*
X358128Y966735D03*
X361829Y953917D03*
X359978Y950713D03*
X371078Y957122D03*
X371079Y950713D03*
X365529Y953917D03*
X367378Y963530D03*
X363679D03*
X365529Y960326D03*
X365528Y966735D03*
X369229Y953917D03*
X359979Y976347D03*
X358129Y979552D03*
X359978Y969939D03*
X361828Y973143D03*
X356279Y982756D03*
X371078Y976347D03*
X371079Y969939D03*
X369229Y973143D03*
X365529Y979552D03*
Y973143D03*
X365962Y999684D03*
Y1006093D03*
X362261D03*
X360411Y1009297D03*
X360412Y1002888D03*
X358562Y999684D03*
X369662Y1006093D03*
X371512Y1009297D03*
X365961Y1012501D03*
X358561D03*
X367811Y1002888D03*
X356712Y1015705D03*
X365962Y1025318D03*
Y1018910D03*
X364112Y1015705D03*
X360411Y1028523D03*
X362261Y1025318D03*
X360412Y1022114D03*
X358562Y1018910D03*
X369662Y1025318D03*
X367811Y1015705D03*
X371511Y1028523D03*
Y1022114D03*
X365962Y1031727D03*
X358561D03*
X356712Y1034931D03*
X365962Y1044544D03*
Y1038136D03*
X362261Y1044544D03*
X360412Y1041340D03*
X358562Y1038136D03*
X369662Y1044544D03*
X371511Y1041340D03*
X360411Y1047749D03*
X371511D03*
X356712Y1054157D03*
X365962Y1057361D03*
Y1050952D03*
X360412Y1060565D03*
X358562Y1057361D03*
X358561Y1050952D03*
X371511Y1060565D03*
X365962Y1063770D03*
X362261D03*
X369662D03*
X356712Y1073383D03*
X365962Y1070178D03*
Y1076587D03*
X360411Y1066974D03*
X358561Y1070178D03*
X358562Y1076587D03*
X371512Y1066974D03*
X360412Y1079791D03*
X371511D03*
X365962Y1089404D03*
Y1082995D03*
X362261D03*
X360411Y1086200D03*
X358561Y1089404D03*
X356712Y1092608D03*
X369662Y1082995D03*
X371512Y1086200D03*
X365962Y1095813D03*
X358561D03*
X365962Y1102221D03*
X362262D03*
X360411Y1099017D03*
X356711Y1105426D03*
Y1099017D03*
X371512Y1105426D03*
Y1099017D03*
X364112Y1111834D03*
X356712D03*
X371512D03*
X358561Y1108630D03*
X360412Y1111834D03*
X364112Y1105426D03*
X369661Y1108630D03*
X362261D03*
X365961D03*
X367812Y1111834D03*
X364111Y1118243D03*
X362261Y1115039D03*
X360411Y1118243D03*
X356711D03*
X367811D03*
X371511D03*
X365962Y1127856D03*
X358561D03*
X365961Y1115039D03*
X358561D03*
X369661D03*
X365961Y1140973D03*
X364112Y1131060D03*
X360412D03*
X358561Y1140973D03*
X356712Y1131060D03*
X367811D03*
X371511D03*
X382179Y841467D03*
X374779D03*
X380329Y851380D03*
X376629D03*
X372929D03*
X384029D03*
X387729D03*
X382179Y854584D03*
X380329Y864197D03*
X376629D03*
X374779Y854584D03*
X372929Y864197D03*
X384029D03*
X387729D03*
X382179Y867401D03*
X374779D03*
X378478D03*
X385878D03*
X378478Y860993D03*
X385878D03*
X382179Y880219D03*
X380329Y877014D03*
X376629D03*
X374779Y880219D03*
X372929Y877014D03*
X384029D03*
X387729D03*
Y870606D03*
X372929D03*
X380329D03*
X374778Y873810D03*
X376629Y870606D03*
X382178Y873810D03*
X384029Y870606D03*
X372929Y883423D03*
X378478Y880219D03*
X380329Y883423D03*
X385878Y880219D03*
X387729Y883423D03*
X376629D03*
X384029D03*
X385878Y873810D03*
X380329Y889832D03*
X378479Y893036D03*
X376629Y889832D03*
X372929D03*
X384029D03*
X387729Y896240D03*
Y889832D03*
X378478Y899445D03*
X385879D03*
X374778Y886627D03*
X382178D03*
X385878D03*
X382179Y905853D03*
X378478Y912262D03*
Y905853D03*
X374778D03*
X372929Y909057D03*
X372928Y902649D03*
X385878Y912262D03*
X384028Y909057D03*
X384029Y902649D03*
X387728Y915466D03*
X387729Y909057D03*
Y902649D03*
X385878Y905853D03*
X382179Y925079D03*
X378478D03*
Y918670D03*
X374778Y925079D03*
X372929Y928283D03*
X372928Y921875D03*
X385879Y918670D03*
X384028Y928283D03*
X384029Y921875D03*
X378478Y931488D03*
X385878D03*
X387729Y921875D03*
Y928283D03*
X385878Y925079D03*
X384029Y941100D03*
X384028Y947509D03*
X374778Y944304D03*
X372929Y947509D03*
X372928Y941100D03*
X382179Y944304D03*
X378478D03*
Y937896D03*
X385879D03*
X387728Y934691D03*
X387729Y947509D03*
Y941100D03*
X385878Y944304D03*
X387729Y953917D03*
X372928Y960326D03*
X374778Y963530D03*
X372929Y966735D03*
X382179Y963530D03*
X378478D03*
Y957122D03*
X384029Y960326D03*
X385879Y957122D03*
X384028Y966735D03*
X385878Y950713D03*
X378478D03*
X387729Y960326D03*
Y966735D03*
X385878Y963530D03*
X387728Y973143D03*
X376629D03*
X380328D03*
X378479Y976347D03*
X378478Y969939D03*
X385879Y976347D03*
X384029Y979552D03*
X385878Y969939D03*
X374778Y982756D03*
X382179D03*
X378478D03*
X372928Y979552D03*
X385878Y982756D03*
X387729Y979552D03*
X376629D03*
X380329D03*
X374778Y976347D03*
X382178D03*
X372929Y973143D03*
X384029D03*
X375210Y996480D03*
X373361Y999684D03*
X378911Y1009297D03*
Y1002888D03*
X386311Y1009297D03*
X386312Y1002888D03*
X384462Y999684D03*
X373362Y1012501D03*
X384461D03*
X382612Y1015705D03*
X378911Y1028523D03*
Y1022114D03*
Y1015705D03*
X375211D03*
X373361Y1018910D03*
X386311Y1028523D03*
X386312Y1022114D03*
X384462Y1018910D03*
X373362Y1031727D03*
X384461D03*
X386311Y1015705D03*
X382612Y1034931D03*
X378911Y1041340D03*
Y1034931D03*
X375211D03*
X373361Y1038136D03*
X386312Y1041340D03*
X384462Y1038136D03*
X378911Y1047749D03*
X386311D03*
Y1034931D03*
X382612Y1054157D03*
X378911Y1060565D03*
Y1054157D03*
X375211D03*
X373361Y1057361D03*
X373362Y1050952D03*
X386312Y1060565D03*
X384462Y1057361D03*
X384461Y1050952D03*
X386311Y1054157D03*
X382612Y1073383D03*
X378911D03*
Y1066974D03*
X375211Y1073383D03*
X373361Y1076587D03*
X373362Y1070178D03*
X386311Y1066974D03*
X384462Y1076587D03*
X384461Y1070178D03*
X378911Y1079791D03*
X386311D03*
Y1073383D03*
X382611Y1092608D03*
X378911D03*
Y1086200D03*
X375211Y1092608D03*
X373362Y1089404D03*
X386311Y1086200D03*
X384461Y1089404D03*
X373362Y1095813D03*
X384462D03*
X386311Y1092608D03*
X375211Y1099017D03*
X380762Y1108630D03*
X378911Y1099017D03*
X377062Y1102221D03*
X373361Y1108630D03*
Y1102221D03*
X386312Y1099017D03*
X384462Y1102221D03*
X382611Y1118243D03*
X378911D03*
X377061Y1115039D03*
X375211Y1118243D03*
X373361Y1115039D03*
X386311Y1118243D03*
X384461Y1115039D03*
X380761Y1127856D03*
X373361D03*
X382611Y1131060D03*
X380761Y1140973D03*
X378911Y1131060D03*
X375211D03*
X373361Y1140973D03*
X386311Y1131060D03*
X396979Y841467D03*
X389579D03*
X398829Y851380D03*
X395129D03*
X391429D03*
X402529D03*
X398829Y864197D03*
X396979Y854584D03*
X395129Y864197D03*
X391429D03*
X389579Y854584D03*
X402529Y864197D03*
X396979Y867401D03*
X389579D03*
X400678D03*
X393278D03*
Y860993D03*
X398829Y877014D03*
X396979Y880219D03*
X395129Y877014D03*
X391429D03*
X389579Y880219D03*
X402529Y877014D03*
X391429Y870606D03*
X395129D03*
X402529D03*
X389578Y873810D03*
X396978D03*
X398829Y870606D03*
X393278Y880219D03*
X395129Y883423D03*
X400678Y880219D03*
X402529Y883423D03*
X391429D03*
X398829D03*
X393278Y873810D03*
X400678D03*
X398829Y889832D03*
X395129Y896240D03*
Y889832D03*
X391428Y896240D03*
X391429Y889832D03*
X389579Y893036D03*
X402529Y889832D03*
X396978Y899445D03*
X402529Y896240D03*
X400678Y899445D03*
X389578D03*
X393278D03*
X393279Y893036D03*
X396979D03*
X396978Y886627D03*
X389578D03*
X398829Y896240D03*
X400678Y893036D03*
X393278Y886627D03*
X400678D03*
X404378Y899445D03*
X398829Y909057D03*
X398828Y902649D03*
X396979Y912262D03*
X391429Y909057D03*
Y902649D03*
X395129Y915466D03*
X391429D03*
X400678Y905853D03*
X402529Y915466D03*
Y909057D03*
X389578Y912262D03*
X393278D03*
X395129Y909057D03*
Y902649D03*
X393278Y905853D03*
X389578D03*
X396978D03*
X406229Y915466D03*
X400678Y912262D03*
X402529Y902649D03*
X400678Y931488D03*
X402529Y928283D03*
Y921875D03*
X398829Y928283D03*
X398828Y921875D03*
X396978Y918670D03*
X391429Y928283D03*
Y921875D03*
X400678Y925079D03*
X396979Y931488D03*
X393278D03*
X395129Y928283D03*
X389578Y918670D03*
X395129Y921875D03*
X393278Y918670D03*
X389578Y931488D03*
X393278Y925079D03*
X389578D03*
X396978D03*
X398829Y934691D03*
X402529D03*
X398828Y941100D03*
X396978Y937896D03*
X395129Y934691D03*
X391429Y941100D03*
Y934691D03*
X400678Y937896D03*
X398829Y947509D03*
X391429D03*
X395129D03*
X389578Y937896D03*
X395129Y941100D03*
X393278Y937896D03*
Y944304D03*
X389578D03*
X396978D03*
X402529Y941100D03*
X400679Y944304D03*
X398828Y960326D03*
X396978Y957122D03*
X396979Y950713D03*
X395129Y953917D03*
X391429Y960326D03*
Y953917D03*
X400678Y957122D03*
X398829Y966735D03*
X391429D03*
X400678Y963530D03*
X389578Y957122D03*
X395129Y960326D03*
X393278Y957122D03*
X395129Y966735D03*
X389578Y950713D03*
X393278D03*
X396978Y963530D03*
X393278D03*
X389578D03*
X402529Y966735D03*
Y960326D03*
X398828Y979552D03*
X396978Y976347D03*
X396979Y969939D03*
X395129Y973143D03*
X391429Y979552D03*
Y973143D03*
X400678Y982756D03*
Y969939D03*
X393278Y982756D03*
X389578D03*
X396978D03*
X393278Y976347D03*
X395129Y979552D03*
X389579Y976347D03*
X389578Y969939D03*
X393278D03*
X397412Y1009297D03*
X397411Y1002888D03*
X395562Y1006093D03*
X391862D03*
Y999684D03*
X388161Y1006093D03*
X401111Y1002888D03*
X399262Y1012501D03*
X391861D03*
X399262Y1006093D03*
X402962D03*
X399262Y999684D03*
X402962D03*
X388162Y1012501D03*
X395562D03*
X390011Y1009297D03*
X393711D03*
X401111D03*
X402962Y1012501D03*
Y1031727D03*
X399261Y1018910D03*
X397411Y1028523D03*
Y1022114D03*
X395562Y1025318D03*
X393711Y1015705D03*
X391862Y1025318D03*
Y1018910D03*
X390012Y1015705D03*
X388161Y1025318D03*
X399262Y1031727D03*
X391862D03*
X397411Y1015705D03*
X388162Y1031727D03*
X390011Y1028523D03*
X395562Y1031727D03*
X393711Y1028523D03*
X390011Y1022114D03*
X388162Y1018910D03*
X393711Y1022114D03*
X395562Y1018910D03*
X401111Y1028523D03*
Y1015705D03*
X399261Y1038136D03*
X397411Y1041340D03*
X395562Y1044544D03*
X391862D03*
Y1038136D03*
X388161Y1044544D03*
X397411Y1047749D03*
X390011Y1041340D03*
X388162Y1038136D03*
X393711Y1041340D03*
X395562Y1038136D03*
X390011Y1047749D03*
X393711D03*
Y1034931D03*
X390011D03*
X397411D03*
X401111Y1047749D03*
X402962Y1038136D03*
X406662Y1057361D03*
X399261D03*
X399262Y1050952D03*
X397411Y1060565D03*
X391862Y1057361D03*
Y1050952D03*
X395562Y1063770D03*
X391862D03*
X388161D03*
X390011Y1060565D03*
X388162Y1057361D03*
X393711Y1060565D03*
X395562Y1057361D03*
X388162Y1050952D03*
X395562D03*
X393711Y1054157D03*
X390011D03*
X397411D03*
X402962Y1057361D03*
Y1063770D03*
X401113Y1060565D03*
X399262Y1063770D03*
X401111Y1054157D03*
X402962Y1050952D03*
Y1076587D03*
Y1070178D03*
X399261Y1076587D03*
X399262Y1070178D03*
X397412Y1066974D03*
X391862Y1076587D03*
Y1070178D03*
X401111Y1073383D03*
X397411Y1079791D03*
X401111D03*
X390011D03*
X388162Y1076587D03*
X393711Y1079791D03*
X395562Y1076587D03*
X388162Y1070178D03*
X390011Y1066974D03*
X395562Y1070178D03*
X393711Y1066974D03*
Y1073383D03*
X390011D03*
X397411D03*
X401112Y1066974D03*
X399262Y1089404D03*
X397412Y1086200D03*
X395562Y1082995D03*
X391862Y1089404D03*
Y1082995D03*
X388161D03*
X401112Y1092608D03*
X401111Y1086200D03*
X399261Y1095813D03*
X391862D03*
X402962D03*
X395562D03*
X388162Y1089404D03*
X390011Y1086200D03*
X395562Y1089404D03*
X393711Y1086200D03*
X388162Y1095813D03*
X393711Y1092608D03*
X390011D03*
X397411D03*
X399262Y1102221D03*
X397412Y1099017D03*
X395562Y1102221D03*
X390011Y1105426D03*
X388162Y1108630D03*
Y1102221D03*
X401111Y1105426D03*
X397411Y1111834D03*
X390011D03*
X393711Y1099017D03*
X390011D03*
X401111D03*
X391862Y1108630D03*
X393711Y1111834D03*
X397411Y1105426D03*
X402962Y1108630D03*
Y1102221D03*
X395562Y1108630D03*
X399262D03*
X401111Y1111834D03*
X397411Y1118243D03*
X395561Y1115039D03*
X393711Y1118243D03*
X390011D03*
X388161Y1115039D03*
X401111Y1118243D03*
X395561Y1127856D03*
X388161D03*
X402961D03*
X399262Y1115039D03*
X391862D03*
X402962D03*
X399262Y1121447D03*
X397411Y1131060D03*
X395561Y1140973D03*
X393711Y1131060D03*
X390011D03*
X388161Y1140973D03*
X402961D03*
X401111Y1131060D03*
X419179Y841467D03*
X404379D03*
X411779D03*
X413629Y851380D03*
X409929D03*
X406229D03*
X417329D03*
X404379Y854584D03*
X413629Y864197D03*
X411779Y854584D03*
X409929Y864197D03*
X406229D03*
X419179Y854584D03*
X417329Y864197D03*
X404379Y867401D03*
X411779D03*
X419179D03*
X408078D03*
X415478D03*
X404379Y880219D03*
X413629Y877014D03*
X411779Y880219D03*
X409929Y877014D03*
Y870606D03*
X406229Y877014D03*
X419179Y880219D03*
X417329Y877014D03*
X404378Y873810D03*
X406229Y870606D03*
X408078Y880219D03*
X409929Y883423D03*
X406229D03*
X419178Y873810D03*
X417329Y870606D03*
X411778Y873810D03*
X413629Y870606D03*
X408078Y873810D03*
X413629Y889832D03*
X411779Y893036D03*
X409929Y889832D03*
X408079Y893036D03*
X406229Y889832D03*
X419179Y893036D03*
X417329Y889832D03*
X404378Y886627D03*
X411778D03*
X404378Y893036D03*
X415478Y886627D03*
X408078D03*
X406229Y896240D03*
X408078Y899445D03*
X415478D03*
X409929Y896240D03*
X415478Y893036D03*
X417329Y896240D03*
X422878Y893036D03*
X411778Y899445D03*
X413629Y896240D03*
X419178Y899445D03*
X422878Y912262D03*
X413629Y902649D03*
X409929Y909057D03*
Y902649D03*
X404378Y912262D03*
Y905853D03*
X419178Y912262D03*
X419179Y905853D03*
X417329Y902649D03*
X409929Y915466D03*
X417329Y909057D03*
X406229D03*
X413629D03*
Y915466D03*
X411778Y905853D03*
X408078D03*
Y912262D03*
X406229Y902649D03*
X415478Y905853D03*
X411778Y912262D03*
X415478D03*
X417329Y915466D03*
X411779Y918670D03*
X406229Y921875D03*
X409929D03*
X404378Y918670D03*
X418229Y926896D03*
X419178Y918670D03*
X405048Y930812D03*
X408078Y918670D03*
X408569Y929108D03*
X406308Y928626D03*
X417329Y921875D03*
X411872Y925264D03*
X415479Y918670D03*
X405145Y946239D03*
Y948539D03*
X414093Y942098D03*
X405048Y938046D03*
Y935746D03*
X416393Y942098D03*
X418693D03*
X407589Y942164D03*
X405289D03*
X409889D03*
X405122Y965896D03*
Y963596D03*
X414365Y971140D03*
X416755D03*
X404861Y981269D03*
Y978969D03*
Y986421D03*
X405101Y992971D03*
Y995271D03*
X404861Y988721D03*
X415185Y985580D03*
X417575D03*
X415185Y1014540D03*
X417575D03*
X405227Y1007156D03*
X405231Y1004848D03*
X417575Y1000060D03*
X415185D03*
X404986Y1022427D03*
X404998Y1026821D03*
X408325Y1031971D03*
Y1034271D03*
X408511Y1041340D03*
X417762Y1044544D03*
X412211Y1047749D03*
X404811D03*
X415911D03*
X419611D03*
X406662Y1044544D03*
X410362D03*
X408511Y1047749D03*
X414062Y1044544D03*
X412211Y1041340D03*
X415911D03*
X419611D03*
X406662Y1050952D03*
X415911Y1060565D03*
Y1054157D03*
X412211Y1060565D03*
X410361Y1050952D03*
X408511Y1054157D03*
X404811Y1060565D03*
X417761Y1050952D03*
X414060D03*
X417762Y1057361D03*
X421462Y1050952D03*
X419611Y1054157D03*
X406662Y1063770D03*
X408511Y1060565D03*
X410362Y1063770D03*
X412211Y1054157D03*
X404811D03*
X414062Y1057361D03*
X410362D03*
X417762Y1063770D03*
X414062D03*
X419611Y1060565D03*
Y1079791D03*
X408511Y1073383D03*
X406662Y1070178D03*
X404811Y1073383D03*
X415911Y1066974D03*
X410362Y1076587D03*
Y1070178D03*
X406661Y1076587D03*
X404811Y1066974D03*
X419611Y1073383D03*
X412211Y1079791D03*
X404811D03*
X417762Y1076587D03*
X408511Y1066974D03*
X412211Y1073383D03*
X415911D03*
X414062Y1070178D03*
X417762D03*
X412211Y1066974D03*
X419611D03*
X415911Y1092608D03*
X415912Y1086200D03*
X412211Y1092608D03*
X408511Y1086200D03*
X417761Y1089404D03*
Y1082995D03*
X410362Y1095813D03*
X406662D03*
X419612Y1099017D03*
X414061Y1095813D03*
X415912Y1099017D03*
X414062Y1108630D03*
X412211Y1099017D03*
X410362Y1102221D03*
X406661Y1108630D03*
Y1102221D03*
X404812Y1105426D03*
X417762Y1102221D03*
X404812Y1111834D03*
X404811Y1099017D03*
X408511Y1105426D03*
X412211Y1111834D03*
X415911D03*
X414062Y1102221D03*
X417762Y1108630D03*
X419611Y1105426D03*
X408511Y1099017D03*
X410362Y1108630D03*
X408511Y1111834D03*
X412211Y1105426D03*
X419611Y1111834D03*
X415911Y1105426D03*
Y1118243D03*
X414061Y1121447D03*
X412211Y1124651D03*
Y1118243D03*
X410361Y1115039D03*
X408511Y1118243D03*
X406661Y1115039D03*
X404811Y1118243D03*
X417761Y1115039D03*
X410361Y1127856D03*
X414062Y1115039D03*
X406661Y1121447D03*
X414062Y1127856D03*
Y1134264D03*
X412212Y1131060D03*
X410361Y1140973D03*
X408511Y1131060D03*
X404811D03*
X412212Y1137469D03*
X432128Y844671D03*
X426579Y841467D03*
X432129Y851380D03*
X428429D03*
X424729D03*
X421029D03*
X435829D03*
X432129Y864197D03*
X428429D03*
X426579Y854584D03*
X424729Y864197D03*
X421029D03*
X433979Y854584D03*
X435829Y864197D03*
X426579Y867401D03*
X433979D03*
X430278D03*
X422878D03*
X432129Y877014D03*
X428429D03*
X426579Y880219D03*
X424729Y877014D03*
X421029D03*
X433979Y880219D03*
X435829Y877014D03*
X432129Y870606D03*
X426578Y873810D03*
X424729Y870606D03*
X433979Y873810D03*
X428429Y870606D03*
X421029D03*
X435829D03*
X430278Y873810D03*
X432129Y889832D03*
X428429D03*
X426579Y893036D03*
X424729Y889832D03*
X421029D03*
X433979Y893036D03*
X435829Y889832D03*
X422878Y886627D03*
X430278D03*
Y899445D03*
X422878D03*
X424729Y896240D03*
X430278Y893036D03*
X432129Y896240D03*
X437678Y893036D03*
X421029Y896240D03*
X426578Y899445D03*
X428429Y896240D03*
X433978Y899445D03*
X435829Y896240D03*
X424729Y915466D03*
X426578Y912262D03*
X424729Y902649D03*
X432129D03*
X428429Y909057D03*
Y902649D03*
X421029D03*
X435829D03*
X428429Y915466D03*
X430278Y912262D03*
X432129Y915466D03*
X421029Y909057D03*
X435829D03*
Y915466D03*
X432128Y909057D03*
X433978Y905853D03*
X424728Y909057D03*
X422878Y905853D03*
X430278D03*
X426578D03*
X421029Y915466D03*
X433979Y912262D03*
X430278Y918670D03*
X433980Y925079D03*
Y931487D03*
X428429Y921875D03*
X432129D03*
X433979Y918670D03*
X435829Y921875D03*
X424927Y927255D03*
X423176Y929465D03*
X422427Y927255D03*
X425676Y929465D03*
X424729Y921875D03*
X422878Y918670D03*
X421029Y921875D03*
X426578Y918670D03*
X430279Y925079D03*
X432130Y928283D03*
X430279Y931487D03*
X432130Y934692D03*
X435830Y928283D03*
X430279Y937897D03*
X433979D03*
X426875Y947199D03*
Y949499D03*
X427875Y936470D03*
X433980Y944305D03*
X435830Y934692D03*
X426905Y965935D03*
Y963635D03*
X433980Y957123D03*
Y950714D03*
Y963531D03*
X426905Y980336D03*
Y978036D03*
X433980Y976348D03*
Y969940D03*
Y982757D03*
X426905Y994722D03*
Y992422D03*
Y1006875D03*
Y1009175D03*
X434411Y1009298D03*
X434412Y1002889D03*
X426905Y1021963D03*
Y1019663D03*
X434411Y1028524D03*
Y1022115D03*
X434412Y1015706D03*
X428862Y1044544D03*
X434412Y1034932D03*
X430712Y1047749D03*
X423311D03*
X427011D03*
X427012Y1041340D03*
X423312D03*
X425162Y1044544D03*
X421462D03*
X427011Y1054157D03*
X430711D03*
X425162Y1057361D03*
X432561Y1050952D03*
X434411Y1060565D03*
Y1054157D03*
X421462Y1063770D03*
X428861Y1057361D03*
X432561D03*
X421462D03*
X425162Y1050952D03*
X423311Y1054157D03*
X428862Y1050952D03*
X425162Y1063770D03*
X423311Y1060565D03*
X427011D03*
X428861Y1063770D03*
X430711Y1060565D03*
X423311Y1073383D03*
X432560Y1070178D03*
X421462Y1076587D03*
X430711Y1073383D03*
X427011D03*
Y1066974D03*
X425162Y1076587D03*
X423311Y1066974D03*
X432561Y1076587D03*
X434411Y1073383D03*
Y1066974D03*
X427012Y1079791D03*
X434411D03*
X421462Y1070178D03*
X425162D03*
X428862D03*
X430711Y1066974D03*
X428861Y1076587D03*
X430711Y1079791D03*
X428861Y1082995D03*
X425162Y1089404D03*
X421462Y1082995D03*
X432561Y1089404D03*
Y1082995D03*
X434411Y1092608D03*
Y1086200D03*
X428861Y1095813D03*
X421462D03*
X432561D03*
X427011Y1099017D03*
X425161Y1102221D03*
X423311Y1105426D03*
X421462Y1108630D03*
X434411Y1105426D03*
X423311Y1111834D03*
X434411D03*
X423311Y1124651D03*
Y1118243D03*
X421462Y1115039D03*
X434411Y1124651D03*
Y1118243D03*
X423312Y1137469D03*
X423311Y1131060D03*
X434412Y1137769D03*
X434411Y1131060D03*
X452478Y848176D03*
X445078D03*
X441378D03*
X439529Y844671D03*
X446929Y851380D03*
X443228D03*
X439529D03*
X450629D03*
X448779Y854584D03*
X446929Y864197D03*
X443229D03*
X441379Y854584D03*
X439529Y864197D03*
X439528Y857789D03*
X437680Y860992D03*
X450629Y864197D03*
X448779Y867401D03*
X441379D03*
X452478D03*
X445078D03*
X437678D03*
X448779Y880219D03*
X446929Y877014D03*
X443229D03*
X441379Y880219D03*
X439529Y877014D03*
X450629D03*
X448779Y873810D03*
X446929Y870606D03*
X441378Y873810D03*
X439529Y870606D03*
X450629D03*
X443229D03*
X437679Y873810D03*
X452479D03*
X445078D03*
X448779Y893036D03*
X446929Y889832D03*
X443229D03*
X441379Y893036D03*
X439529Y896240D03*
Y889832D03*
X437678Y886627D03*
X450629Y889832D03*
X437679Y899445D03*
X452478Y886627D03*
X445078D03*
X452478Y899445D03*
X441378D03*
X445078Y893036D03*
X446929Y896240D03*
X452479Y893036D03*
X445078Y899445D03*
X443229Y896240D03*
X448778Y899445D03*
X450630Y896240D03*
X446929Y909057D03*
Y902649D03*
X443229D03*
X439528D03*
X437678Y912262D03*
X437679Y905853D03*
X450629Y902649D03*
X446929Y915466D03*
X443229Y909057D03*
X439529Y915466D03*
X445079Y905853D03*
X441379D03*
X450630Y909057D03*
X452479Y905853D03*
X448779D03*
X448780Y912262D03*
X441380D03*
X439529Y909057D03*
X445080Y912262D03*
X443229Y915466D03*
X450629D03*
X452478Y912262D03*
X448779Y918670D03*
X454329Y915466D03*
X439529Y921875D03*
X446930Y928283D03*
X441379Y925079D03*
Y931487D03*
X446929Y921875D03*
X437678Y918670D03*
X441378D03*
X450629Y921875D03*
X445078Y918670D03*
X443229Y921875D03*
X452478Y918670D03*
X446930Y934692D03*
X443230Y928283D03*
X448780Y931487D03*
X437679D03*
X450630Y928283D03*
X448780Y925079D03*
X445079Y931487D03*
X439530Y934692D03*
X445079Y925079D03*
X439530Y928283D03*
X437679Y925079D03*
X441379Y937897D03*
X445079D03*
X437679D03*
X448779D03*
X446929Y941101D03*
X446930Y947510D03*
X443230Y934692D03*
X446930Y960327D03*
Y953918D03*
Y966736D03*
Y979553D03*
Y973144D03*
X447362Y1006094D03*
Y999685D03*
Y1012502D03*
Y1025319D03*
Y1018911D03*
Y1031728D03*
X447360Y1038136D03*
X452911Y1041340D03*
X451061Y1044544D03*
X449211Y1047749D03*
X452911D03*
X447361Y1057361D03*
Y1050952D03*
X452911Y1060565D03*
X447361Y1063770D03*
X449211Y1054157D03*
X449213Y1060565D03*
X451061Y1063770D03*
X452911Y1054157D03*
X451062Y1050952D03*
X454762D03*
Y1057361D03*
X451062D03*
X451061Y1076587D03*
X452911Y1073383D03*
X447361Y1076587D03*
Y1070178D03*
X449211Y1073383D03*
X452911Y1079791D03*
X449211D03*
X452911Y1066974D03*
X449211D03*
X451062Y1070178D03*
X447361Y1082995D03*
X452911Y1092608D03*
X451062Y1089404D03*
X449212Y1086200D03*
X451062Y1095813D03*
X452911Y1086200D03*
X451060Y1082995D03*
X447361Y1108630D03*
Y1102221D03*
X452911Y1099017D03*
X447361Y1121447D03*
Y1115039D03*
Y1127856D03*
Y1134264D03*
X461729Y851380D03*
X458029D03*
X454328D03*
X456179Y841467D03*
X463579D03*
X469129Y851380D03*
X465429D03*
X456179Y854584D03*
X463579D03*
X461729Y864197D03*
X458029D03*
X454329D03*
X469129D03*
X465429D03*
X456179Y867401D03*
X463579D03*
X467278D03*
X459878D03*
X461729Y877014D03*
X458029D03*
X456179Y880219D03*
X454329Y877014D03*
X463579Y880219D03*
X469129Y877014D03*
X465429D03*
X469129Y870606D03*
X463578Y873810D03*
X461729Y870606D03*
X456178Y873810D03*
X454329Y870606D03*
X465429D03*
X458029D03*
X461729Y889832D03*
X458029D03*
X456179Y893036D03*
X454329Y889832D03*
X463579Y893036D03*
X469129Y896240D03*
Y889832D03*
X465429D03*
X454329Y896240D03*
X459878Y893036D03*
X461729Y896240D03*
X467278Y893036D03*
X456178Y899445D03*
X458029Y896240D03*
X463578Y899445D03*
X465429Y896240D03*
X470978Y899445D03*
X463578Y905853D03*
X470980Y912262D03*
X461729Y902649D03*
X458029D03*
X456178Y912262D03*
Y905853D03*
X454329Y902649D03*
X465429D03*
Y909057D03*
Y915466D03*
X469129Y902649D03*
X454329Y909057D03*
X470978Y918670D03*
X467278Y912262D03*
X469129Y915466D03*
X458029Y909057D03*
X459878Y905853D03*
X461729Y915466D03*
X467278Y905853D03*
X461729Y909057D03*
X458029Y915466D03*
X459878Y918670D03*
X463578Y912262D03*
X459878D03*
X469129Y909057D03*
X454103Y931359D03*
Y933659D03*
X461729Y921875D03*
X456178Y918670D03*
X467278D03*
X454329Y921875D03*
X468236Y928349D03*
X465936D03*
X463636D03*
X461336D03*
X459036D03*
X469129Y921875D03*
X463578Y918670D03*
X465429Y921875D03*
X458029D03*
X462261Y942152D03*
X464561D03*
X466861D03*
X454423Y949139D03*
X469251Y942246D03*
X454393Y963829D03*
Y966129D03*
X463874Y956540D03*
X466272D03*
X454423Y951439D03*
X466272Y971100D03*
X463874Y971140D03*
X454263Y981209D03*
Y978909D03*
X454463Y995299D03*
Y992999D03*
X466272Y985580D03*
X463874D03*
X466272Y1014540D03*
X463874D03*
X454443Y1009409D03*
Y1007109D03*
X466272Y1000060D03*
X463874D03*
X468895Y1014550D03*
X454434Y1022186D03*
Y1019886D03*
X457942Y1031909D03*
X467711Y1047750D03*
X460311D03*
Y1041340D03*
X467372Y1036874D03*
X465861Y1044544D03*
X456611Y1047749D03*
X464011D03*
X471411Y1041340D03*
X467711D03*
X454762Y1044544D03*
Y1038136D03*
X460971Y1037069D03*
X463271D03*
X458671D03*
X457942Y1034409D03*
X456611Y1041340D03*
X464011D03*
X462162Y1044544D03*
X458462D03*
X464011Y1054157D03*
X465860Y1050952D03*
X456611Y1060565D03*
X462161Y1057361D03*
X456611Y1054157D03*
X462162Y1050952D03*
X465862Y1057361D03*
X458462Y1063770D03*
X465862D03*
X462161D03*
X460312Y1054157D03*
X458462Y1057361D03*
X454761Y1063770D03*
X464012Y1060565D03*
X458460Y1050952D03*
X460311Y1060565D03*
X454761Y1076587D03*
X456611Y1073383D03*
X454762Y1070178D03*
X462162D03*
X467711Y1073383D03*
Y1066974D03*
X456612Y1079791D03*
X467711D03*
X460311Y1073383D03*
X458460Y1070178D03*
X460311Y1066974D03*
X464011D03*
X465860Y1070178D03*
X469560D03*
X464012Y1079791D03*
X460312D03*
X462162Y1076587D03*
X456611Y1066974D03*
X465862Y1076587D03*
X464011Y1073383D03*
X458462Y1076587D03*
X458461Y1082995D03*
X456611Y1086200D03*
X460311Y1092608D03*
X464011Y1086200D03*
X467712D03*
Y1092608D03*
X462161Y1095812D03*
X458461D03*
X465861Y1089403D03*
X456612Y1092607D03*
X454761Y1089403D03*
X460311Y1086200D03*
X454760Y1082995D03*
X465861Y1095812D03*
X464012Y1092607D03*
X454761Y1095812D03*
X458461Y1089403D03*
X462161D03*
X460312Y1105426D03*
X458462Y1102221D03*
X456611Y1099017D03*
X464012Y1105426D03*
Y1099017D03*
X462162Y1108630D03*
X465861D03*
Y1102221D03*
X464012Y1111834D03*
X467711Y1105426D03*
Y1111834D03*
X460312Y1099016D03*
X458462Y1121447D03*
Y1115039D03*
X467712Y1124651D03*
X467711Y1118243D03*
X465862Y1121447D03*
Y1115039D03*
X458462Y1127856D03*
Y1134264D03*
X478379Y841467D03*
X470979D03*
X476529Y851380D03*
X480229D03*
X472829D03*
X483929D03*
X480229Y864197D03*
X478379Y854584D03*
X476529Y864197D03*
X470979Y854584D03*
X472829Y864197D03*
X483929D03*
X478379Y867401D03*
X470979D03*
X474678D03*
X482078D03*
X480229Y877014D03*
X478379Y880219D03*
X476529Y877014D03*
X472829D03*
X472828Y870606D03*
X470979Y880219D03*
Y873810D03*
X483929Y877014D03*
X480229Y870606D03*
X476529D03*
X478378Y873810D03*
X483929Y870606D03*
X474678Y880219D03*
X476529Y883423D03*
X482078Y880219D03*
X483929Y883423D03*
X472829D03*
X480229D03*
X480228Y896240D03*
X480229Y889832D03*
X478379Y893036D03*
X470979D03*
X476529Y889832D03*
X472829D03*
X483929D03*
X474678Y899445D03*
X482078D03*
X474678Y893036D03*
X472829Y896240D03*
X482078Y893036D03*
X483929Y896240D03*
X478378Y886627D03*
Y899445D03*
X476529Y896240D03*
Y915466D03*
X478380Y912262D03*
X478379Y918670D03*
X480229Y902649D03*
X474678Y912262D03*
Y905853D03*
X483929Y909057D03*
X482079Y912262D03*
X483928Y902649D03*
X483929Y915466D03*
X480229D03*
X472828D03*
X472829Y902649D03*
X480228Y909057D03*
X476529Y902649D03*
X470978Y905853D03*
X478378D03*
X472829Y909057D03*
X476529D03*
X480229Y928283D03*
X478378Y931488D03*
Y925079D03*
X482078D03*
X476285Y930126D03*
X480229Y921875D03*
X476528D03*
X474678Y918670D03*
X483929Y928283D03*
X482078Y918670D03*
X483928Y921875D03*
X482079Y931488D03*
X472829Y921875D03*
X470536Y928349D03*
X478378Y937896D03*
X480229Y941100D03*
X476285Y934726D03*
X476180Y945355D03*
Y947655D03*
X478378Y944304D03*
X480229Y934691D03*
X483928Y941100D03*
X482079Y944304D03*
X482078Y937896D03*
X483928Y947509D03*
X483929Y934691D03*
X471550Y942152D03*
X473851Y942246D03*
X476285Y962326D03*
Y960026D03*
Y964626D03*
X483928Y960326D03*
X482078Y957122D03*
X482079Y950713D03*
X483929Y966735D03*
X478378Y963530D03*
X483929Y953917D03*
X480228Y960326D03*
X480229Y966735D03*
X482078Y963529D03*
X476285Y966926D03*
X476192Y977670D03*
X476335Y980737D03*
X482079Y969939D03*
X483928Y979552D03*
X482078Y976347D03*
X483929Y973143D03*
X482078Y982756D03*
X478379Y969939D03*
X480229Y979552D03*
X478378Y982756D03*
X480229Y973143D03*
X478378Y976347D03*
X476285Y996826D03*
Y994526D03*
Y989926D03*
Y987626D03*
X476295Y1010500D03*
X476285Y1012926D03*
Y1006026D03*
Y1003726D03*
X471204Y1014540D03*
X484361Y999684D03*
X482512Y1009297D03*
X482511Y1002888D03*
X484362Y1012501D03*
X480662Y999684D03*
X478811Y1002888D03*
Y1009297D03*
X480662Y1012501D03*
X484362Y1006093D03*
X476275Y1022636D03*
X476285Y1017526D03*
X482511Y1028523D03*
Y1022114D03*
X484361Y1018910D03*
Y1031727D03*
X484362Y1025318D03*
X480662Y1031727D03*
X482511Y1015705D03*
X480662Y1025318D03*
X471282Y1036526D03*
X473507Y1035928D03*
X475111Y1041340D03*
X482511D03*
X482512Y1034931D03*
X484361Y1038136D03*
X471411Y1047749D03*
X482511D03*
X484362Y1044544D03*
X475111Y1047749D03*
X469562Y1044544D03*
X478811Y1034931D03*
X480662Y1038136D03*
X478811Y1041340D03*
X480662Y1044544D03*
X473262D03*
X480662Y1050952D03*
X475111Y1060565D03*
X471411Y1054157D03*
X484361Y1057361D03*
X482511Y1060565D03*
X484362Y1050952D03*
Y1063770D03*
X478811Y1066974D03*
X475111D03*
X473262Y1070178D03*
X478811Y1073383D03*
X484361Y1076587D03*
X484362Y1070178D03*
X482512Y1066974D03*
X478812Y1079791D03*
X475111D03*
X482511D03*
X471411Y1066974D03*
X476962Y1076587D03*
X480662D03*
Y1070178D03*
X476962D03*
X473262Y1076587D03*
X469562D03*
X471411Y1073383D03*
Y1079791D03*
X475111Y1073383D03*
X482511D03*
X480662Y1082995D03*
X476962Y1089404D03*
X473262Y1082995D03*
X469561Y1089404D03*
X482512Y1086200D03*
X484362Y1089404D03*
X480661Y1095813D03*
X469562D03*
X484362D03*
Y1082995D03*
X478812Y1092607D03*
X475112D03*
X473261Y1089403D03*
X471412Y1086199D03*
X476961Y1082994D03*
X482512Y1092607D03*
X476961Y1095812D03*
X471412Y1092607D03*
X475112Y1086199D03*
X478812D03*
X480662Y1108630D03*
X478811Y1099017D03*
X473262Y1108630D03*
X476962Y1102221D03*
X475112Y1099017D03*
X471411D03*
X469562Y1102221D03*
X482511Y1105426D03*
Y1111834D03*
X484362Y1108630D03*
X475111Y1111834D03*
X471411D03*
X478811Y1105426D03*
X469562Y1108630D03*
X473262Y1102221D03*
X482511Y1099017D03*
X478811Y1111834D03*
X476962Y1108630D03*
X471411Y1105426D03*
X475111D03*
X484362Y1102221D03*
X480661Y1115039D03*
X478811Y1118243D03*
X476961Y1115039D03*
X475111Y1118243D03*
X471411D03*
X469561Y1115039D03*
X482511Y1118243D03*
X476961Y1127856D03*
X469562D03*
X484361D03*
X484362Y1115039D03*
X473262D03*
X478811Y1131060D03*
X476961Y1140973D03*
X475111Y1131060D03*
X471412Y1137469D03*
Y1131060D03*
X469561Y1140973D03*
X473261Y1134264D03*
X482511Y1131060D03*
X484361Y1140973D03*
X493179Y841467D03*
X485779D03*
X500579D03*
X495029Y851380D03*
X491329D03*
X487629D03*
X498729D03*
X495029Y864197D03*
X493179Y854584D03*
X491329Y864197D03*
X487629D03*
X485779Y854584D03*
X498729Y864197D03*
X500579Y854584D03*
X493179Y867401D03*
X485779D03*
X500579D03*
X489478D03*
X496878D03*
X495029Y877014D03*
X493179Y880219D03*
X491329Y877014D03*
X487629D03*
X485779Y880219D03*
X500579D03*
X498729Y877014D03*
X487629Y870606D03*
X495029D03*
X485778Y873810D03*
X491329Y870606D03*
X493178Y873810D03*
X498729Y870606D03*
X500578Y873810D03*
X489478Y880219D03*
X491329Y883423D03*
X496878Y880219D03*
X498729Y883423D03*
X487629D03*
X495029D03*
X489479Y893036D03*
X495029Y889832D03*
X491329D03*
X487629D03*
X498729D03*
X500579Y893036D03*
X498729Y896240D03*
X496879Y899445D03*
X489478D03*
X485778D03*
X493178D03*
Y893036D03*
X496878D03*
X485778D03*
X491329Y896240D03*
X487629D03*
X495029D03*
X485778Y886627D03*
X493178D03*
X500578D03*
X496878Y912262D03*
X495029Y909057D03*
X489478Y912262D03*
Y905853D03*
X495029Y902649D03*
X493179Y905853D03*
X485778D03*
X498728Y915466D03*
X485778Y912262D03*
X487629Y909057D03*
X493178Y912262D03*
X491329Y909057D03*
X487629Y902649D03*
X491329D03*
X487629Y915466D03*
X495029D03*
X491329D03*
X495028Y928283D03*
X493179Y925079D03*
X489478D03*
Y918670D03*
X485778Y925079D03*
X496879Y918670D03*
X495029Y921875D03*
X496878Y931488D03*
X489478D03*
X491329Y921875D03*
X493178Y918670D03*
X485778Y931488D03*
X491329Y928283D03*
X493178Y931488D03*
X487629Y928283D03*
Y921875D03*
X485778Y918670D03*
X496879Y937896D03*
X495029Y941100D03*
X493179Y944304D03*
X489478D03*
Y937896D03*
X485778Y944304D03*
X498729Y934691D03*
X495028Y947509D03*
X487629D03*
X491329D03*
X487629Y941100D03*
X485778Y937896D03*
X491329Y941100D03*
X493178Y937896D03*
X487629Y934691D03*
X495029D03*
X491329D03*
X496879Y957122D03*
X495029Y960326D03*
X489478Y957122D03*
Y950713D03*
X496878D03*
X498729Y953917D03*
X495028Y966735D03*
X493179Y963530D03*
X485778D03*
X489478D03*
X500579D03*
X487629Y966735D03*
X491329D03*
X498729D03*
X496878Y963530D03*
X485778Y950713D03*
X493178D03*
X491329Y960326D03*
X493178Y957122D03*
X487629Y960326D03*
X485778Y957122D03*
X495029Y953917D03*
X487629D03*
X491329D03*
X496879Y976347D03*
X496878Y969939D03*
X489478Y976347D03*
Y969939D03*
X495029Y979552D03*
X498728Y973143D03*
X493179Y982756D03*
X489478D03*
X485778D03*
X495029Y973143D03*
X487629D03*
X491329D03*
X485778Y969939D03*
X493178D03*
X500578D03*
X497311Y1009297D03*
X497312Y1002888D03*
X495462Y999684D03*
X489911Y1009297D03*
X489912Y1002888D03*
X491761Y1006093D03*
X488062D03*
X499161D03*
X495461Y1012501D03*
X495462Y1006093D03*
X486211Y1002888D03*
X493611D03*
X488062Y999684D03*
X491762D03*
X491761Y1012501D03*
X493611Y1009297D03*
X488062Y1012501D03*
X486211Y1009297D03*
X497311Y1028523D03*
X489911D03*
Y1022114D03*
Y1015705D03*
X497311Y1022114D03*
X495462Y1018910D03*
X493612Y1015705D03*
X486211D03*
X501012D03*
X499161Y1025318D03*
X495461Y1031727D03*
X488062D03*
X486211Y1028523D03*
X491762Y1031727D03*
X493611Y1028523D03*
X486211Y1022114D03*
X488062Y1018910D03*
X493611Y1022114D03*
X491762Y1018910D03*
X488062Y1025318D03*
X495462D03*
X491762D03*
X497312Y1041340D03*
X489911D03*
Y1034931D03*
X495462Y1038136D03*
X493612Y1034931D03*
X486211D03*
X499161Y1044544D03*
X489911Y1047749D03*
X497311D03*
X486211D03*
X493611D03*
X486211Y1041340D03*
X488062Y1038136D03*
X493611Y1041340D03*
X491762Y1038136D03*
X488062Y1044544D03*
X495462D03*
X491762D03*
X497311Y1060565D03*
X495462Y1057361D03*
X489911Y1060565D03*
Y1054157D03*
X495461Y1050952D03*
X493611Y1054157D03*
X486211D03*
X499162Y1063770D03*
X486211Y1060565D03*
X488062Y1057361D03*
X493611Y1060565D03*
X491762Y1057361D03*
X488062Y1050952D03*
X491762D03*
X488062Y1063770D03*
X495462D03*
X491762D03*
X495462Y1076587D03*
X493612Y1073383D03*
X489911Y1066974D03*
X486211Y1073383D03*
X497311Y1066974D03*
X495461Y1070178D03*
X489911Y1073383D03*
X497312Y1079791D03*
X489911D03*
X486211D03*
X488062Y1076587D03*
X493611Y1079791D03*
X491762Y1076587D03*
X488062Y1070178D03*
X486211Y1066974D03*
X491762Y1070178D03*
X493611Y1066974D03*
X497311Y1086200D03*
X493612Y1092608D03*
X489911D03*
Y1086200D03*
X486211Y1092608D03*
X495461Y1089404D03*
X499161Y1082995D03*
X495462Y1095813D03*
X499162D03*
X491762D03*
Y1089404D03*
X493611Y1086200D03*
X488062Y1089404D03*
X486211Y1086200D03*
X495462Y1082995D03*
X488062D03*
X491762D03*
X497312Y1105426D03*
X493611D03*
X491762Y1102221D03*
X488061D03*
X486211Y1105426D03*
X486212Y1099017D03*
X499161Y1108630D03*
Y1102221D03*
X497312Y1111834D03*
X489911D03*
Y1099017D03*
X495462Y1102221D03*
X501011Y1099017D03*
X493611D03*
X497311D03*
X495462Y1108630D03*
X489911Y1105426D03*
X486211Y1111834D03*
X493611D03*
X491762Y1108630D03*
X488062D03*
X501012Y1105426D03*
Y1111833D03*
X497311Y1118243D03*
X495462Y1121447D03*
X493612Y1118243D03*
X489911D03*
X486211D03*
X501011D03*
X499161Y1115039D03*
X491761Y1127856D03*
X499161D03*
X491762Y1115039D03*
X495462D03*
X497311Y1131060D03*
X493611D03*
X489911D03*
X486211D03*
X491761Y1140973D03*
X501011Y1131060D03*
X499161Y1140973D03*
X507979Y841467D03*
X515379D03*
X506129Y851380D03*
X502429D03*
X513529D03*
X509829D03*
X517229D03*
X513529Y864197D03*
X509829D03*
X506129D03*
X502429D03*
X507979Y854584D03*
X515379D03*
X517229Y864197D03*
X507979Y867401D03*
X515379D03*
X511678D03*
X504278D03*
X509829Y877014D03*
X507979Y880219D03*
X502429Y877014D03*
X513529D03*
X506129D03*
X515379Y880219D03*
X517229Y877014D03*
Y870606D03*
X502429D03*
X509829D03*
X513529D03*
X515378Y873810D03*
X506129Y870606D03*
X507978Y873810D03*
X511678Y880219D03*
X513529Y883423D03*
X504278Y880219D03*
X506129Y883423D03*
X509829D03*
X517229D03*
X502429D03*
X506129Y889832D03*
X502428Y896240D03*
X502429Y889832D03*
X513529D03*
X509829D03*
X506128Y896240D03*
X504279Y893036D03*
X515379D03*
X517229Y889832D03*
X507978Y899445D03*
X515378D03*
Y886627D03*
X507978D03*
X511678Y905853D03*
X509829Y909057D03*
X507979Y912262D03*
X502429Y909057D03*
Y902649D03*
X509828D03*
X515378Y912262D03*
Y905853D03*
X502429Y915466D03*
X506129D03*
X511678Y925079D03*
X509829Y928283D03*
X502429D03*
Y921875D03*
X509828D03*
X507978Y918670D03*
X515378Y925079D03*
Y918670D03*
X507979Y931488D03*
X515378D03*
X511678Y944304D03*
X509828Y941100D03*
X507978Y937896D03*
X506129Y934691D03*
X502429Y941100D03*
Y934691D03*
X515378Y944304D03*
Y937896D03*
X509829Y947509D03*
X502429D03*
X509828Y960326D03*
X507978Y957122D03*
X506129Y953917D03*
X502429Y960326D03*
Y953917D03*
X507979Y950713D03*
X515378Y957122D03*
Y950713D03*
X509829Y966735D03*
X502428D03*
X511678Y963530D03*
X504278D03*
X515378D03*
X506129Y966735D03*
X507978Y963530D03*
Y976347D03*
X507979Y969939D03*
X502429Y979552D03*
Y973143D03*
X513529D03*
X509828Y979552D03*
X506129Y973143D03*
X515379Y976347D03*
X515378Y969939D03*
X517228Y973143D03*
X511678Y982756D03*
X515378D03*
X504278Y969939D03*
X510261Y999684D03*
X508411Y1002888D03*
X506562Y1006093D03*
X502862Y999684D03*
X502861Y1012501D03*
X508412Y1009297D03*
X510262Y1012501D03*
X515811Y1009297D03*
Y1002888D03*
X502862Y1006093D03*
X508411Y1028523D03*
X502862Y1025318D03*
Y1018910D03*
X510261D03*
X508411Y1022114D03*
X506562Y1025318D03*
X504711Y1015705D03*
X515811Y1028523D03*
Y1022114D03*
X510262Y1031727D03*
X502862D03*
X515811Y1015705D03*
X512111D03*
X502862Y1044544D03*
Y1038136D03*
X512111Y1034931D03*
X510261Y1038136D03*
X508411Y1041340D03*
X506562Y1044544D03*
X515811Y1034931D03*
Y1041340D03*
X508411Y1047749D03*
X515811D03*
X510262Y1057361D03*
X508411Y1060565D03*
X502862Y1057361D03*
Y1050952D03*
X512111Y1054157D03*
X510262Y1050952D03*
X515811Y1054157D03*
Y1060565D03*
X502862Y1063770D03*
X506562D03*
X510262Y1076587D03*
Y1070178D03*
X502862Y1076587D03*
Y1070178D03*
X512111Y1073383D03*
X508411Y1066974D03*
X515811Y1073383D03*
Y1066974D03*
X508411Y1079791D03*
X515811D03*
X512112Y1092608D03*
X510262Y1089404D03*
X508412Y1086200D03*
X506562Y1082995D03*
X502862Y1089404D03*
Y1082995D03*
X515812Y1092608D03*
X515811Y1086200D03*
X513961Y1095813D03*
X502862D03*
X517662D03*
X513962Y1108630D03*
Y1102221D03*
X512112Y1099017D03*
X508411D03*
X506562Y1108630D03*
X504711Y1099017D03*
X502862Y1102221D03*
X515811Y1105426D03*
Y1111834D03*
X517662Y1108630D03*
X502861Y1108629D03*
X512112Y1105426D03*
X508412Y1111833D03*
X506561Y1102220D03*
X504712Y1111833D03*
Y1105426D03*
X510261Y1108630D03*
X512112Y1111833D03*
X508412Y1105426D03*
X513961Y1115039D03*
X512111Y1118243D03*
X508411D03*
X504711D03*
X510261Y1115039D03*
X515811Y1118243D03*
X513961Y1127856D03*
X506561D03*
X517662Y1115039D03*
X506561Y1115038D03*
X513961Y1140973D03*
X512111Y1131060D03*
X508411D03*
X504711D03*
X506561Y1140973D03*
X515811Y1131060D03*
X528329Y844671D03*
X522779Y841467D03*
X528329Y851380D03*
X524629D03*
X520929D03*
X532029D03*
X528329Y864197D03*
X524629D03*
X520929D03*
X530179Y860993D03*
Y854584D03*
X522779D03*
X532028Y857789D03*
X533879Y860993D03*
X530178Y867401D03*
X522779D03*
X533879D03*
X519078D03*
X526479D03*
X528329Y877014D03*
X522779Y880219D03*
X520929Y877014D03*
X530179Y880219D03*
X524629Y877014D03*
X532029D03*
X533879Y880219D03*
Y873810D03*
X532028Y883423D03*
X524629Y870606D03*
X532029D03*
X520929D03*
X522778Y873810D03*
X528329Y870606D03*
X530178Y873810D03*
X519078Y880219D03*
X520929Y883423D03*
X526479Y880219D03*
X528329Y883423D03*
X524629D03*
X528329Y896240D03*
Y889832D03*
X524629D03*
X526479Y893036D03*
X524629Y896240D03*
X520929Y889832D03*
X532029D03*
Y896240D03*
X533879Y893036D03*
X522779Y899445D03*
X533879D03*
X530178Y893036D03*
X522778Y886627D03*
X530179D03*
X528329Y902649D03*
X522778Y912262D03*
X520928Y909057D03*
X519079Y905853D03*
X520929Y902649D03*
X528329Y915466D03*
X524628D03*
X532029D03*
X528329Y909057D03*
X533879Y912262D03*
X528329Y921875D03*
X520928Y928283D03*
X519079Y925079D03*
X522779Y918670D03*
X520929Y921875D03*
X522778Y931488D03*
X528329Y928283D03*
X533879Y918670D03*
X533878Y931488D03*
X528329Y941100D03*
Y934691D03*
X524628D03*
X522779Y937896D03*
X520929Y941100D03*
X519079Y944304D03*
X520928Y947509D03*
X532029Y934691D03*
X533879Y937896D03*
X528329Y947509D03*
Y960326D03*
Y953917D03*
X524629D03*
X522779Y957122D03*
X520929Y960326D03*
X522778Y950713D03*
X520928Y966735D03*
X526479Y963530D03*
X519079D03*
X533879Y957122D03*
X532029Y953917D03*
X533879Y950713D03*
X530178Y963530D03*
X528329Y966735D03*
Y979552D03*
Y973143D03*
X522779Y976347D03*
X522778Y969939D03*
X524628Y973143D03*
X520929Y979552D03*
X533879Y976347D03*
X519079Y982756D03*
X533901Y980606D03*
X533879Y969939D03*
X532029Y973143D03*
X521361Y1012501D03*
Y999684D03*
X528762Y1006093D03*
Y999684D03*
X525061Y1006093D03*
X523211Y1009297D03*
X523212Y1002888D03*
X534311Y1009297D03*
Y1002888D03*
X532461Y1006093D03*
X528761Y1012501D03*
X528762Y1025318D03*
X523211Y1028523D03*
X525061Y1025318D03*
X528762Y1031727D03*
X521361D03*
X519512Y1015705D03*
X521362Y1018910D03*
X523211Y1022114D03*
X526912Y1015705D03*
X528762Y1018910D03*
X530611Y1015705D03*
X534311Y1028523D03*
X534310Y1022114D03*
X532461Y1025318D03*
X528762Y1044544D03*
X525061D03*
X523212Y1041340D03*
X521362Y1038136D03*
X519512Y1034931D03*
X532462Y1044544D03*
X523211Y1047749D03*
X528762Y1038136D03*
X534311Y1041340D03*
Y1047749D03*
X528762Y1057361D03*
Y1050952D03*
X523212Y1060565D03*
X521362Y1057361D03*
X521361Y1050952D03*
X519512Y1054157D03*
X528762Y1063770D03*
X525061D03*
X534311Y1060565D03*
X532462Y1063770D03*
X528762Y1076587D03*
Y1070178D03*
X521362Y1076587D03*
X521361Y1070178D03*
X519512Y1073383D03*
X523211Y1066974D03*
X523212Y1079791D03*
X534311Y1066974D03*
Y1079791D03*
X523211Y1086200D03*
X521361Y1089404D03*
X519511Y1092608D03*
X528762Y1089404D03*
Y1082995D03*
X525061D03*
X532462Y1082996D03*
X534311Y1086200D03*
X528761Y1095813D03*
X526911Y1105426D03*
X521361Y1102221D03*
X519511Y1105426D03*
X519512Y1099017D03*
X532461Y1108630D03*
X530612Y1111834D03*
X523211D03*
X526911Y1099017D03*
X534311D03*
X532460Y1102221D03*
X521362Y1108630D03*
X525062D03*
X534311Y1111834D03*
X523211Y1105426D03*
X534311D03*
X528762Y1108630D03*
X519511Y1111834D03*
X526911D03*
X530611Y1124651D03*
Y1118243D03*
X528762Y1121447D03*
X523211Y1118243D03*
X521361Y1115039D03*
X519511Y1118243D03*
X532461Y1115039D03*
X528761Y1127856D03*
X521361D03*
X525062Y1115039D03*
X528762D03*
X532461Y1121446D03*
X534311Y1124650D03*
X532461Y1127855D03*
X530612Y1137469D03*
Y1131060D03*
X526912D03*
X523211D03*
X519511D03*
X528761Y1134264D03*
X521361Y1140973D03*
X534311Y1131060D03*
X537580Y848176D03*
X535729Y844671D03*
Y851380D03*
X544979Y860993D03*
Y854584D03*
X539428Y864197D03*
X537579Y854584D03*
Y860993D03*
X544979Y867401D03*
X541279D03*
X537579D03*
X546829Y870606D03*
X541279Y873810D03*
X535729Y870606D03*
Y883423D03*
X541279Y880219D03*
X546829Y883423D03*
X537579Y893036D03*
X541279Y886627D03*
X544979D03*
X537579D03*
X535729Y889832D03*
X550529D03*
X537579Y899445D03*
X548679Y912262D03*
X537579D03*
X539429Y909057D03*
X537579Y905853D03*
X535729Y909057D03*
X543129D03*
X535729Y902649D03*
X548679Y905853D03*
X543129Y928283D03*
X539429D03*
X537579Y918670D03*
X537578Y925079D03*
X535729Y928283D03*
Y921875D03*
X548678Y925079D03*
X537578Y931488D03*
X548678D03*
X537579Y937896D03*
X537578Y944304D03*
X535729Y941100D03*
X548678Y944304D03*
X539429Y947509D03*
X535729D03*
X549278Y949619D03*
X549719Y962436D03*
X537579Y957122D03*
Y950713D03*
X535729Y960326D03*
Y966735D03*
X537579Y963530D03*
X548146Y965640D03*
X539429Y979552D03*
X537579Y982756D03*
X541279Y969939D03*
X539429Y973143D03*
X535729D03*
X543729Y984866D03*
X539862Y1006092D03*
X539861Y999684D03*
X536161D03*
Y1006093D03*
X543563Y1006092D03*
X549254Y1000648D03*
X536161Y1012501D03*
Y1025318D03*
X539861Y1018910D03*
X541712Y1015705D03*
X545412D03*
X538012D03*
X536161Y1018910D03*
X549112Y1015705D03*
X536161Y1031727D03*
X545412Y1034931D03*
X539862Y1044544D03*
X539861Y1038136D03*
X541711Y1034931D03*
X538011D03*
X536161Y1038136D03*
X549112Y1034931D03*
X541711Y1054157D03*
X538011D03*
X536161Y1057361D03*
X545411Y1054157D03*
X538011Y1060565D03*
X536161Y1050952D03*
X549422Y1064850D03*
X538011Y1066974D03*
X541711Y1073383D03*
X545411Y1066974D03*
X539861Y1076587D03*
X536161D03*
X536162Y1070178D03*
X538011Y1073383D03*
X547262Y1070178D03*
X536162Y1082996D03*
X538011Y1092608D03*
X536161Y1089404D03*
X545411Y1092608D03*
X547262Y1082996D03*
X543561Y1095813D03*
X536161D03*
X547261D03*
X545412Y1105426D03*
X541711D03*
X539861Y1108630D03*
Y1102221D03*
X536161D03*
X541711Y1111834D03*
X545411D03*
X538011Y1105426D03*
X536161Y1108630D03*
X538011Y1111834D03*
X543561Y1108630D03*
X545411Y1124651D03*
Y1118243D03*
X543562Y1115039D03*
X539862D03*
X538011Y1124651D03*
X536161Y1115039D03*
X538010Y1118242D03*
X543561Y1121446D03*
X539861Y1127855D03*
X536161D03*
Y1121446D03*
X539861D03*
X541711Y1124650D03*
X543561Y1127855D03*
X541711Y1131060D03*
X536162Y1134264D03*
X538012Y1131059D03*
X551429Y979057D03*
X550701Y972608D03*
X550961Y1031727D03*
X650599Y766798D03*
X918264Y506011D03*
X1030780Y1266532D03*
X1074480Y1263742D03*
X1181941Y766798D03*
X1297012Y157449D03*
X1293802Y159299D03*
Y162999D03*
X1297007Y161149D03*
X1297012Y168549D03*
X1297007Y164849D03*
X1293802Y166699D03*
X1293511Y179048D03*
X1296999Y183349D03*
X1297007Y172249D03*
X1296999Y175949D03*
X1293802Y183349D03*
Y170399D03*
X1294163Y175865D03*
X1296999Y179649D03*
Y194449D03*
Y198149D03*
Y190749D03*
X1293802Y187049D03*
Y190749D03*
Y198149D03*
Y194449D03*
Y201849D03*
X1296999Y187049D03*
Y201849D03*
X1293805Y211099D03*
X1293798Y205833D03*
X1296999Y216649D03*
Y209249D03*
X1293807Y218499D03*
Y214799D03*
X1296999Y212949D03*
Y205549D03*
X1294357Y224688D03*
X1296999Y224049D03*
X1293807Y222199D03*
X1300393Y235762D03*
X1303417Y164849D03*
X1300213Y162999D03*
X1300212Y166699D03*
X1306622D03*
X1300774Y155288D03*
X1309832Y161149D03*
X1303417D03*
X1309832Y168549D03*
X1303417D03*
X1309832Y157449D03*
X1306626Y162999D03*
Y159299D03*
X1313037Y162999D03*
X1309832Y164849D03*
X1313037Y159299D03*
X1303417Y157449D03*
X1300217Y159299D03*
X1313033Y166699D03*
X1300212Y170399D03*
X1306626D03*
X1303407Y183349D03*
X1309817Y175949D03*
X1300212Y174099D03*
X1313037Y170399D03*
X1300207Y177799D03*
X1303422Y172249D03*
X1313033Y174099D03*
X1306622D03*
X1300207Y185199D03*
X1306617Y181499D03*
Y185199D03*
X1309832Y172249D03*
X1313027Y181499D03*
Y185199D03*
X1303407Y175949D03*
Y179649D03*
X1306617Y177799D03*
X1309817Y179649D03*
X1300204Y181499D03*
X1309817Y194449D03*
X1306617Y188899D03*
X1303407Y194449D03*
X1306617Y196299D03*
X1300207D03*
X1303407Y190749D03*
Y187049D03*
X1300207Y192599D03*
X1309817Y187049D03*
X1306617Y192599D03*
X1313023Y199999D03*
X1306617D03*
X1300207D03*
X1303407Y201849D03*
X1300204Y188899D03*
X1313027Y192599D03*
X1309817Y190749D03*
X1313025Y188899D03*
X1309817Y198149D03*
X1303407D03*
X1300207Y203699D03*
Y207399D03*
X1303422Y209249D03*
X1313032Y214799D03*
X1306622Y218499D03*
X1303417Y212949D03*
Y216649D03*
X1300207Y214799D03*
X1313027Y203699D03*
X1300220Y218499D03*
X1309833Y220349D03*
X1303416Y205549D03*
X1306614Y203699D03*
X1306627Y214799D03*
X1316242Y209249D03*
X1300207Y211099D03*
X1303422Y220349D03*
X1301151Y225450D03*
X1309828Y224049D03*
X1306622Y222199D03*
X1300220D03*
X1313033D03*
X1303425Y224049D03*
X1309100Y236477D03*
X1300493Y238062D03*
X1314184Y849978D03*
X1313920Y854584D03*
X1312266Y857972D03*
X1312070Y877014D03*
X1310221Y880219D03*
X1308370Y877014D03*
X1312070Y896240D03*
X1310220Y893036D03*
X1308371Y902649D03*
X1312070Y915466D03*
X1308370D03*
X1308371Y921875D03*
X1312070Y934692D03*
X1308371Y941100D03*
X1308370Y934692D03*
X1312070Y953917D03*
X1308370D03*
X1310221Y957122D03*
X1308371Y973143D03*
X1310221Y976347D03*
X1307426Y978814D03*
X1311491Y985939D03*
X1314352Y996480D03*
X1314353Y1002888D03*
X1308803Y1006093D03*
X1314353Y1015705D03*
Y1022114D03*
X1308803Y1025318D03*
Y1018910D03*
X1314353Y1041340D03*
X1308803Y1044544D03*
X1310653Y1041340D03*
X1314353Y1060565D03*
X1309976Y1062790D03*
X1305774Y1092168D03*
X1312502Y1082995D03*
X1314353Y1111834D03*
Y1105426D03*
X1311486Y1097289D03*
X1314353Y1124651D03*
X1312503Y1115039D03*
Y1127856D03*
X1319452Y162999D03*
X1316242Y168549D03*
X1319442Y159299D03*
X1316241Y157449D03*
X1320469Y155288D03*
X1322652Y161149D03*
X1316242D03*
X1319452Y166699D03*
X1329062Y168549D03*
X1316242Y164849D03*
X1322652D03*
X1329062D03*
X1326918Y161161D03*
X1329062Y157449D03*
X1322652D03*
X1319442Y170399D03*
X1318502Y176574D03*
Y186024D03*
Y182874D03*
X1329062Y172249D03*
X1316237D03*
X1331102Y176574D03*
X1327952Y186024D03*
Y182874D03*
X1315352Y186024D03*
Y179724D03*
X1319442Y174099D03*
X1332268D03*
X1318502Y189174D03*
X1315352Y195474D03*
X1327952Y189174D03*
X1331102Y195474D03*
X1327952Y198624D03*
X1321652D03*
X1315405Y189227D03*
X1325852Y214799D03*
X1319442Y218499D03*
X1329062Y209249D03*
X1319442Y207399D03*
X1329062Y216649D03*
X1319442Y211099D03*
X1324802Y204924D03*
X1327952D03*
X1318502D03*
X1315352D03*
X1322652Y209249D03*
X1325857Y218499D03*
X1322652Y216649D03*
X1319442Y222199D03*
X1329061Y224049D03*
X1329062Y220349D03*
X1325856Y222199D03*
X1322652Y224049D03*
Y220349D03*
X1326377Y235784D03*
X1321986Y236726D03*
X1326869Y844971D03*
X1323170D03*
X1321320Y848176D03*
X1330571Y851380D03*
X1323170D03*
X1319469D03*
X1321320Y854584D03*
X1317620D03*
X1315770Y857789D03*
X1328721Y854584D03*
X1330571Y864197D03*
X1326871D03*
X1323171D03*
Y857789D03*
X1325020Y854584D03*
X1321321Y860993D03*
X1319469Y857789D03*
X1317621Y867401D03*
X1328721D03*
X1325021D03*
X1330571Y877014D03*
X1328722Y880219D03*
X1323171Y870606D03*
X1326871Y877014D03*
X1321321Y873810D03*
X1315771Y877014D03*
X1317621Y873810D03*
X1321321Y880219D03*
X1319471Y877014D03*
X1315771Y883423D03*
X1326871D03*
X1323171D03*
X1326871Y870606D03*
X1330571D03*
X1328720Y873810D03*
X1330571Y883423D03*
X1323171Y877014D03*
X1325020Y880219D03*
X1328720Y899445D03*
X1315771Y896240D03*
Y889832D03*
X1328720Y893036D03*
Y886627D03*
X1325021D03*
X1323171Y889832D03*
X1321321Y893036D03*
X1319470Y896240D03*
X1321321Y899445D03*
X1328720Y905853D03*
X1325020D03*
X1317621Y912262D03*
X1317620Y905853D03*
X1328720Y912262D03*
X1323171Y909057D03*
Y902649D03*
X1321321Y912262D03*
X1315771Y915466D03*
X1319471D03*
X1328720Y925079D03*
Y918670D03*
X1325020Y925079D03*
X1317620D03*
X1323171Y928283D03*
Y921875D03*
X1321321Y918670D03*
X1317621Y931488D03*
X1328720D03*
X1321321D03*
X1323171Y941100D03*
X1325020Y944304D03*
X1323171Y947509D03*
X1317620Y944304D03*
X1328720D03*
Y937896D03*
X1315771Y934692D03*
X1321321Y937896D03*
X1319470Y934692D03*
X1321321Y957122D03*
X1323171Y966735D03*
X1325020Y963530D03*
X1323171Y960326D03*
X1321321Y950713D03*
X1315771Y953917D03*
Y966735D03*
X1319470Y953917D03*
X1319471Y966735D03*
X1319470Y960326D03*
X1317621Y950713D03*
X1328720Y957122D03*
Y963530D03*
Y950713D03*
X1321321Y969939D03*
X1325020Y982756D03*
X1323171Y979552D03*
X1321321Y976347D03*
X1315771Y973143D03*
X1319471D03*
X1328720Y969939D03*
X1330570Y973143D03*
X1326871D03*
X1328720Y982756D03*
X1328721Y976347D03*
X1315771Y979552D03*
X1318053Y1009297D03*
Y1002888D03*
X1327304Y1006093D03*
X1331003D03*
X1329153Y1009297D03*
Y1002888D03*
X1323603Y999684D03*
X1321753Y1009297D03*
X1319903Y1006093D03*
X1321753Y1002888D03*
X1323603Y1012501D03*
X1319903Y999684D03*
X1329153Y1028523D03*
Y1015705D03*
X1318053Y1022114D03*
Y1015705D03*
X1329153Y1022114D03*
X1325453Y1015705D03*
X1323603Y1018910D03*
X1321753Y1028523D03*
X1319903Y1018910D03*
X1321753Y1022114D03*
Y1015705D03*
X1319903Y1031727D03*
X1323603D03*
X1329153Y1034931D03*
Y1047749D03*
X1318053Y1041340D03*
X1319903Y1038136D03*
X1329153Y1041340D03*
X1325453Y1034931D03*
X1323603Y1038136D03*
X1321753Y1041340D03*
X1319903Y1044544D03*
X1321753Y1047749D03*
X1329153Y1060565D03*
Y1054157D03*
X1325453D03*
X1319903Y1057361D03*
Y1050952D03*
X1323603D03*
Y1057361D03*
X1321753Y1060565D03*
X1319903Y1063770D03*
X1329153Y1073383D03*
X1319903Y1076587D03*
Y1070178D03*
X1316204Y1076587D03*
X1329153Y1066974D03*
X1323603Y1076587D03*
Y1070178D03*
X1325454Y1073383D03*
X1321753Y1066974D03*
X1329153Y1079791D03*
X1321753D03*
X1318053D03*
X1329153Y1086200D03*
Y1092608D03*
X1325452Y1092609D03*
X1323603Y1089404D03*
X1321752Y1086200D03*
X1319902Y1082995D03*
X1319849Y1091513D03*
X1316202Y1082995D03*
X1316203Y1095813D03*
X1331003Y1108630D03*
X1329153Y1099017D03*
X1323603Y1108630D03*
X1316203D03*
Y1102221D03*
X1325453Y1099017D03*
X1323603Y1102221D03*
X1319903D03*
X1329153Y1105426D03*
X1325454Y1111834D03*
X1327303Y1102221D03*
X1321753Y1111834D03*
X1318054D03*
X1318053Y1105426D03*
X1327304Y1108630D03*
X1329154Y1111834D03*
X1331003Y1102221D03*
X1319904Y1108630D03*
X1321753Y1105426D03*
X1316203Y1115039D03*
X1331003D03*
X1327303Y1121447D03*
Y1115039D03*
X1325453Y1124651D03*
X1325454Y1118243D03*
X1321753D03*
X1319903Y1115039D03*
X1318053Y1124651D03*
X1323603Y1115039D03*
X1329152Y1137469D03*
X1329153Y1131060D03*
X1321752Y1137469D03*
X1321753Y1131060D03*
X1325453D03*
X1319903Y1134264D03*
X1339727Y161149D03*
X1341992Y156897D03*
X1344103Y155288D03*
X1342936Y159301D03*
X1335472Y161149D03*
X1346137Y168549D03*
X1342907Y166699D03*
X1332268D03*
X1346137Y164849D03*
X1339727D03*
X1335472Y168549D03*
X1332268Y162999D03*
X1342903Y170399D03*
X1339727Y168549D03*
X1335472Y164849D03*
X1346140Y161149D03*
X1342937Y162999D03*
X1335472Y157449D03*
X1346140D03*
X1339727D03*
X1339568Y176028D03*
X1339727Y179649D03*
X1342937Y181499D03*
Y185199D03*
X1346137Y172249D03*
X1335472D03*
X1334252Y176574D03*
X1339727Y183349D03*
X1346137Y175949D03*
X1342937Y177799D03*
X1346137Y183349D03*
X1339727Y190749D03*
X1342937Y188899D03*
X1334252Y195474D03*
X1346137Y194449D03*
Y190749D03*
X1337901Y196035D03*
X1339727Y187049D03*
X1337345Y201831D03*
X1339727Y201849D03*
X1337402Y198624D03*
X1342937Y192599D03*
X1346137Y187049D03*
X1346147Y201849D03*
Y198149D03*
X1336527Y214799D03*
X1339727Y216649D03*
X1346147Y212949D03*
Y216649D03*
X1336527Y218499D03*
X1342937D03*
Y214799D03*
X1346147Y209248D03*
X1337102Y206675D03*
X1332262Y218499D03*
Y214799D03*
X1339686Y205478D03*
X1332262Y207399D03*
X1339727Y209249D03*
Y220349D03*
X1336527Y222199D03*
X1346147Y220349D03*
X1332285Y226210D03*
X1342937Y222199D03*
X1332267D03*
X1343521Y841467D03*
X1336121D03*
X1345371Y851380D03*
X1341671D03*
X1337971D03*
X1334271D03*
X1345371Y864197D03*
X1343521Y854584D03*
X1341671Y864197D03*
X1337971D03*
X1336121Y854584D03*
X1334271Y864197D03*
X1343521Y867401D03*
X1336121D03*
X1347220D03*
X1332420D03*
X1339820D03*
X1345371Y877014D03*
X1343521Y880219D03*
X1341671Y877014D03*
X1337971D03*
X1336121Y880219D03*
X1334271Y877014D03*
Y870606D03*
X1337971D03*
X1341671D03*
X1336120Y873810D03*
X1343520D03*
X1345371Y870606D03*
X1332420Y880219D03*
X1334271Y883423D03*
X1339820Y880219D03*
X1341671Y883423D03*
X1347220Y880219D03*
X1337971Y883423D03*
X1345371D03*
X1332420Y886627D03*
X1345371Y896240D03*
Y889832D03*
X1341671Y896240D03*
Y889832D03*
X1337970Y896240D03*
X1337971Y889832D03*
X1336121Y893036D03*
X1334270Y889832D03*
X1336121Y899445D03*
X1347220D03*
X1339821Y893036D03*
X1343521D03*
X1336120Y886627D03*
X1343520D03*
X1332420Y905853D03*
X1341671Y909057D03*
Y902649D03*
X1336120Y912262D03*
X1334270Y909057D03*
X1334271Y902649D03*
X1347221Y912262D03*
X1345371Y915466D03*
X1341671D03*
X1337970D03*
X1332421Y925079D03*
X1341671Y928283D03*
Y921875D03*
X1336121Y918670D03*
X1334270Y928283D03*
X1334271Y921875D03*
X1347220Y918670D03*
X1336120Y931488D03*
X1347221D03*
X1341671Y947509D03*
Y941100D03*
X1334270Y947509D03*
X1334271Y941100D03*
X1332421Y944304D03*
X1345371Y934691D03*
X1341671D03*
X1337970D03*
X1336121Y937896D03*
X1347220D03*
X1337971Y953917D03*
X1345371D03*
X1341671D03*
Y960326D03*
X1347220Y957122D03*
X1343520Y963530D03*
X1339821D03*
X1341670Y966735D03*
X1347221Y950713D03*
X1334271Y960326D03*
X1336121Y957122D03*
X1332421Y963530D03*
X1334270Y966735D03*
X1336120Y950713D03*
X1347221Y969939D03*
X1337970Y973143D03*
X1347220Y976347D03*
X1345371Y973143D03*
X1341671Y979552D03*
Y973143D03*
X1336120Y969939D03*
X1336121Y976347D03*
X1334271Y979552D03*
X1332421Y982756D03*
X1345804Y1006093D03*
X1342104Y999684D03*
Y1006093D03*
X1338403D03*
X1336553Y1009297D03*
X1336554Y1002888D03*
X1334704Y999684D03*
X1347654Y1009297D03*
X1342103Y1012501D03*
X1334703D03*
X1343953Y1002888D03*
X1332854Y1015705D03*
X1345804Y1025318D03*
X1343953Y1015705D03*
X1342104Y1025318D03*
Y1018910D03*
X1340254Y1015705D03*
X1336553Y1028523D03*
X1338403Y1025318D03*
X1336554Y1022114D03*
X1334704Y1018910D03*
X1347653Y1028523D03*
Y1022114D03*
X1342104Y1031727D03*
X1334703D03*
X1332854Y1034931D03*
X1345804Y1044544D03*
X1342104D03*
Y1038136D03*
X1338403Y1044544D03*
X1336554Y1041340D03*
X1334704Y1038136D03*
X1347653Y1041340D03*
X1336553Y1047749D03*
X1347653D03*
X1332854Y1054157D03*
X1342104Y1057361D03*
Y1050952D03*
X1336554Y1060565D03*
X1334704Y1057361D03*
X1334703Y1050952D03*
X1347653Y1060565D03*
X1345804Y1063770D03*
X1342104D03*
X1338403D03*
X1332854Y1073383D03*
X1342104Y1070178D03*
Y1076587D03*
X1336553Y1066974D03*
X1334703Y1070178D03*
X1334704Y1076587D03*
X1347654Y1066974D03*
X1336554Y1079791D03*
X1347653D03*
X1345804Y1082995D03*
X1342104Y1089404D03*
Y1082995D03*
X1338403D03*
X1336553Y1086200D03*
X1334703Y1089404D03*
X1332854Y1092608D03*
X1347654Y1086200D03*
X1342104Y1095813D03*
X1334703D03*
X1342104Y1102221D03*
X1338404D03*
X1336553Y1099017D03*
X1332853Y1105426D03*
Y1099017D03*
X1347654Y1105426D03*
Y1099017D03*
X1340254Y1111834D03*
X1332854D03*
X1347654D03*
X1343953Y1118243D03*
X1340253D03*
X1338403Y1115039D03*
X1336553Y1118243D03*
X1332853D03*
X1347653D03*
X1342104Y1127856D03*
X1334703D03*
X1343953Y1131060D03*
X1342103Y1140973D03*
X1340254Y1131060D03*
X1336554D03*
X1334703Y1140973D03*
X1332854Y1131060D03*
X1347653D03*
X1352550Y157449D03*
X1349351Y159298D03*
X1355758D03*
X1355761Y162998D03*
X1358865Y166732D03*
Y158854D03*
Y162793D03*
X1349351Y166698D03*
X1352557Y164848D03*
X1355961Y155458D03*
X1352557Y168548D03*
X1355762Y166698D03*
X1349344Y162999D03*
X1348386Y156646D03*
X1352551Y161148D03*
X1358865Y170671D03*
Y174603D03*
Y182484D03*
Y178544D03*
X1355761Y170398D03*
Y177798D03*
X1352557Y179648D03*
Y172248D03*
X1349351Y177798D03*
Y170398D03*
Y174098D03*
X1358371Y188778D03*
X1358865Y195240D03*
Y199180D03*
X1349351Y196298D03*
X1352561Y194448D03*
X1352551Y190748D03*
X1349345Y188898D03*
X1355761Y192598D03*
X1349351D03*
X1352551Y187048D03*
X1355761Y188898D03*
X1349361Y199998D03*
X1352561Y201848D03*
X1355766Y214798D03*
X1349351Y218498D03*
X1352561Y216648D03*
X1355766Y218498D03*
X1358865Y207060D03*
Y203120D03*
Y213994D03*
Y217934D03*
X1352560Y205549D03*
X1355765Y207399D03*
X1349351Y214798D03*
X1352561Y212948D03*
X1349351Y211098D03*
X1352561Y220348D03*
X1355766Y222198D03*
X1349351D03*
X1360186Y226264D03*
X1358321Y841467D03*
X1350921D03*
X1360171Y851380D03*
X1356471D03*
X1352771D03*
X1349071D03*
X1363871D03*
X1360171Y864197D03*
X1358321Y854584D03*
X1356471Y864197D03*
X1352771D03*
X1350921Y854584D03*
X1349071Y864197D03*
X1363871D03*
X1358321Y867401D03*
X1350921D03*
X1354620D03*
X1362020D03*
Y860993D03*
X1354620D03*
X1360171Y877014D03*
X1358321Y880219D03*
X1356471Y877014D03*
X1352771D03*
X1350921Y880219D03*
X1349071Y877014D03*
X1363871D03*
Y870606D03*
X1349071D03*
X1356471D03*
X1350920Y873810D03*
X1352771Y870606D03*
X1358320Y873810D03*
X1360171Y870606D03*
X1349071Y883423D03*
X1354620Y880219D03*
X1356471Y883423D03*
X1362020Y880219D03*
X1363871Y883423D03*
X1352771D03*
X1360171D03*
X1362020Y873810D03*
X1360171Y889832D03*
X1356471D03*
X1354621Y893036D03*
X1352771Y889832D03*
X1349071D03*
X1363871Y896240D03*
Y889832D03*
X1362021Y899445D03*
X1354620D03*
X1350920Y886627D03*
X1358320D03*
X1362020D03*
Y912262D03*
X1360170Y909057D03*
X1360171Y902649D03*
X1358321Y905853D03*
X1354620Y912262D03*
Y905853D03*
X1350920D03*
X1349071Y909057D03*
X1349070Y902649D03*
X1363870Y915466D03*
X1363871Y909057D03*
Y902649D03*
X1362020Y905853D03*
X1362021Y918670D03*
X1360170Y928283D03*
X1360171Y921875D03*
X1358321Y925079D03*
X1354620D03*
Y918670D03*
X1350920Y925079D03*
X1349071Y928283D03*
X1349070Y921875D03*
X1362020Y931488D03*
X1354620D03*
X1363871Y921875D03*
Y928283D03*
X1362020Y925079D03*
X1360171Y941100D03*
X1358321Y944304D03*
X1354620D03*
X1360170Y947509D03*
X1350920Y944304D03*
X1349071Y947509D03*
X1349070Y941100D03*
X1362021Y937896D03*
X1354620D03*
X1363870Y934691D03*
X1363871Y947509D03*
Y941100D03*
X1362020Y944304D03*
X1363871Y953917D03*
X1360171Y960326D03*
X1362021Y957122D03*
X1354620D03*
X1358321Y963530D03*
X1354620D03*
X1360170Y966735D03*
X1354620Y950713D03*
X1362020D03*
X1349070Y960326D03*
X1350920Y963530D03*
X1349071Y966735D03*
X1363871Y960326D03*
Y966735D03*
X1362020Y963530D03*
Y969939D03*
X1354620D03*
X1363870Y973143D03*
X1362021Y976347D03*
X1360171Y979552D03*
X1358321Y982756D03*
X1356470Y973143D03*
X1354620Y982756D03*
X1354621Y976347D03*
X1350920Y982756D03*
X1349070Y979552D03*
X1352771Y973143D03*
X1362020Y982756D03*
X1363871Y979552D03*
X1352771D03*
X1356471D03*
X1350920Y976347D03*
X1358320D03*
X1349071Y973143D03*
X1360171D03*
X1351352Y996480D03*
X1349503Y999684D03*
X1362453Y1009297D03*
X1362454Y1002888D03*
X1360604Y999684D03*
X1355053Y1009297D03*
Y1002888D03*
X1360603Y1012501D03*
X1349504D03*
X1362453Y1028523D03*
X1362454Y1022114D03*
X1360604Y1018910D03*
X1358754Y1015705D03*
X1355053Y1028523D03*
Y1022114D03*
Y1015705D03*
X1351353D03*
X1349503Y1018910D03*
X1360603Y1031727D03*
X1349504D03*
X1362453Y1015705D03*
X1362454Y1041340D03*
X1360604Y1038136D03*
X1358754Y1034931D03*
X1355053Y1041340D03*
Y1034931D03*
X1351353D03*
X1349503Y1038136D03*
X1362453Y1047749D03*
X1355053D03*
X1362453Y1034931D03*
X1362454Y1060565D03*
X1360604Y1057361D03*
X1360603Y1050952D03*
X1358754Y1054157D03*
X1355053Y1060565D03*
Y1054157D03*
X1351353D03*
X1349503Y1057361D03*
X1349504Y1050952D03*
X1362453Y1054157D03*
Y1066974D03*
X1360604Y1076587D03*
X1360603Y1070178D03*
X1358754Y1073383D03*
X1355053D03*
Y1066974D03*
X1351353Y1073383D03*
X1349503Y1076587D03*
X1349504Y1070178D03*
X1362453Y1079791D03*
X1355053D03*
X1362453Y1073383D03*
Y1086200D03*
X1360603Y1089404D03*
X1358753Y1092608D03*
X1355053D03*
Y1086200D03*
X1351353Y1092608D03*
X1349504Y1089404D03*
X1360604Y1095813D03*
X1349504D03*
X1362453Y1092608D03*
X1351354Y1099017D03*
X1362454D03*
X1360604Y1102221D03*
X1356904Y1108630D03*
X1355053Y1099017D03*
X1353204Y1102221D03*
X1349503Y1108630D03*
Y1102221D03*
X1362453Y1111834D03*
Y1105426D03*
X1358753D03*
X1351353Y1111834D03*
Y1105426D03*
X1358753Y1111834D03*
X1360604Y1108630D03*
X1355053Y1111834D03*
X1356904Y1102221D03*
X1353204Y1108630D03*
X1355054Y1105426D03*
X1362453Y1118243D03*
X1360603Y1115039D03*
X1358753Y1118243D03*
X1355053D03*
X1353203Y1115039D03*
X1351353Y1118243D03*
X1349503Y1115039D03*
X1356903Y1127856D03*
X1349503D03*
X1356904Y1115039D03*
X1362453Y1131060D03*
X1358753D03*
X1356903Y1140973D03*
X1355053Y1131060D03*
X1351353D03*
X1349503Y1140973D03*
X1373121Y841467D03*
X1365721D03*
X1378671Y851380D03*
X1374971D03*
X1371271D03*
X1367571D03*
X1378671Y864197D03*
X1374971D03*
X1373121Y854584D03*
X1371271Y864197D03*
X1367571D03*
X1365721Y854584D03*
X1373121Y867401D03*
X1365721D03*
X1376820D03*
X1369420D03*
Y860993D03*
X1378671Y877014D03*
X1374971D03*
X1373121Y880219D03*
X1371271Y877014D03*
X1367571D03*
X1365721Y880219D03*
X1367571Y870606D03*
X1371271D03*
X1378671D03*
X1365720Y873810D03*
X1373120D03*
X1374971Y870606D03*
X1369420Y880219D03*
X1371271Y883423D03*
X1376820Y880219D03*
X1378671Y883423D03*
X1367571D03*
X1374971D03*
X1369420Y873810D03*
X1376820D03*
X1378671Y889832D03*
X1374971D03*
X1371271Y896240D03*
Y889832D03*
X1367570Y896240D03*
X1367571Y889832D03*
X1365721Y893036D03*
X1373120Y899445D03*
X1378671Y896240D03*
X1376820Y899445D03*
X1365720D03*
X1369420D03*
X1369421Y893036D03*
X1373121D03*
X1373120Y886627D03*
X1365720D03*
X1374971Y896240D03*
X1376820Y893036D03*
X1369420Y886627D03*
X1376820D03*
X1380520Y899445D03*
X1374971Y909057D03*
X1374970Y902649D03*
X1373121Y912262D03*
X1367571Y909057D03*
Y902649D03*
X1371271Y915466D03*
X1367571D03*
X1376820Y905853D03*
X1378671Y915466D03*
Y909057D03*
X1365720Y912262D03*
X1369420D03*
X1371271Y909057D03*
Y902649D03*
X1369420Y905853D03*
X1365720D03*
X1373120D03*
X1376820Y912262D03*
X1378671Y902649D03*
X1376820Y931488D03*
X1378671Y928283D03*
X1376820Y925079D03*
X1374971Y928283D03*
X1374970Y921875D03*
X1373120Y918670D03*
X1367571Y928283D03*
Y921875D03*
X1373120Y931488D03*
X1369420D03*
X1371271Y928283D03*
X1365720Y918670D03*
X1371271Y921875D03*
X1369420Y918670D03*
X1365720Y931488D03*
X1369420Y925079D03*
X1365720D03*
X1373120D03*
X1378671Y921875D03*
X1374971Y934691D03*
X1378671D03*
X1376820Y937896D03*
X1374970Y941100D03*
X1373120Y937896D03*
X1371271Y934691D03*
X1367571Y941100D03*
Y934691D03*
X1374971Y947509D03*
X1367571D03*
X1371271D03*
X1365720Y937896D03*
X1371271Y941100D03*
X1369420Y937896D03*
Y944304D03*
X1365720D03*
X1373120D03*
X1376820Y957122D03*
X1374970Y960326D03*
X1373120Y957122D03*
X1373121Y950713D03*
X1371271Y953917D03*
X1367571Y960326D03*
Y953917D03*
X1376820Y963530D03*
X1374971Y966735D03*
X1367571D03*
X1365720Y957122D03*
X1371271Y960326D03*
X1369420Y957122D03*
X1371271Y966735D03*
X1365720Y950713D03*
X1369420D03*
X1373120Y963530D03*
X1369420D03*
X1365720D03*
X1378671Y966735D03*
Y960326D03*
X1376820Y982756D03*
Y969939D03*
X1374970Y979552D03*
X1373120Y976347D03*
X1373121Y969939D03*
X1371271Y973143D03*
X1367571Y979552D03*
Y973143D03*
X1369420Y982756D03*
X1365720D03*
X1373120D03*
X1369420Y976347D03*
X1371271Y979552D03*
X1365721Y976347D03*
X1365720Y969939D03*
X1369420D03*
X1364303Y1006093D03*
X1377253Y1002888D03*
X1373554Y1009297D03*
X1373553Y1002888D03*
X1371704Y1006093D03*
X1368004D03*
Y999684D03*
X1375404Y1012501D03*
X1368003D03*
X1375404Y1006093D03*
X1379104D03*
X1375404Y999684D03*
X1379104D03*
X1364304Y1012501D03*
X1371704D03*
X1366153Y1009297D03*
X1369853D03*
X1377253D03*
X1379104Y1012501D03*
Y1031727D03*
X1364303Y1025318D03*
X1375403Y1018910D03*
X1373553Y1028523D03*
Y1022114D03*
X1371704Y1025318D03*
X1369853Y1015705D03*
X1368004Y1025318D03*
Y1018910D03*
X1366154Y1015705D03*
X1375404Y1031727D03*
X1368004D03*
X1373553Y1015705D03*
X1364304Y1031727D03*
X1366153Y1028523D03*
X1371704Y1031727D03*
X1369853Y1028523D03*
X1366153Y1022114D03*
X1364304Y1018910D03*
X1369853Y1022114D03*
X1371704Y1018910D03*
X1377253Y1028523D03*
Y1015705D03*
X1364303Y1044544D03*
X1375403Y1038136D03*
X1373553Y1041340D03*
X1371704Y1044544D03*
X1368004D03*
Y1038136D03*
X1373553Y1047749D03*
X1366153Y1041340D03*
X1364304Y1038136D03*
X1369853Y1041340D03*
X1371704Y1038136D03*
X1366153Y1047749D03*
X1369853D03*
Y1034931D03*
X1366153D03*
X1373553D03*
X1379104Y1038136D03*
X1377253Y1047749D03*
X1375403Y1057361D03*
X1375404Y1050952D03*
X1373553Y1060565D03*
X1368004Y1057361D03*
Y1050952D03*
X1364303Y1063770D03*
X1371704D03*
X1368004D03*
X1366153Y1060565D03*
X1364304Y1057361D03*
X1369853Y1060565D03*
X1371704Y1057361D03*
X1364304Y1050952D03*
X1371704D03*
X1369853Y1054157D03*
X1366153D03*
X1373553D03*
X1379104Y1057361D03*
Y1063770D03*
X1377255Y1060565D03*
X1375404Y1063770D03*
X1377253Y1054157D03*
X1379104Y1050952D03*
X1380953Y1054157D03*
X1379104Y1076587D03*
Y1070178D03*
X1377253Y1073383D03*
X1375403Y1076587D03*
X1375404Y1070178D03*
X1373554Y1066974D03*
X1368004Y1076587D03*
Y1070178D03*
X1377253Y1079791D03*
X1373553D03*
X1366153D03*
X1364304Y1076587D03*
X1369853Y1079791D03*
X1371704Y1076587D03*
X1364304Y1070178D03*
X1366153Y1066974D03*
X1371704Y1070178D03*
X1369853Y1066974D03*
Y1073383D03*
X1366153D03*
X1373553D03*
X1377254Y1066974D03*
X1364303Y1082995D03*
X1377254Y1092608D03*
X1377253Y1086200D03*
X1375404Y1089404D03*
X1373554Y1086200D03*
X1371704Y1082995D03*
X1368004Y1089404D03*
Y1082995D03*
X1379104Y1095813D03*
X1375403D03*
X1368004D03*
X1371704D03*
X1364304Y1089404D03*
X1366153Y1086200D03*
X1371704Y1089404D03*
X1369853Y1086200D03*
X1364304Y1095813D03*
X1369853Y1092608D03*
X1366153D03*
X1373553D03*
X1379104Y1082995D03*
X1379103Y1089404D03*
X1364304Y1108630D03*
Y1102221D03*
X1377253Y1105426D03*
X1375404Y1102221D03*
X1373554Y1099017D03*
X1371704Y1102221D03*
X1366153Y1105426D03*
X1373553Y1111834D03*
X1366153D03*
X1369853Y1099017D03*
X1366153D03*
X1364303Y1115039D03*
X1377253Y1118243D03*
X1373553D03*
X1371703Y1115039D03*
X1369853Y1118243D03*
X1366153D03*
X1364303Y1127856D03*
X1379103D03*
X1371703D03*
X1375404Y1121447D03*
X1364303Y1140973D03*
X1379103D03*
X1377253Y1131060D03*
X1373553D03*
X1371703Y1140973D03*
X1369853Y1131060D03*
X1366153D03*
X1380521Y841467D03*
X1395321D03*
X1387921D03*
X1393471Y851380D03*
X1389771D03*
X1386071D03*
X1382371D03*
X1380521Y854584D03*
X1395321D03*
X1393471Y864197D03*
X1389771D03*
X1387921Y854584D03*
X1386071Y864197D03*
X1382371D03*
X1380521Y867401D03*
X1395321D03*
X1387921D03*
X1384220D03*
X1391620D03*
X1380521Y880219D03*
X1395321D03*
X1393471Y877014D03*
X1389771D03*
X1387921Y880219D03*
X1386071Y877014D03*
Y870606D03*
X1382371Y877014D03*
X1380520Y873810D03*
X1382371Y870606D03*
X1384220Y880219D03*
X1386071Y883423D03*
X1382371D03*
X1395320Y873810D03*
X1393471Y870606D03*
X1387920Y873810D03*
X1389771Y870606D03*
X1384220Y873810D03*
X1395321Y893036D03*
X1393471Y889832D03*
X1389771D03*
X1387921Y893036D03*
X1386071Y889832D03*
X1384221Y893036D03*
X1382371Y889832D03*
X1380520Y886627D03*
X1387920D03*
X1380520Y893036D03*
X1382371Y896240D03*
X1384220Y886627D03*
X1391620D03*
Y899445D03*
X1384221Y899446D03*
X1386071Y902649D03*
X1380520Y912262D03*
Y905853D03*
X1395320Y912262D03*
X1395321Y905853D03*
X1393471Y902649D03*
X1389771D03*
X1386071Y909057D03*
Y915466D03*
X1393471Y909057D03*
X1382371D03*
X1389771D03*
Y915466D03*
X1399020Y905853D03*
X1382371Y915466D03*
X1384220Y918670D03*
X1387920Y905853D03*
X1384220D03*
Y912262D03*
X1382371Y902649D03*
X1391620Y905853D03*
X1387920Y912262D03*
X1391620D03*
X1393471Y915466D03*
X1391621Y918670D03*
X1380520D03*
X1395187Y926265D03*
X1395320Y918670D03*
X1386071Y921875D03*
X1381189Y930811D03*
X1382371Y921875D03*
X1382809Y927986D03*
X1385070Y928468D03*
X1393471Y921875D03*
X1391550Y925219D03*
X1387921Y918670D03*
X1381189Y938045D03*
X1381287Y946239D03*
Y948539D03*
X1381189Y935745D03*
X1390234Y942097D03*
X1386030Y942163D03*
X1383730D03*
X1381430D03*
X1381264Y965896D03*
Y963596D03*
X1390506Y971139D03*
X1392896D03*
X1381003Y981269D03*
Y978969D03*
Y986421D03*
X1381243Y992971D03*
Y995271D03*
X1381003Y988721D03*
X1393716Y985579D03*
X1391326D03*
X1381369Y1007156D03*
X1381373Y1004848D03*
X1391326Y1014539D03*
X1393716D03*
Y1000059D03*
X1391326D03*
X1381128Y1022427D03*
X1381140Y1026821D03*
X1384466Y1034270D03*
Y1031970D03*
X1393904Y1044544D03*
X1384653Y1041340D03*
X1380953Y1047749D03*
X1388353D03*
Y1041340D03*
X1392053D03*
X1395753D03*
Y1047749D03*
X1392053D03*
X1382804Y1044544D03*
X1386504D03*
X1384653Y1047749D03*
X1390204Y1044544D03*
X1382804Y1050952D03*
X1380953Y1060565D03*
X1393904Y1050952D03*
X1392053Y1060565D03*
Y1054157D03*
X1388353Y1060565D03*
X1386504Y1050952D03*
X1384653Y1054157D03*
X1382804Y1057361D03*
X1386504D03*
X1390204Y1050952D03*
X1393904Y1057361D03*
X1395753Y1054157D03*
X1382804Y1063770D03*
X1384653Y1060565D03*
X1386504Y1063770D03*
X1388353Y1054157D03*
X1390204Y1057361D03*
X1393904Y1063770D03*
X1390204D03*
X1395753Y1060565D03*
Y1079791D03*
X1384653Y1073383D03*
X1382804Y1070178D03*
X1380953Y1073383D03*
Y1066974D03*
X1395753Y1073383D03*
X1392053Y1066974D03*
X1386504Y1076587D03*
Y1070178D03*
X1382803Y1076587D03*
X1380953Y1079791D03*
X1388353D03*
X1393904Y1076587D03*
X1384653Y1066974D03*
X1388353Y1073383D03*
X1392053D03*
X1390204Y1070178D03*
X1393904D03*
X1388353Y1066974D03*
X1395753D03*
X1384653Y1079791D03*
X1393903Y1089404D03*
Y1082995D03*
X1392053Y1092608D03*
X1392054Y1086200D03*
X1388353Y1092608D03*
X1384653Y1086200D03*
X1386504Y1095813D03*
X1382804D03*
X1395754Y1099017D03*
X1390203Y1095813D03*
X1388353Y1086200D03*
X1386504Y1082995D03*
X1390204Y1089404D03*
X1382804D03*
X1390204Y1082995D03*
X1382804D03*
X1395753Y1086200D03*
Y1092608D03*
X1380953Y1086200D03*
X1386504Y1089404D03*
X1384653Y1092608D03*
X1380954Y1105426D03*
X1393904Y1102221D03*
X1392054Y1099017D03*
X1390204Y1108630D03*
X1388353Y1099017D03*
X1386504Y1102221D03*
X1382803Y1108630D03*
Y1102221D03*
X1380954Y1111834D03*
X1380953Y1118243D03*
X1393903Y1115039D03*
X1392053Y1118243D03*
X1390203Y1121447D03*
X1388353Y1124651D03*
Y1118243D03*
X1386503Y1115039D03*
X1384653Y1118243D03*
X1382803Y1115039D03*
X1386503Y1127856D03*
X1382803Y1121447D03*
X1390204Y1127856D03*
X1380953Y1131060D03*
X1390204Y1134264D03*
X1388354Y1131060D03*
X1386503Y1140973D03*
X1384653Y1131060D03*
X1388354Y1137469D03*
X1408269Y844971D03*
X1402721Y841467D03*
X1397171Y851380D03*
X1408271D03*
X1404571D03*
X1400871D03*
X1411971D03*
X1397171Y864197D03*
X1408271D03*
X1404571D03*
X1402721Y854584D03*
X1400871Y864197D03*
X1410121Y854584D03*
X1411971Y864197D03*
X1410121Y867401D03*
X1402721D03*
X1406420D03*
X1399020D03*
X1397171Y877014D03*
X1410121Y880219D03*
X1408271Y877014D03*
X1404571D03*
X1402721Y880219D03*
X1400871Y877014D03*
X1411971D03*
X1408271Y870606D03*
X1402720Y873810D03*
X1400871Y870606D03*
X1410121Y873810D03*
X1404571Y870606D03*
X1397171D03*
X1411971D03*
X1406420Y873810D03*
X1397171Y889832D03*
X1410121Y893036D03*
X1408271Y889832D03*
X1404571D03*
X1402721Y893036D03*
X1400871Y889832D03*
X1411971D03*
X1406420Y886627D03*
X1399020D03*
X1406420Y899445D03*
X1399020D03*
Y912262D03*
X1400871Y915466D03*
X1402720Y912262D03*
X1400871Y902649D03*
X1397171D03*
X1408271D03*
X1404571Y909057D03*
Y902649D03*
X1411971D03*
X1404571Y915466D03*
X1406420Y912262D03*
X1408271Y915466D03*
X1397171Y909057D03*
X1411971D03*
Y915466D03*
X1408270Y909057D03*
X1410120Y905853D03*
X1400870Y909057D03*
X1406420Y905853D03*
X1402720D03*
X1397171Y915466D03*
X1410121Y912262D03*
X1406420Y918670D03*
X1410121Y925079D03*
Y931488D03*
X1404571Y921875D03*
X1408271D03*
X1410121Y918670D03*
X1411971Y921875D03*
X1401528Y927155D03*
X1399028D03*
X1401817Y929464D03*
X1399317D03*
X1400871Y921875D03*
X1399020Y918670D03*
X1397171Y921875D03*
X1402720Y918670D03*
X1411971Y934691D03*
X1406420Y925079D03*
X1408271Y928283D03*
X1406420Y931488D03*
X1411971Y928283D03*
X1403016Y949498D03*
Y947198D03*
X1406420Y937896D03*
X1404016Y936469D03*
X1410120Y937896D03*
X1410121Y944304D03*
X1408271Y934691D03*
X1403046Y963634D03*
Y965934D03*
X1410121Y957122D03*
Y950713D03*
Y963530D03*
X1403046Y978035D03*
Y980335D03*
X1410121Y976347D03*
Y969939D03*
Y982756D03*
X1403046Y992421D03*
Y994721D03*
Y1009174D03*
Y1006874D03*
X1410553Y1009297D03*
Y1002888D03*
X1403046Y1021962D03*
Y1019662D03*
X1410553Y1028523D03*
Y1022114D03*
Y1015705D03*
X1405004Y1044544D03*
X1410553Y1034931D03*
X1406854Y1047749D03*
X1399453D03*
X1403153D03*
X1403154Y1041340D03*
X1399454D03*
X1401304Y1044544D03*
X1397604D03*
X1403153Y1054157D03*
X1406853D03*
X1408703Y1050952D03*
X1401304Y1057361D03*
X1410553Y1060565D03*
Y1054157D03*
X1397604Y1063770D03*
X1405003Y1057361D03*
X1408703D03*
Y1063770D03*
X1397604Y1057361D03*
X1401304Y1050952D03*
X1399453Y1054157D03*
X1405004Y1050952D03*
X1397604D03*
X1401304Y1063770D03*
X1399453Y1060565D03*
X1403153D03*
X1405003Y1063770D03*
X1406853Y1060565D03*
X1397604Y1076587D03*
X1408703D03*
X1406853Y1073383D03*
X1403153D03*
Y1066974D03*
X1401304Y1076587D03*
X1399453Y1066974D03*
X1410553Y1073383D03*
Y1066974D03*
X1403154Y1079791D03*
X1410553D03*
X1408702Y1070178D03*
X1399453Y1073383D03*
X1397604Y1070178D03*
X1401304D03*
X1405004D03*
X1406853Y1066974D03*
X1408703Y1089404D03*
Y1082995D03*
X1405003D03*
X1401304Y1089404D03*
X1397604Y1082995D03*
X1410553Y1092608D03*
Y1086200D03*
X1408703Y1095813D03*
X1405003D03*
X1397604D03*
X1401304Y1082995D03*
X1405003Y1089404D03*
X1399453Y1086200D03*
X1406853Y1092608D03*
X1399453D03*
X1397604Y1089404D03*
X1403154Y1086200D03*
X1406852D03*
X1403153Y1092608D03*
X1401304Y1095813D03*
X1403153Y1099017D03*
X1401303Y1102221D03*
X1399453Y1105426D03*
X1397604Y1108630D03*
X1410553Y1105426D03*
X1399453Y1111834D03*
X1410553D03*
X1399453Y1124651D03*
Y1118243D03*
X1397604Y1115039D03*
X1410553Y1124651D03*
Y1118243D03*
X1399454Y1137469D03*
X1399453Y1131060D03*
X1410554Y1137769D03*
X1410553Y1131060D03*
X1428620Y848176D03*
X1415669Y844971D03*
X1421220Y848176D03*
X1417520D03*
X1426771Y851380D03*
X1423070D03*
X1419370D03*
X1415671D03*
X1413822Y860993D03*
X1426771Y864197D03*
X1424921Y854584D03*
X1423071Y864197D03*
X1419371D03*
X1417521Y854584D03*
X1415671Y864197D03*
Y857789D03*
X1424921Y867401D03*
X1417521D03*
X1428620D03*
X1421220D03*
X1413820D03*
X1426771Y877014D03*
X1424921Y880219D03*
X1423071Y877014D03*
X1419371D03*
X1417521Y880219D03*
X1415671Y877014D03*
X1424921Y873810D03*
X1423071Y870606D03*
X1417520Y873810D03*
X1415671Y870606D03*
X1426771D03*
X1419371D03*
X1413821Y873810D03*
X1428621D03*
X1421220D03*
X1413820Y886627D03*
X1426771Y889832D03*
X1424921Y893036D03*
X1423071Y889832D03*
X1419371D03*
X1417521Y893036D03*
X1415671Y896240D03*
Y889832D03*
X1413821Y899445D03*
X1428620D03*
Y886627D03*
X1421220D03*
X1413820Y912262D03*
X1413821Y905853D03*
X1426771Y902649D03*
X1423071Y909057D03*
Y902649D03*
X1419371D03*
X1415670D03*
X1423071Y915466D03*
X1419371Y909057D03*
X1415671Y915466D03*
X1421221Y905853D03*
X1417521D03*
X1430471Y909057D03*
X1426772D03*
X1428621Y905853D03*
X1424921D03*
X1424922Y912262D03*
X1417522D03*
X1415671Y909057D03*
X1421222Y912262D03*
X1419371Y915466D03*
X1426771D03*
X1428620Y912262D03*
X1424921Y918670D03*
X1430471Y915466D03*
X1415671Y921875D03*
X1423071Y928283D03*
X1417520Y925079D03*
Y931488D03*
X1413820Y918670D03*
X1423071Y921875D03*
X1417520Y918670D03*
X1426771Y921875D03*
X1421220Y918670D03*
X1419371Y921875D03*
X1428620Y918670D03*
X1424921Y931488D03*
X1419371Y928283D03*
X1413820Y931488D03*
X1424921Y925079D03*
X1419371Y934691D03*
X1421220Y931488D03*
Y925079D03*
X1415671Y928283D03*
X1413820Y925079D03*
X1426771Y928283D03*
X1424920Y937896D03*
X1421220D03*
X1417520D03*
X1413820D03*
X1423070Y941100D03*
X1423071Y947509D03*
Y934691D03*
X1415671D03*
X1423071Y960326D03*
Y953917D03*
Y966735D03*
Y979552D03*
Y973143D03*
X1423503Y1006093D03*
Y999684D03*
Y1012501D03*
Y1025318D03*
Y1018910D03*
Y1031727D03*
X1429053Y1041340D03*
X1427203Y1044544D03*
X1423503Y1038136D03*
X1425353Y1047749D03*
X1429053D03*
Y1060565D03*
X1423503Y1057361D03*
Y1050952D03*
Y1063770D03*
X1425353Y1054157D03*
X1425355Y1060565D03*
X1427203Y1063770D03*
X1429053Y1054157D03*
X1427203Y1050952D03*
X1430903D03*
X1430904Y1057361D03*
X1427204D03*
X1425353Y1073383D03*
X1423503Y1076587D03*
Y1070178D03*
X1429053Y1079791D03*
X1425353D03*
X1429053Y1073383D03*
X1427203Y1076587D03*
X1429053Y1066974D03*
X1425353D03*
X1427204Y1070178D03*
X1429053Y1092608D03*
X1427204Y1089404D03*
X1425354Y1086200D03*
X1423503Y1082995D03*
X1427203Y1095812D03*
X1429053Y1086200D03*
X1427202Y1082995D03*
X1429053Y1099017D03*
X1423503Y1108630D03*
Y1102221D03*
Y1121447D03*
Y1115039D03*
Y1127856D03*
Y1134264D03*
X1437871Y851380D03*
X1434171D03*
X1430470D03*
X1432321Y841467D03*
X1439721D03*
X1445271Y851380D03*
X1441571D03*
X1439721Y854584D03*
X1432321D03*
X1437871Y864197D03*
X1434171D03*
X1430471D03*
X1445271D03*
X1441571D03*
X1432321Y867401D03*
X1439721D03*
X1443420D03*
X1436020D03*
X1437871Y877014D03*
X1434171D03*
X1432321Y880219D03*
X1430471Y877014D03*
X1445271D03*
X1441571D03*
X1439721Y880219D03*
X1445271Y870606D03*
X1439720Y873810D03*
X1437871Y870606D03*
X1432320Y873810D03*
X1430471Y870606D03*
X1441571D03*
X1434171D03*
X1437871Y889832D03*
X1434171D03*
X1432321Y893036D03*
X1430471Y889832D03*
X1445271Y896240D03*
X1439721Y893036D03*
X1445271Y889832D03*
X1441571D03*
X1447120Y899445D03*
X1437871Y902649D03*
X1434171D03*
X1432320Y912262D03*
Y905853D03*
X1430471Y902649D03*
X1441571D03*
Y909057D03*
Y915466D03*
X1445271Y902649D03*
X1434171Y909057D03*
X1437871Y915466D03*
X1443420Y912262D03*
X1445271Y915466D03*
X1437871Y909057D03*
X1434171Y915466D03*
X1436020Y918670D03*
X1439720Y912262D03*
X1436020D03*
Y905853D03*
X1439720D03*
X1443420D03*
X1445271Y909057D03*
X1430244Y931358D03*
Y933658D03*
X1437871Y921875D03*
X1432320Y918670D03*
X1430471Y921875D03*
X1443420Y918670D03*
X1439777Y928348D03*
X1437477D03*
X1435177D03*
X1444377D03*
X1442077D03*
X1445271Y921875D03*
X1439720Y918670D03*
X1441571Y921875D03*
X1434171D03*
X1438402Y942151D03*
X1440702D03*
X1443002D03*
X1430564Y949138D03*
X1445392Y942195D03*
X1440015Y956539D03*
X1430564Y951438D03*
X1442413Y956539D03*
X1430534Y963828D03*
Y966128D03*
X1440015Y971139D03*
X1442413Y971099D03*
X1430404Y981208D03*
Y978908D03*
X1440015Y985579D03*
X1430604Y995298D03*
Y992998D03*
X1442413Y985579D03*
X1440015Y1014539D03*
Y1000059D03*
X1430584Y1009408D03*
Y1007108D03*
X1442413Y1014539D03*
Y1000059D03*
X1430575Y1022185D03*
Y1019885D03*
X1434083Y1031908D03*
X1443541Y1036914D03*
X1436453Y1041340D03*
X1442003Y1044544D03*
X1432753Y1047749D03*
X1440153D03*
X1447553Y1041340D03*
X1443853D03*
X1436453Y1047750D03*
X1443853D03*
X1430904Y1044544D03*
Y1038136D03*
X1434083Y1034408D03*
X1434813Y1037069D03*
X1439413D03*
X1437113D03*
X1432753Y1041340D03*
X1440153D03*
X1438304Y1044544D03*
X1434604D03*
X1432753Y1060565D03*
X1438303Y1057361D03*
X1432753Y1054157D03*
X1442004Y1057361D03*
X1438304Y1050952D03*
X1434604Y1063770D03*
X1442004D03*
X1438303D03*
X1442002Y1050952D03*
X1440153Y1054157D03*
X1436454D03*
X1434604Y1057361D03*
X1430903Y1063770D03*
X1440154Y1060565D03*
X1434603Y1050952D03*
X1436453Y1060565D03*
X1432753Y1073383D03*
X1430903Y1076587D03*
X1430904Y1070178D03*
X1443853Y1073383D03*
Y1066974D03*
X1438304Y1070178D03*
X1432754Y1079791D03*
X1443853D03*
X1436453Y1073383D03*
X1434602Y1070178D03*
X1436453Y1066974D03*
X1440153D03*
X1442002Y1070178D03*
X1447553Y1066974D03*
X1440154Y1079791D03*
X1436454D03*
X1438304Y1076587D03*
X1432753Y1066974D03*
X1442004Y1076587D03*
X1440153Y1073383D03*
X1434604Y1076587D03*
X1434603Y1082995D03*
X1432753Y1086200D03*
X1436453Y1092608D03*
X1443854Y1086200D03*
X1440153D03*
X1443854Y1092608D03*
X1438303Y1095812D03*
X1434603D03*
X1442003Y1089403D03*
X1432754Y1092607D03*
X1430903Y1089403D03*
X1436454Y1086199D03*
X1430902Y1082995D03*
X1442003Y1095812D03*
X1440154Y1092607D03*
X1430903Y1095812D03*
X1434603Y1089403D03*
X1438303D03*
X1436454Y1105426D03*
X1434604Y1102221D03*
X1432753Y1099017D03*
X1442003Y1108630D03*
Y1102221D03*
X1440154Y1105426D03*
Y1099017D03*
X1438304Y1108630D03*
X1440154Y1111834D03*
X1443853Y1105426D03*
Y1111834D03*
X1436454Y1099016D03*
X1434604Y1121447D03*
Y1115039D03*
X1443854Y1124651D03*
X1443853Y1118243D03*
X1442004Y1121447D03*
Y1115039D03*
X1434604Y1127856D03*
Y1134264D03*
X1454521Y841467D03*
X1447121D03*
X1460071Y851380D03*
X1452671D03*
X1456371D03*
X1448971D03*
X1460071Y864197D03*
X1456371D03*
X1454521Y854584D03*
X1452671Y864197D03*
X1447121Y854584D03*
X1448971Y864197D03*
X1454521Y867401D03*
X1447121D03*
X1450820D03*
X1458220D03*
X1460071Y877014D03*
X1456371D03*
X1454521Y880219D03*
X1452671Y877014D03*
X1448971D03*
X1448970Y870606D03*
X1447121Y880219D03*
Y873810D03*
X1456371Y870606D03*
X1452671D03*
X1454520Y873810D03*
X1460071Y870606D03*
X1450820Y880219D03*
X1452671Y883423D03*
X1458220Y880219D03*
X1460071Y883423D03*
X1448971D03*
X1456371D03*
X1456370Y896240D03*
X1456371Y889832D03*
X1454521Y893036D03*
X1447121D03*
X1460071Y889832D03*
X1452671D03*
X1448971D03*
X1458220Y899445D03*
X1450820D03*
Y893036D03*
X1448971Y896240D03*
X1458220Y893036D03*
X1460071Y896240D03*
X1454520Y886627D03*
Y899445D03*
X1452671Y896240D03*
X1456371Y902649D03*
X1460071Y909057D03*
X1458221Y912262D03*
X1450820D03*
Y905853D03*
X1460070Y902649D03*
X1460071Y915466D03*
X1456371D03*
X1447122Y912262D03*
X1454521Y918670D03*
X1452671Y915466D03*
X1454522Y912262D03*
X1448971Y902649D03*
X1456370Y909057D03*
X1452671Y902649D03*
X1448970Y915466D03*
X1447120Y905853D03*
X1454520D03*
X1448971Y909057D03*
X1452671D03*
X1456371Y928283D03*
X1454522Y931488D03*
X1454520Y925079D03*
X1458220D03*
X1452426Y930125D03*
X1460071Y928283D03*
X1458220Y918670D03*
X1456371Y921875D03*
X1460070D03*
X1452670D03*
X1450820Y918670D03*
X1458220Y931488D03*
X1448971Y921875D03*
X1447120Y918670D03*
X1446677Y928348D03*
X1454520Y937896D03*
X1456371Y941100D03*
X1452426Y934725D03*
X1454520Y944304D03*
X1452321Y945354D03*
Y947654D03*
X1460070Y941100D03*
X1458221Y944304D03*
X1458220Y937896D03*
X1456371Y934691D03*
X1460070Y947509D03*
X1460071Y934691D03*
X1449992Y942195D03*
X1447692D03*
X1452426Y962325D03*
Y960025D03*
Y964625D03*
X1460070Y960326D03*
X1458220Y957122D03*
X1458221Y950713D03*
X1460071Y966735D03*
X1454520Y963530D03*
X1456371Y966735D03*
X1458220Y963529D03*
X1460071Y953917D03*
X1456370Y960326D03*
X1452426Y966925D03*
X1452333Y977669D03*
X1452476Y980736D03*
X1458221Y969939D03*
X1460070Y979552D03*
X1458220Y976347D03*
X1460071Y973143D03*
X1458220Y982756D03*
X1454521Y969939D03*
X1456371Y979552D03*
X1454520Y982756D03*
X1456371Y973143D03*
X1454520Y976347D03*
X1452426Y996825D03*
Y994525D03*
Y989925D03*
Y987625D03*
X1452436Y1010499D03*
X1452426Y1006025D03*
Y1003725D03*
Y1012925D03*
X1460503Y999684D03*
X1458654Y1009297D03*
X1458653Y1002888D03*
X1460504Y1012501D03*
X1456804Y999684D03*
X1454953Y1002888D03*
Y1009297D03*
X1456804Y1012501D03*
X1460504Y1006093D03*
X1452416Y1022635D03*
X1452426Y1017525D03*
X1458653Y1028523D03*
Y1022114D03*
X1460503Y1018910D03*
Y1031727D03*
X1460504Y1025318D03*
X1456804Y1031727D03*
Y1025318D03*
X1458653Y1015705D03*
X1447424Y1036526D03*
X1449649Y1035928D03*
X1458653Y1041340D03*
X1458654Y1034931D03*
X1451253Y1041340D03*
X1460503Y1038136D03*
X1458653Y1047749D03*
X1447553D03*
X1460504Y1044544D03*
X1451253Y1047749D03*
X1445704Y1044544D03*
X1454953Y1034931D03*
X1456804Y1038136D03*
X1454953Y1041340D03*
X1456804Y1044544D03*
X1449404D03*
X1460503Y1057361D03*
X1458653Y1060565D03*
X1456804Y1050952D03*
X1451253Y1060565D03*
X1447553Y1054157D03*
X1460504Y1050952D03*
Y1063770D03*
X1460503Y1076587D03*
X1451253Y1066974D03*
X1449404Y1070178D03*
X1460504D03*
X1458654Y1066974D03*
X1454953Y1073383D03*
X1458653Y1079791D03*
X1454954D03*
X1451253D03*
X1454953Y1066974D03*
X1445702Y1070178D03*
X1453104Y1076587D03*
X1456804D03*
Y1070178D03*
X1453104D03*
X1447553Y1073383D03*
X1449404Y1076587D03*
X1445704D03*
X1447553Y1079791D03*
X1451253Y1073383D03*
X1458653D03*
X1445703Y1089404D03*
X1458654Y1086200D03*
X1456804Y1082995D03*
X1453104Y1089404D03*
X1449404Y1082995D03*
X1460504Y1089404D03*
X1445704Y1095813D03*
X1460504D03*
X1456803D03*
X1460504Y1082995D03*
X1454954Y1092607D03*
X1451254D03*
X1449403Y1089403D03*
X1447554Y1086199D03*
X1453103Y1082994D03*
X1458654Y1092607D03*
X1453103Y1095812D03*
X1447554Y1092607D03*
X1451254Y1086199D03*
X1454954D03*
X1445704Y1102221D03*
X1458653Y1105426D03*
X1456804Y1108630D03*
X1454953Y1099017D03*
X1449404Y1108630D03*
X1453104Y1102221D03*
X1451254Y1099017D03*
X1447553D03*
X1458653Y1111834D03*
X1460504Y1108630D03*
X1451253Y1111834D03*
X1447553D03*
X1454953Y1105426D03*
X1445704Y1108630D03*
X1449404Y1102221D03*
X1458653Y1099017D03*
X1454953Y1111834D03*
X1453104Y1108630D03*
X1447553Y1105426D03*
X1451253D03*
X1460504Y1102221D03*
X1445703Y1115039D03*
X1458653Y1118243D03*
X1456803Y1115039D03*
X1454953Y1118243D03*
X1453103Y1115039D03*
X1451253Y1118243D03*
X1447553D03*
X1445704Y1127856D03*
X1460503D03*
X1453103D03*
X1460504Y1115039D03*
X1449404D03*
X1445703Y1140973D03*
X1458653Y1131060D03*
X1454953D03*
X1453103Y1140973D03*
X1451253Y1131060D03*
X1447554Y1137469D03*
Y1131060D03*
X1449403Y1134264D03*
X1460503Y1140973D03*
X1469321Y841467D03*
X1461921D03*
X1476721D03*
X1474871Y851380D03*
X1471171D03*
X1467471D03*
X1463771D03*
X1461921Y854584D03*
X1474871Y864197D03*
X1471171D03*
X1469321Y854584D03*
X1467471Y864197D03*
X1463771D03*
X1476721Y854584D03*
X1461921Y867401D03*
X1476721D03*
X1469321D03*
X1465620D03*
X1473020D03*
X1461921Y880219D03*
X1471171Y877014D03*
X1476721Y880219D03*
X1474871Y877014D03*
X1469321Y880219D03*
X1467471Y877014D03*
X1463771D03*
Y870606D03*
X1471171D03*
X1461920Y873810D03*
X1467471Y870606D03*
X1469320Y873810D03*
X1474871Y870606D03*
X1476720Y873810D03*
X1465620Y880219D03*
X1467471Y883423D03*
X1473020Y880219D03*
X1474871Y883423D03*
X1463771D03*
X1471171D03*
X1474871Y889832D03*
X1465621Y893036D03*
X1476721D03*
X1474871Y896240D03*
X1471171Y889832D03*
X1467471D03*
X1463771D03*
X1473021Y899445D03*
X1465620D03*
X1461920D03*
X1469320D03*
Y893036D03*
X1473020D03*
X1461920D03*
X1467471Y896240D03*
X1463771D03*
X1471171D03*
X1461920Y886627D03*
X1469320D03*
X1476720D03*
X1461920Y905853D03*
X1473020Y912262D03*
X1471171Y909057D03*
X1465620Y912262D03*
Y905853D03*
X1471171Y902649D03*
X1469321Y905853D03*
X1474870Y915466D03*
X1461920Y912262D03*
X1463771Y909057D03*
X1469320Y912262D03*
X1467471Y909057D03*
X1463771Y902649D03*
X1467471D03*
X1463771Y915466D03*
X1471171D03*
X1467471D03*
X1461920Y925079D03*
X1471170Y928283D03*
X1469321Y925079D03*
X1465620D03*
Y918670D03*
X1473021D03*
X1471171Y921875D03*
X1473020Y931488D03*
X1465620D03*
X1467471Y921875D03*
X1469320Y918670D03*
X1461920Y931488D03*
X1467471Y928283D03*
X1469320Y931488D03*
X1463771Y928283D03*
Y921875D03*
X1461920Y918670D03*
Y944304D03*
X1474871Y934691D03*
X1473021Y937896D03*
X1471171Y941100D03*
X1469321Y944304D03*
X1465620D03*
Y937896D03*
X1471170Y947509D03*
X1463771D03*
X1467471D03*
X1463771Y941100D03*
X1461920Y937896D03*
X1467471Y941100D03*
X1469320Y937896D03*
X1463771Y934691D03*
X1471171D03*
X1467471D03*
X1474871Y953917D03*
X1473021Y957122D03*
X1471171Y960326D03*
X1465620Y957122D03*
Y950713D03*
X1473020D03*
X1461920Y963530D03*
X1476721D03*
X1471170Y966735D03*
X1469321Y963530D03*
X1465620D03*
X1463771Y966735D03*
X1467471D03*
X1474871D03*
X1473020Y963530D03*
X1461920Y950713D03*
X1469320D03*
X1467471Y960326D03*
X1469320Y957122D03*
X1463771Y960326D03*
X1461920Y957122D03*
X1471171Y953917D03*
X1463771D03*
X1467471D03*
X1473021Y976347D03*
X1473020Y969939D03*
X1465620Y976347D03*
Y969939D03*
X1474870Y973143D03*
X1471171Y979552D03*
X1461920Y982756D03*
X1469321D03*
X1465620D03*
X1471171Y973143D03*
X1463771D03*
X1467471D03*
X1461920Y969939D03*
X1469320D03*
X1476720D03*
X1475303Y1006093D03*
X1473453Y1009297D03*
X1473454Y1002888D03*
X1471604Y999684D03*
X1466053Y1009297D03*
X1466054Y1002888D03*
X1467903Y1006093D03*
X1464204D03*
X1471603Y1012501D03*
X1471604Y1006093D03*
X1462353Y1002888D03*
X1469753D03*
X1464204Y999684D03*
X1467904D03*
X1467903Y1012501D03*
X1469753Y1009297D03*
X1464204Y1012501D03*
X1462353Y1009297D03*
Y1015705D03*
X1473453Y1028523D03*
X1466053D03*
Y1022114D03*
Y1015705D03*
X1477154D03*
X1475303Y1025318D03*
X1473453Y1022114D03*
X1471604Y1018910D03*
X1469754Y1015705D03*
X1471603Y1031727D03*
X1464204D03*
X1462353Y1028523D03*
X1467904Y1031727D03*
X1469753Y1028523D03*
X1462353Y1022114D03*
X1464204Y1018910D03*
X1469753Y1022114D03*
X1467904Y1018910D03*
X1464204Y1025318D03*
X1471604D03*
X1467904D03*
X1462353Y1034931D03*
X1473454Y1041340D03*
X1466053D03*
Y1034931D03*
X1475303Y1044544D03*
X1471604Y1038136D03*
X1469754Y1034931D03*
X1466053Y1047749D03*
X1473453D03*
X1462353D03*
X1469753D03*
X1462353Y1041340D03*
X1464204Y1038136D03*
X1469753Y1041340D03*
X1467904Y1038136D03*
X1464204Y1044544D03*
X1471604D03*
X1467904D03*
X1462353Y1054157D03*
X1473453Y1060565D03*
X1471604Y1057361D03*
X1466053Y1060565D03*
Y1054157D03*
X1471603Y1050952D03*
X1469753Y1054157D03*
X1475304Y1063770D03*
X1462353Y1060565D03*
X1464204Y1057361D03*
X1469753Y1060565D03*
X1467904Y1057361D03*
X1464204Y1050952D03*
X1467904D03*
X1464204Y1063770D03*
X1471604D03*
X1467904D03*
X1462353Y1073383D03*
X1471604Y1076587D03*
X1469754Y1073383D03*
X1466053Y1066974D03*
X1473453D03*
X1471603Y1070178D03*
X1466053Y1073383D03*
X1473454Y1079791D03*
X1466053D03*
X1462353D03*
X1464204Y1076587D03*
X1469753Y1079791D03*
X1467904Y1076587D03*
X1464204Y1070178D03*
X1462353Y1066974D03*
X1467904Y1070178D03*
X1469753Y1066974D03*
X1462353Y1092608D03*
X1475303Y1082995D03*
X1473453Y1086200D03*
X1469754Y1092608D03*
X1466053D03*
Y1086200D03*
X1471603Y1089404D03*
X1475304Y1095813D03*
X1471604D03*
X1467904D03*
Y1089404D03*
X1469753Y1086200D03*
X1464204Y1089404D03*
X1462353Y1086200D03*
X1471604Y1082995D03*
X1464204D03*
X1467904D03*
X1462353Y1105426D03*
X1462354Y1099017D03*
X1475303Y1108630D03*
Y1102221D03*
X1473454Y1105426D03*
X1469753D03*
X1467904Y1102221D03*
X1464203D03*
X1473454Y1111834D03*
X1466053D03*
Y1099017D03*
X1471604Y1102221D03*
X1477153Y1099017D03*
X1469753D03*
X1473453D03*
X1471604Y1108630D03*
X1466053Y1105426D03*
X1462353Y1111834D03*
X1469753D03*
X1467904Y1108630D03*
X1464204D03*
X1477154Y1105426D03*
Y1111833D03*
X1462353Y1118243D03*
X1477153D03*
X1475303Y1115039D03*
X1473453Y1118243D03*
X1471604Y1121447D03*
X1469754Y1118243D03*
X1466053D03*
X1475303Y1127856D03*
X1467903D03*
X1467904Y1115039D03*
X1471604D03*
X1462353Y1131060D03*
X1477153D03*
X1475303Y1140973D03*
X1473453Y1131060D03*
X1469753D03*
X1466053D03*
X1467903Y1140973D03*
X1491521Y841467D03*
X1484121D03*
X1478571Y851380D03*
X1482271D03*
X1489671D03*
X1485971D03*
X1493371D03*
X1478571Y864197D03*
X1491521Y854584D03*
X1489671Y864197D03*
X1485971D03*
X1482271D03*
X1493371D03*
X1491521Y867401D03*
X1484121D03*
Y854584D03*
X1487820Y867401D03*
X1480420D03*
X1478571Y877014D03*
X1491521Y880219D03*
X1485971Y877014D03*
X1484121Y880219D03*
X1489671Y877014D03*
X1482271D03*
X1493371D03*
Y870606D03*
X1478571D03*
X1485971D03*
X1489671D03*
X1491520Y873810D03*
X1482271Y870606D03*
X1484120Y873810D03*
X1487820Y880219D03*
X1489671Y883423D03*
X1480420Y880219D03*
X1482271Y883423D03*
X1485971D03*
X1493371D03*
X1478571D03*
X1478570Y896240D03*
X1478571Y889832D03*
X1491521Y893036D03*
X1482271Y889832D03*
X1489671D03*
X1485971D03*
X1482270Y896240D03*
X1480421Y893036D03*
X1493371Y889832D03*
X1491520Y899445D03*
X1484120D03*
X1491520Y886627D03*
X1484120D03*
X1478571Y909057D03*
Y902649D03*
X1491520Y912262D03*
X1487820Y905853D03*
X1485971Y909057D03*
X1484121Y912262D03*
X1491520Y905853D03*
X1485970Y902649D03*
X1478571Y915466D03*
X1482271D03*
X1478571Y928283D03*
Y921875D03*
X1491520Y925079D03*
Y918670D03*
X1487820Y925079D03*
X1485971Y928283D03*
X1485970Y921875D03*
X1484120Y918670D03*
X1491520Y931488D03*
X1484121D03*
X1478571Y941100D03*
Y934691D03*
X1491520Y944304D03*
Y937896D03*
X1487820Y944304D03*
X1485970Y941100D03*
X1484120Y937896D03*
X1482271Y934691D03*
X1478571Y947509D03*
X1485971D03*
X1478571Y960326D03*
Y953917D03*
X1491520Y957122D03*
Y950713D03*
X1485970Y960326D03*
X1484120Y957122D03*
X1482271Y953917D03*
X1484121Y950713D03*
X1478570Y966735D03*
X1491520Y963530D03*
X1485971Y966735D03*
X1487820Y963530D03*
X1480420D03*
X1482271Y966735D03*
X1484120Y963530D03*
X1478571Y979552D03*
Y973143D03*
X1491521Y976347D03*
X1491520Y969939D03*
X1484120Y976347D03*
X1484121Y969939D03*
X1489671Y973143D03*
X1485970Y979552D03*
X1482271Y973143D03*
X1493370D03*
X1491520Y982756D03*
X1487820D03*
X1480420Y969939D03*
X1479004Y999684D03*
X1486403D03*
X1484553Y1002888D03*
X1482704Y1006093D03*
X1479003Y1012501D03*
X1486404D03*
X1491953Y1009297D03*
Y1002888D03*
X1484554Y1009297D03*
X1479004Y1006093D03*
Y1025318D03*
Y1018910D03*
X1491953Y1028523D03*
Y1022114D03*
X1484553Y1028523D03*
X1486403Y1018910D03*
X1484553Y1022114D03*
X1482704Y1025318D03*
X1480853Y1015705D03*
X1479004Y1031727D03*
X1486404D03*
X1488253Y1015705D03*
X1491953D03*
X1479004Y1044544D03*
Y1038136D03*
X1491953Y1034931D03*
Y1041340D03*
X1488253Y1034931D03*
X1486403Y1038136D03*
X1484553Y1041340D03*
X1482704Y1044544D03*
X1491953Y1047749D03*
X1484553D03*
X1479004Y1057361D03*
Y1050952D03*
X1491953Y1054157D03*
X1486404Y1057361D03*
X1484553Y1060565D03*
X1488253Y1054157D03*
X1486404Y1050952D03*
X1491953Y1060565D03*
X1479004Y1063770D03*
X1482704D03*
X1479004Y1076587D03*
Y1070178D03*
X1486404Y1076587D03*
Y1070178D03*
X1488253Y1073383D03*
X1484553Y1066974D03*
X1491953Y1073383D03*
Y1066974D03*
X1484553Y1079791D03*
X1491953D03*
X1479004Y1089404D03*
Y1082995D03*
X1488254Y1092608D03*
X1486404Y1089404D03*
X1484554Y1086200D03*
X1482704Y1082995D03*
X1491954Y1092608D03*
X1491953Y1086200D03*
X1479004Y1095813D03*
X1490103D03*
X1493804D03*
X1479004Y1102221D03*
X1490104Y1108630D03*
Y1102221D03*
X1488254Y1099017D03*
X1484553D03*
X1482704Y1108630D03*
X1480853Y1099017D03*
X1491953Y1105426D03*
Y1111834D03*
X1493804Y1108630D03*
X1479003Y1108629D03*
X1488254Y1105426D03*
X1484554Y1111833D03*
X1482703Y1102220D03*
X1480854Y1111833D03*
Y1105426D03*
X1486403Y1108630D03*
X1488254Y1111833D03*
X1484554Y1105426D03*
X1490103Y1115039D03*
X1488253Y1118243D03*
X1484553D03*
X1480853D03*
X1486403Y1115039D03*
X1491953Y1118243D03*
X1490103Y1127856D03*
X1482703D03*
X1493804Y1115039D03*
X1482703Y1115038D03*
X1490103Y1140973D03*
X1488253Y1131060D03*
X1484553D03*
X1480853D03*
X1482703Y1140973D03*
X1491953Y1131060D03*
X1504471Y844671D03*
X1498921Y841467D03*
X1508171Y851380D03*
X1504471D03*
X1500771D03*
X1497071D03*
X1504471Y864197D03*
X1500771D03*
X1508170Y857789D03*
X1497071Y864197D03*
X1506321Y860993D03*
Y854584D03*
X1498921D03*
X1510021Y860993D03*
X1506320Y867401D03*
X1498921D03*
X1510021D03*
X1495220D03*
X1502621D03*
X1504471Y877014D03*
X1498921Y880219D03*
X1508171Y877014D03*
X1497071D03*
X1506321Y880219D03*
X1500771Y877014D03*
X1510021Y880219D03*
Y873810D03*
X1508170Y883423D03*
X1500771Y870606D03*
X1508171D03*
X1497071D03*
X1498920Y873810D03*
X1504471Y870606D03*
X1506321Y873810D03*
X1495220Y880219D03*
X1497071Y883423D03*
X1502621Y880219D03*
X1504471Y883423D03*
X1500771D03*
X1508171Y889832D03*
X1504471Y896240D03*
Y889832D03*
X1500771D03*
X1508171Y896240D03*
X1502621Y893036D03*
X1500771Y896240D03*
X1497071Y889832D03*
X1510021Y893036D03*
X1498921Y899445D03*
X1510021D03*
X1506320Y893036D03*
X1498920Y886627D03*
X1506321D03*
X1495221Y905853D03*
X1504471Y902649D03*
X1498920Y912262D03*
X1497070Y909057D03*
X1497071Y902649D03*
X1508171Y915466D03*
X1504471D03*
X1500770D03*
X1504471Y909057D03*
X1510021Y912262D03*
X1495221Y925079D03*
X1504471Y921875D03*
X1497070Y928283D03*
X1498921Y918670D03*
X1497071Y921875D03*
X1498920Y931488D03*
X1504471Y928283D03*
X1510021Y918670D03*
X1510020Y931488D03*
X1495221Y944304D03*
X1504471Y941100D03*
Y934691D03*
X1500770D03*
X1498921Y937896D03*
X1497071Y941100D03*
X1497070Y947509D03*
X1508171Y934691D03*
X1510021Y937896D03*
X1504471Y947509D03*
Y960326D03*
Y953917D03*
X1500771D03*
X1498921Y957122D03*
X1497071Y960326D03*
X1498920Y950713D03*
X1495221Y963530D03*
X1497070Y966735D03*
X1502621Y963530D03*
X1510021Y957122D03*
X1508171Y953917D03*
X1510021Y950713D03*
X1506320Y963530D03*
X1504471Y966735D03*
Y979552D03*
Y973143D03*
X1498921Y976347D03*
X1498920Y969939D03*
X1500770Y973143D03*
X1497071Y979552D03*
X1510021Y976347D03*
X1495221Y982756D03*
X1510043Y980606D03*
X1510021Y969939D03*
X1508171Y973143D03*
X1497503Y1012501D03*
Y999684D03*
X1504904Y1006093D03*
Y999684D03*
X1501203Y1006093D03*
X1499353Y1009297D03*
X1499354Y1002888D03*
X1510453Y1009297D03*
Y1002888D03*
X1508603Y1006093D03*
X1504903Y1012501D03*
X1504904Y1025318D03*
X1499353Y1028523D03*
X1501203Y1025318D03*
X1504904Y1031727D03*
X1497503D03*
X1495654Y1015705D03*
X1497504Y1018910D03*
X1499353Y1022114D03*
X1503054Y1015705D03*
X1504904Y1018910D03*
X1506753Y1015705D03*
X1510453Y1028523D03*
X1510452Y1022114D03*
X1508603Y1025318D03*
X1504904Y1044544D03*
X1501203D03*
X1499354Y1041340D03*
X1497504Y1038136D03*
X1495654Y1034931D03*
X1508604Y1044544D03*
X1499353Y1047749D03*
X1504904Y1038136D03*
X1510453Y1041340D03*
Y1047749D03*
X1504904Y1057361D03*
Y1050952D03*
X1499354Y1060565D03*
X1497504Y1057361D03*
X1497503Y1050952D03*
X1495654Y1054157D03*
X1504904Y1063770D03*
X1501203D03*
X1510453Y1060565D03*
X1508604Y1063770D03*
X1504904Y1076587D03*
Y1070178D03*
X1497504Y1076587D03*
X1497503Y1070178D03*
X1495654Y1073383D03*
X1499353Y1066974D03*
X1499354Y1079791D03*
X1510453Y1066974D03*
Y1079791D03*
X1499353Y1086200D03*
X1497503Y1089404D03*
X1495653Y1092608D03*
X1504904Y1089404D03*
Y1082995D03*
X1501203D03*
X1508604Y1082996D03*
X1510453Y1086200D03*
X1504903Y1095813D03*
X1503053Y1105426D03*
X1497503Y1102221D03*
X1495653Y1105426D03*
X1495654Y1099017D03*
X1508603Y1108630D03*
X1506754Y1111834D03*
X1499353D03*
X1503053Y1099017D03*
X1510453D03*
X1508602Y1102221D03*
X1497504Y1108630D03*
X1501204D03*
X1510453Y1111834D03*
X1499353Y1105426D03*
X1510453D03*
X1504904Y1108630D03*
X1495653Y1111834D03*
X1503053D03*
X1506753Y1124651D03*
Y1118243D03*
X1504904Y1121447D03*
X1499353Y1118243D03*
X1497503Y1115039D03*
X1495653Y1118243D03*
X1508603Y1115039D03*
X1504904Y1127856D03*
X1497503D03*
X1501204Y1115039D03*
X1504904D03*
X1508603Y1121446D03*
X1510453Y1124650D03*
X1508603Y1127855D03*
X1506754Y1137469D03*
X1506753Y1131060D03*
X1503053D03*
X1499353D03*
X1495653D03*
X1504904Y1134264D03*
X1497503Y1140973D03*
X1510453Y1131060D03*
X1511871Y844671D03*
X1513722Y848176D03*
X1511871Y851380D03*
X1521121Y860993D03*
Y854584D03*
X1515570Y864197D03*
X1513721Y854584D03*
Y860993D03*
X1521121Y867401D03*
X1517421D03*
X1513721D03*
X1511871Y870606D03*
X1522971D03*
X1517421Y873810D03*
X1511871Y883423D03*
X1517421Y880219D03*
X1522971Y883423D03*
X1511871Y889832D03*
X1513721Y893036D03*
X1517421Y886627D03*
X1521121D03*
X1513721D03*
X1526671Y889832D03*
X1513721Y899445D03*
X1524821Y912262D03*
X1511871Y909057D03*
Y902649D03*
X1513721Y912262D03*
X1515571Y909057D03*
X1524821Y905853D03*
X1513721D03*
X1519271Y909057D03*
X1511871Y928283D03*
Y921875D03*
X1519271Y928283D03*
X1515571D03*
X1513721Y918670D03*
X1524820Y925079D03*
X1513720D03*
X1524820Y931488D03*
X1513720D03*
X1511871Y941100D03*
X1513721Y937896D03*
X1524820Y944304D03*
X1513720D03*
X1511871Y947509D03*
X1525420Y949619D03*
X1519271Y947509D03*
X1515571D03*
X1525861Y962436D03*
X1511871Y960326D03*
X1513721Y957122D03*
Y950713D03*
X1511871Y966735D03*
X1524288Y965640D03*
X1513721Y963530D03*
X1515571Y979552D03*
X1513721Y982756D03*
X1511871Y973143D03*
X1517421Y969939D03*
X1515571Y973143D03*
X1519871Y984866D03*
X1516004Y1006092D03*
X1516003Y999684D03*
X1512303D03*
Y1006093D03*
X1519705Y1006092D03*
X1525396Y1000648D03*
X1512303Y1012501D03*
Y1025318D03*
X1516003Y1018910D03*
X1517854Y1015705D03*
X1525254D03*
X1521554D03*
X1514154D03*
X1512303Y1018910D03*
Y1031727D03*
X1525254Y1034931D03*
X1521554D03*
X1516004Y1044544D03*
X1516003Y1038136D03*
X1517853Y1034931D03*
X1514153D03*
X1512303Y1038136D03*
X1517853Y1054157D03*
X1514153D03*
X1512303Y1057361D03*
X1521553Y1054157D03*
X1514153Y1060565D03*
X1512303Y1050952D03*
X1525564Y1064850D03*
X1523404Y1070178D03*
X1514153Y1066974D03*
X1517853Y1073383D03*
X1521553Y1066974D03*
X1516003Y1076587D03*
X1512303D03*
X1512304Y1070178D03*
X1514153Y1073383D03*
X1523404Y1082996D03*
X1512304D03*
X1514153Y1092608D03*
X1512303Y1089404D03*
X1521553Y1092608D03*
X1523403Y1095813D03*
X1519703D03*
X1512303D03*
X1521554Y1105426D03*
X1517853D03*
X1516003Y1108630D03*
Y1102221D03*
X1512303D03*
X1517853Y1111834D03*
X1521553D03*
X1514153Y1105426D03*
X1512303Y1108630D03*
X1514153Y1111834D03*
X1519703Y1108630D03*
X1521553Y1124651D03*
Y1118243D03*
X1519704Y1115039D03*
X1516004D03*
X1514153Y1124651D03*
X1512303Y1115039D03*
X1519703Y1121446D03*
X1516003Y1127855D03*
X1512303D03*
Y1121446D03*
X1516003D03*
X1517853Y1124650D03*
X1519703Y1127855D03*
X1517854Y1131560D03*
X1512304Y1134264D03*
X1514154Y1131059D03*
X1527571Y979057D03*
X1526843Y972608D03*
X1527103Y1031726D03*
X1611475Y1259227D03*
X1714440Y1255381D03*
X1821083Y1252034D03*
G54D47*
X707677Y1714961D03*
X1155708D03*
G54D55*
X900196Y175197D03*
X944684Y155216D03*
G54D35*
X238780Y1681456D03*
X230906Y1677519D03*
Y1682244D03*
X238780Y1686180D03*
Y1709803D03*
Y1714527D03*
X230906Y1705866D03*
Y1710590D03*
X254528Y1681456D03*
X246654Y1677519D03*
Y1682244D03*
X254528Y1686180D03*
Y1709803D03*
Y1714527D03*
X246654Y1705866D03*
Y1710590D03*
X270276Y1681456D03*
X262402Y1677519D03*
Y1682244D03*
X270276Y1686180D03*
Y1709803D03*
Y1714527D03*
X262402Y1705866D03*
Y1710590D03*
X286024Y1681456D03*
X278150Y1677519D03*
Y1682244D03*
X286024Y1686180D03*
Y1709803D03*
Y1714527D03*
X278150Y1705866D03*
Y1710590D03*
X297835Y1677519D03*
Y1682244D03*
X305709Y1681456D03*
Y1686180D03*
X297835Y1705866D03*
Y1710590D03*
X305709Y1709803D03*
Y1714527D03*
X313583Y1677519D03*
Y1682244D03*
X321457Y1681456D03*
Y1686180D03*
X313583Y1705866D03*
Y1710590D03*
X321457Y1709803D03*
Y1714527D03*
X329331Y1677519D03*
Y1682244D03*
X337205Y1681456D03*
Y1686180D03*
X329331Y1705866D03*
Y1710590D03*
X337205Y1709803D03*
Y1714527D03*
X345079Y1677519D03*
Y1682244D03*
X352953Y1681456D03*
Y1686180D03*
X345079Y1705866D03*
Y1710590D03*
X352953Y1709803D03*
Y1714527D03*
X495079Y1691692D03*
Y1696417D03*
Y1720039D03*
Y1724763D03*
X510827Y1691692D03*
X502953Y1695629D03*
X510827Y1696417D03*
X502953Y1700354D03*
X510827Y1720039D03*
X502953Y1723976D03*
X510827Y1724763D03*
X502953Y1728700D03*
X526575Y1691692D03*
X518701Y1695629D03*
X526575Y1696417D03*
X534449Y1695629D03*
X518701Y1700354D03*
X534449D03*
X526575Y1720039D03*
X518701Y1723976D03*
X526575Y1724763D03*
X534449Y1723976D03*
X518701Y1728700D03*
X534449D03*
X542323Y1691692D03*
Y1696417D03*
X550197Y1695629D03*
Y1700354D03*
X542323Y1720039D03*
Y1724763D03*
X550197Y1723976D03*
Y1728700D03*
X562008Y1691692D03*
Y1696417D03*
Y1720039D03*
Y1724763D03*
X577756Y1691692D03*
X569882Y1695629D03*
X577756Y1696417D03*
X569882Y1700354D03*
X577756Y1720039D03*
X569882Y1723976D03*
X577756Y1724763D03*
X569882Y1728700D03*
X593504Y1691692D03*
X585630Y1695629D03*
X593504Y1696417D03*
X585630Y1700354D03*
X593504Y1720039D03*
X585630Y1723976D03*
X593504Y1724763D03*
X585630Y1728700D03*
X609252Y1691692D03*
X601378Y1695629D03*
X609252Y1696417D03*
X601378Y1700354D03*
X609252Y1720039D03*
X601378Y1723976D03*
X609252Y1724763D03*
X601378Y1728700D03*
X617126Y1695629D03*
Y1700354D03*
Y1723976D03*
Y1728700D03*
X1238780Y1677519D03*
Y1682244D03*
X1246654Y1681456D03*
Y1686180D03*
X1238780Y1705866D03*
Y1710590D03*
X1246654Y1709803D03*
Y1714527D03*
X1254528Y1677519D03*
Y1682244D03*
X1262402Y1681456D03*
Y1686180D03*
X1254528Y1705866D03*
Y1710590D03*
X1262402Y1709803D03*
Y1714527D03*
X1270276Y1677519D03*
Y1682244D03*
X1278150Y1681456D03*
Y1686180D03*
X1270276Y1705866D03*
Y1710590D03*
X1278150Y1709803D03*
Y1714527D03*
X1286024Y1677519D03*
Y1682244D03*
X1293898Y1681456D03*
Y1686180D03*
X1286024Y1705866D03*
Y1710590D03*
X1293898Y1709803D03*
Y1714527D03*
X1305709Y1677519D03*
Y1682244D03*
X1313583Y1681456D03*
Y1686180D03*
X1305709Y1705866D03*
Y1710590D03*
X1313583Y1709803D03*
Y1714527D03*
X1321457Y1677519D03*
Y1682244D03*
X1329331Y1681456D03*
Y1686180D03*
X1321457Y1705866D03*
Y1710590D03*
X1329331Y1709803D03*
Y1714527D03*
X1337205Y1677519D03*
Y1682244D03*
X1345079Y1681456D03*
Y1686180D03*
X1337205Y1705866D03*
Y1710590D03*
X1345079Y1709803D03*
Y1714527D03*
X1352953Y1677519D03*
Y1682244D03*
X1360827Y1681456D03*
Y1686180D03*
X1352953Y1705866D03*
Y1710590D03*
X1360827Y1709803D03*
Y1714527D03*
X1502953Y1691692D03*
Y1696417D03*
X1510827Y1695629D03*
Y1700354D03*
X1502953Y1720039D03*
Y1724763D03*
X1510827Y1723976D03*
Y1728700D03*
X1518701Y1691692D03*
Y1696417D03*
X1526575Y1695629D03*
Y1700354D03*
X1518701Y1720039D03*
Y1724763D03*
X1526575Y1723976D03*
Y1728700D03*
X1534449Y1691692D03*
Y1696417D03*
X1542323Y1695629D03*
Y1700354D03*
X1534449Y1720039D03*
Y1724763D03*
X1542323Y1723976D03*
Y1728700D03*
X1550197Y1691692D03*
Y1696417D03*
X1558071Y1695629D03*
Y1700354D03*
X1550197Y1720039D03*
Y1724763D03*
X1558071Y1723976D03*
Y1728700D03*
X1569882Y1691692D03*
Y1696417D03*
Y1720039D03*
Y1724763D03*
X1585630Y1691692D03*
X1577756Y1695629D03*
X1585630Y1696417D03*
X1577756Y1700354D03*
X1585630Y1720039D03*
X1577756Y1723976D03*
X1585630Y1724763D03*
X1577756Y1728700D03*
X1601378Y1691692D03*
X1593504Y1695629D03*
X1601378Y1696417D03*
X1593504Y1700354D03*
X1601378Y1720039D03*
X1593504Y1723976D03*
X1601378Y1724763D03*
X1593504Y1728700D03*
X1617126Y1691692D03*
X1609252Y1695629D03*
X1617126Y1696417D03*
X1609252Y1700354D03*
X1617126Y1720039D03*
X1609252Y1723976D03*
X1617126Y1724763D03*
X1609252Y1728700D03*
X1625000Y1695629D03*
Y1700354D03*
Y1723976D03*
Y1728700D03*
G54D42*
X383224Y1354446D03*
X412990D03*
X443326D03*
X458600Y1379662D03*
X472700Y1353962D03*
X1359365Y1353946D03*
X1389131D03*
X1419467D03*
X1434200Y1379362D03*
X1449233Y1353946D03*
G54D63*
X1769790Y204632D03*
G54D60*
X1099970Y1702570D03*
G54D61*
X1133779Y1653543D03*
G54D33*
X238780Y1648385D03*
X230906Y1644448D03*
X238780Y1662558D03*
X230906Y1658621D03*
X238780Y1676732D03*
X230906Y1672795D03*
X238780Y1690905D03*
X230906Y1686968D03*
X238780Y1705078D03*
X230906Y1701141D03*
Y1715314D03*
X238780Y1719251D03*
X230906Y1729488D03*
X238780Y1733425D03*
X254528Y1648385D03*
X246654Y1644448D03*
X254528Y1662558D03*
X246654Y1658621D03*
X254528Y1676732D03*
X246654Y1672795D03*
X254528Y1690905D03*
X246654Y1686968D03*
X254528Y1705078D03*
X246654Y1701141D03*
Y1715314D03*
X254528Y1719251D03*
X246654Y1729488D03*
X254528Y1733425D03*
X270276Y1648385D03*
X262402Y1644448D03*
X270276Y1662558D03*
X262402Y1658621D03*
X270276Y1676732D03*
X262402Y1672795D03*
X270276Y1690905D03*
X262402Y1686968D03*
X270276Y1705078D03*
X262402Y1701141D03*
Y1715314D03*
X270276Y1719251D03*
X262402Y1729488D03*
X270276Y1733425D03*
X286024Y1648385D03*
X278150Y1644448D03*
X286024Y1662558D03*
X278150Y1658621D03*
X286024Y1676732D03*
X278150Y1672795D03*
X286024Y1690905D03*
X278150Y1686968D03*
X286024Y1705078D03*
X278150Y1701141D03*
Y1715314D03*
X286024Y1719251D03*
X278150Y1729488D03*
X286024Y1733425D03*
X297835Y1672795D03*
X305709Y1676732D03*
X297835Y1686968D03*
X305709Y1690905D03*
X297835Y1701141D03*
X305709Y1705078D03*
X297835Y1715314D03*
X305709Y1719251D03*
X297835Y1729488D03*
X305709Y1733425D03*
X313583Y1672795D03*
X321457Y1676732D03*
X313583Y1686968D03*
X321457Y1690905D03*
X313583Y1701141D03*
X321457Y1705078D03*
X313583Y1715314D03*
X321457Y1719251D03*
X313583Y1729488D03*
X321457Y1733425D03*
X329331Y1672795D03*
X337205Y1676732D03*
X329331Y1686968D03*
X337205Y1690905D03*
X329331Y1701141D03*
X337205Y1705078D03*
X329331Y1715314D03*
X337205Y1719251D03*
X329331Y1729488D03*
X337205Y1733425D03*
X345079Y1672795D03*
X352953Y1676732D03*
X345079Y1686968D03*
X352953Y1690905D03*
X345079Y1701141D03*
X352953Y1705078D03*
X345079Y1715314D03*
X352953Y1719251D03*
X345079Y1729488D03*
X352953Y1733425D03*
X495079Y1672795D03*
Y1686968D03*
Y1701141D03*
Y1715314D03*
Y1729488D03*
X510827Y1672795D03*
X502953Y1676732D03*
X518701D03*
X510827Y1686968D03*
X502953Y1690905D03*
X518701D03*
X510827Y1701141D03*
X502953Y1705078D03*
X518701D03*
X510827Y1715314D03*
X502953Y1719251D03*
X518701D03*
X510827Y1729488D03*
X502953Y1733425D03*
X518701D03*
X526575Y1672795D03*
X534449Y1676732D03*
X526575Y1686968D03*
X534449Y1690905D03*
X526575Y1701141D03*
X534449Y1705078D03*
X526575Y1715314D03*
X534449Y1719251D03*
X526575Y1729488D03*
X534449Y1733425D03*
X542323Y1672795D03*
X550197Y1676732D03*
X542323Y1686968D03*
X550197Y1690905D03*
X542323Y1701141D03*
X550197Y1705078D03*
X542323Y1715314D03*
X550197Y1719251D03*
X542323Y1729488D03*
X550197Y1733425D03*
X562008Y1672795D03*
Y1686968D03*
Y1701141D03*
Y1715314D03*
Y1729488D03*
X577756Y1672795D03*
X569882Y1676732D03*
X577756Y1686968D03*
X569882Y1690905D03*
X577756Y1701141D03*
X569882Y1705078D03*
X577756Y1715314D03*
X569882Y1719251D03*
X577756Y1729488D03*
X569882Y1733425D03*
X593504Y1672795D03*
X585630Y1676732D03*
X593504Y1686968D03*
X585630Y1690905D03*
X593504Y1701141D03*
X585630Y1705078D03*
X593504Y1715314D03*
X585630Y1719251D03*
X593504Y1729488D03*
X585630Y1733425D03*
X609252Y1672795D03*
X601378Y1676732D03*
X609252Y1686968D03*
X601378Y1690905D03*
X609252Y1701141D03*
X601378Y1705078D03*
X609252Y1715314D03*
X601378Y1719251D03*
X609252Y1729488D03*
X601378Y1733425D03*
X617126Y1676732D03*
Y1690905D03*
Y1705078D03*
Y1719251D03*
Y1733425D03*
X1238780Y1672795D03*
X1246654Y1676732D03*
X1238780Y1686968D03*
X1246654Y1690905D03*
X1238780Y1701141D03*
X1246654Y1705078D03*
X1238780Y1715314D03*
X1246654Y1719251D03*
X1238780Y1729488D03*
X1246654Y1733425D03*
X1254528Y1672795D03*
X1262402Y1676732D03*
X1254528Y1686968D03*
X1262402Y1690905D03*
X1254528Y1701141D03*
X1262402Y1705078D03*
X1254528Y1715314D03*
X1262402Y1719251D03*
X1254528Y1729488D03*
X1262402Y1733425D03*
X1270276Y1672795D03*
X1278150Y1676732D03*
X1270276Y1686968D03*
X1278150Y1690905D03*
X1270276Y1701141D03*
X1278150Y1705078D03*
X1270276Y1715314D03*
X1278150Y1719251D03*
X1270276Y1729488D03*
X1278150Y1733425D03*
X1286024Y1672795D03*
X1293898Y1676732D03*
X1286024Y1686968D03*
X1293898Y1690905D03*
X1286024Y1701141D03*
X1293898Y1705078D03*
X1286024Y1715314D03*
X1293898Y1719251D03*
X1286024Y1729488D03*
X1293898Y1733425D03*
X1305709Y1672795D03*
X1313583Y1676732D03*
X1305709Y1686968D03*
X1313583Y1690905D03*
X1305709Y1701141D03*
X1313583Y1705078D03*
X1305709Y1715314D03*
X1313583Y1719251D03*
X1305709Y1729488D03*
X1313583Y1733425D03*
X1321457Y1672795D03*
X1329331Y1676732D03*
X1321457Y1686968D03*
X1329331Y1690905D03*
X1321457Y1701141D03*
X1329331Y1705078D03*
X1321457Y1715314D03*
X1329331Y1719251D03*
X1321457Y1729488D03*
X1329331Y1733425D03*
X1337205Y1672795D03*
X1345079Y1676732D03*
X1337205Y1686968D03*
X1345079Y1690905D03*
X1337205Y1701141D03*
X1345079Y1705078D03*
X1337205Y1715314D03*
X1345079Y1719251D03*
X1337205Y1729488D03*
X1345079Y1733425D03*
X1352953Y1672795D03*
X1360827Y1676732D03*
X1352953Y1686968D03*
X1360827Y1690905D03*
X1352953Y1701141D03*
X1360827Y1705078D03*
X1352953Y1715314D03*
X1360827Y1719251D03*
X1352953Y1729488D03*
X1360827Y1733425D03*
X1502953Y1672795D03*
X1510827Y1676732D03*
X1502953Y1686968D03*
X1510827Y1690905D03*
X1502953Y1701141D03*
X1510827Y1705078D03*
X1502953Y1715314D03*
X1510827Y1719251D03*
X1502953Y1729488D03*
X1510827Y1733425D03*
X1518701Y1672795D03*
X1526575Y1676732D03*
X1518701Y1686968D03*
X1526575Y1690905D03*
X1518701Y1701141D03*
X1526575Y1705078D03*
X1518701Y1715314D03*
X1526575Y1719251D03*
X1518701Y1729488D03*
X1526575Y1733425D03*
X1534449Y1672795D03*
X1542323Y1676732D03*
X1534449Y1686968D03*
X1542323Y1690905D03*
X1534449Y1701141D03*
X1542323Y1705078D03*
X1534449Y1715314D03*
X1542323Y1719251D03*
X1534449Y1729488D03*
X1542323Y1733425D03*
X1550197Y1672795D03*
X1558071Y1676732D03*
X1550197Y1686968D03*
X1558071Y1690905D03*
X1550197Y1701141D03*
X1558071Y1705078D03*
X1550197Y1715314D03*
X1558071Y1719251D03*
X1550197Y1729488D03*
X1558071Y1733425D03*
X1569882Y1672795D03*
Y1686968D03*
Y1701141D03*
Y1715314D03*
Y1729488D03*
X1585630Y1672795D03*
X1577756Y1676732D03*
X1585630Y1686968D03*
X1577756Y1690905D03*
X1585630Y1701141D03*
X1577756Y1705078D03*
X1585630Y1715314D03*
X1577756Y1719251D03*
X1585630Y1729488D03*
X1577756Y1733425D03*
X1601378Y1672795D03*
X1593504Y1676732D03*
X1601378Y1686968D03*
X1593504Y1690905D03*
X1601378Y1701141D03*
X1593504Y1705078D03*
X1601378Y1715314D03*
X1593504Y1719251D03*
X1601378Y1729488D03*
X1593504Y1733425D03*
X1617126Y1672795D03*
X1609252Y1676732D03*
X1625000D03*
X1617126Y1686968D03*
X1609252Y1690905D03*
X1625000D03*
X1617126Y1701141D03*
X1609252Y1705078D03*
X1625000D03*
X1617126Y1715314D03*
X1609252Y1719251D03*
X1625000D03*
X1617126Y1729488D03*
X1609252Y1733425D03*
X1625000D03*
G54D37*
X270252Y676260D03*
Y700414D03*
X387897Y1242785D03*
X412297D03*
X436619D03*
X461019D03*
X485419D03*
X1364038D03*
X1388438D03*
X1412760D03*
X1437160D03*
X1461560D03*
G54D29*
X159474Y1328627D03*
X183847Y1328652D03*
X208247D03*
X275289Y583576D03*
Y607735D03*
Y631889D03*
Y656043D03*
X673093Y1328652D03*
X697466Y1328677D03*
X721866D03*
X1100800Y259362D03*
X1100700Y283662D03*
X1131100Y1364962D03*
X1155500D03*
X1179900D03*
X1577000Y599762D03*
Y624262D03*
Y648762D03*
Y673162D03*
Y697662D03*
Y722162D03*
X1634259Y1362248D03*
X1658632Y1362273D03*
X1683032D03*
G54D72*
X1902608Y988322D03*
X1902682Y1351295D03*
X1951178Y1349597D03*
X1993618Y1349897D03*
G54D69*
X1881720Y988279D03*
X1881211Y1350983D03*
X1930200Y1349548D03*
X1972697Y1349606D03*
G54D18*
X40120Y744554D03*
Y1000853D03*
X69820Y744554D03*
Y1000853D03*
X99520Y744554D03*
Y1000853D03*
X129220Y744554D03*
X158920D03*
X188620D03*
X218320D03*
X722420Y1000853D03*
X752120D03*
X781820D03*
X811520D03*
X841220D03*
X1016262D03*
X1045962D03*
X1075662D03*
X1105362D03*
X1639162Y744554D03*
X1668862D03*
X1698562D03*
Y1000853D03*
X1728262Y744554D03*
Y1000853D03*
G54D57*
X928739Y321653D03*
G54D10*
X27559Y87795D03*
X40708Y631890D03*
Y1368897D03*
X51181Y1714961D03*
X373622Y87795D03*
X395670Y1714961D03*
X661023Y631890D03*
X800787Y87795D03*
X931692Y757874D03*
Y1072834D03*
Y1387795D03*
X1045865Y87795D03*
X1271260Y631890D03*
X1461805Y1714961D03*
X1499606Y87795D03*
X1816771Y631890D03*
Y1368897D03*
X1806299Y1714961D03*
X1829921Y87795D03*
G54D32*
X250326Y185236D03*
X368437D03*
G54D62*
X1247638Y269488D03*
X1405118Y112008D03*
X1766929Y1714960D03*
G54D12*
X19685Y-29134D03*
Y1803261D03*
X1837795Y-29134D03*
Y1803261D03*
X2081889Y-29134D03*
Y1803261D03*
G54D36*
X277098Y185236D03*
X395208D03*
G54D15*
X38346Y1420330D03*
X117932Y605380D03*
X763601Y605413D03*
X1094074Y605380D03*
X1739706Y605455D03*
X1819208Y1420330D03*
G54D16*
X49280Y337402D03*
X41870Y1511291D03*
X441043Y1672205D03*
Y1718465D03*
X1416437Y1672204D03*
Y1718464D03*
X1808192Y1569255D03*
X1812980Y502472D03*
G54D39*
X322500Y1391830D03*
X537477Y1395413D03*
X1298642Y1391830D03*
X1513618Y1395413D03*
G54D38*
X306772Y991220D03*
X350099Y811121D03*
X356063Y1171318D03*
X531240Y811121D03*
X525276Y1171318D03*
X574567Y991220D03*
X1282914D03*
X1326240Y811121D03*
X1332205Y1171318D03*
X1507382Y811121D03*
X1501418Y1171318D03*
X1550709Y991220D03*
G54D50*
X791280Y1704890D03*
X1066280D03*
G54D43*
X441043Y1698268D03*
X1416437Y1698267D03*
G54D52*
X805690Y204724D03*
X1057658D03*
G54D26*
X72485Y1304152D03*
X75485D03*
X78485D03*
X72485Y1307152D03*
X75485D03*
X69485Y1304152D03*
Y1307152D03*
X75485Y1316152D03*
X72485Y1313152D03*
Y1310152D03*
X75485Y1313152D03*
Y1310152D03*
X69485D03*
X93485Y1304152D03*
X87485D03*
X90485D03*
X93485Y1307152D03*
X84485Y1304152D03*
X81485D03*
X93485Y1318152D03*
Y1315652D03*
Y1310152D03*
Y1313152D03*
X108465Y1304292D03*
Y1307292D03*
X105475Y1304222D03*
Y1307222D03*
X102485Y1304152D03*
X99485D03*
X96485D03*
X102485Y1307152D03*
X99485D03*
X96485D03*
X108465Y1318292D03*
Y1310292D03*
Y1313292D03*
Y1315792D03*
X105475Y1318222D03*
Y1310222D03*
Y1313222D03*
Y1315722D03*
X99485Y1318152D03*
X96485D03*
Y1315652D03*
Y1310152D03*
Y1313152D03*
X99485Y1310152D03*
Y1313152D03*
Y1315652D03*
X102485Y1318152D03*
Y1310152D03*
Y1313152D03*
Y1315652D03*
X189800Y705062D03*
X208312Y576125D03*
X196526Y567825D03*
X208312Y581085D03*
Y578605D03*
X197423Y601496D03*
X208312Y615085D03*
Y610125D03*
Y612605D03*
X194059Y638901D03*
X197423Y635496D03*
X208312Y649085D03*
Y644125D03*
Y646605D03*
X213912Y576125D03*
X220668Y574131D03*
X223775D03*
X224064Y568113D03*
X221464D03*
X213912Y578605D03*
Y581085D03*
X217556Y590575D03*
X217561Y582131D03*
Y579531D03*
X223775Y587731D03*
X223759Y590675D03*
X220652D03*
X223775Y584531D03*
X220668Y576731D03*
Y579331D03*
X223775Y581931D03*
Y579331D03*
Y576731D03*
X220668Y581931D03*
Y608131D03*
X223775D03*
X224064Y602113D03*
X221464D03*
X223403Y596820D03*
Y594220D03*
X213912Y612605D03*
Y615085D03*
Y610125D03*
X217561Y616131D03*
Y613531D03*
X217556Y624575D03*
X223759Y624675D03*
X220652D03*
X223775Y618531D03*
X220668Y610731D03*
Y613331D03*
X223775Y615931D03*
Y613331D03*
Y610731D03*
X220668Y615931D03*
X223775Y621731D03*
X223403Y630820D03*
Y628220D03*
X224064Y636113D03*
X221464D03*
X213912Y646605D03*
Y649085D03*
Y644125D03*
X217561Y650131D03*
Y647531D03*
X223775Y655731D03*
Y652531D03*
X220668Y644731D03*
Y647331D03*
Y642131D03*
X223775Y649931D03*
Y647331D03*
Y644731D03*
Y642131D03*
X220668Y649931D03*
X217556Y658575D03*
X223403Y664820D03*
X223759Y658675D03*
X220652D03*
X217510Y668712D03*
X225167Y672006D03*
X222567D03*
X219967D03*
X217367D03*
X211348Y688087D03*
Y685287D03*
X214100Y687376D03*
Y690376D03*
Y684376D03*
Y681376D03*
Y678376D03*
X211348Y690787D03*
Y693587D03*
X214100Y693576D03*
X224506Y698138D03*
Y700738D03*
X221906Y698138D03*
Y700738D03*
X219306D03*
Y698138D03*
X231864Y568113D03*
X229264D03*
X226664D03*
X238393Y570490D03*
X229264Y602113D03*
X226664D03*
X226003Y594220D03*
Y596820D03*
X228603Y594220D03*
Y596820D03*
X231864Y602113D03*
X233803Y594220D03*
Y596820D03*
X231203Y594220D03*
Y596820D03*
X238393Y604490D03*
Y596820D03*
Y594220D03*
X226003Y628220D03*
Y630820D03*
X228603Y628220D03*
Y630820D03*
X231864Y636113D03*
X233803Y628220D03*
Y630820D03*
X231203Y628220D03*
Y630820D03*
X229264Y636113D03*
X226664D03*
X238393Y638490D03*
Y630820D03*
Y628220D03*
X228603Y664820D03*
X233803D03*
X231203D03*
X226003D03*
X230367Y672006D03*
X227767D03*
X227106Y698138D03*
Y700738D03*
X260500Y227362D03*
Y224862D03*
X264055Y566935D03*
X263995Y569485D03*
X261495D03*
X261555Y566935D03*
X266495Y569485D03*
X266555Y566935D03*
X268995Y569485D03*
X269055Y566935D03*
X320245Y1357401D03*
X322575Y1358151D03*
X329648Y252202D03*
X324905Y1357401D03*
X327235Y1358151D03*
X354672Y252693D03*
X352373Y1334603D03*
X354703Y1335353D03*
X366498Y290264D03*
X357033Y1334603D03*
X359363Y1335353D03*
X384501Y1321177D03*
X386831Y1321927D03*
X392083Y290954D03*
X389161Y1321177D03*
X391491Y1321927D03*
X417218Y291274D03*
X416629Y1321177D03*
X418959Y1321927D03*
X421289Y1321177D03*
X423619Y1321927D03*
X448757Y1321177D03*
X451087Y1321927D03*
X453417Y1321177D03*
X455747Y1321927D03*
X480885Y1321177D03*
X485545D03*
X483215Y1321927D03*
X487875D03*
X513013Y1334603D03*
X517673D03*
X515343Y1335353D03*
X520003D03*
X545141Y1357401D03*
X549801D03*
X547471Y1358151D03*
X552131D03*
X714000Y496132D03*
X762345Y1284542D03*
Y1287542D03*
Y1290542D03*
X762205Y1293272D03*
X758830Y1674823D03*
X765345Y1284542D03*
X768335Y1284612D03*
X765345Y1287542D03*
Y1290542D03*
X768335Y1287612D03*
Y1290612D03*
X765205Y1293272D03*
X768195Y1293342D03*
X778005Y1294092D03*
X792045Y1284542D03*
Y1290542D03*
Y1287542D03*
X791905Y1293272D03*
X798035Y1284612D03*
X795045Y1284542D03*
X798035Y1290612D03*
Y1287612D03*
X795045Y1290542D03*
Y1287542D03*
X797895Y1293342D03*
X794905Y1293272D03*
X956022Y1620730D03*
X953022D03*
Y1632730D03*
X956022D03*
Y1629730D03*
X953022D03*
X956022Y1626730D03*
X953022D03*
Y1623730D03*
X956022D03*
X966852Y1585920D03*
X969852D03*
X960852D03*
X963852D03*
X957852D03*
X962022Y1620730D03*
X959022D03*
Y1632730D03*
X962022D03*
Y1629730D03*
X959022D03*
X962022Y1626730D03*
X959022D03*
Y1623730D03*
X962022D03*
X978403Y-9022D03*
Y-13978D03*
Y-19022D03*
Y-23978D03*
Y6022D03*
Y10978D03*
Y20978D03*
Y16022D03*
X987662Y1620870D03*
Y1629870D03*
Y1626870D03*
Y1623870D03*
Y1632870D03*
X1002782Y1585920D03*
X999782D03*
X996782D03*
X990782D03*
X993782D03*
X990662Y1620870D03*
X993662D03*
Y1629870D03*
X990662D03*
X993662Y1626870D03*
X990662D03*
Y1623870D03*
X993662D03*
X990662Y1632870D03*
X993662D03*
X1001810Y1662700D03*
Y1665200D03*
X1021695Y364518D03*
X1021942Y1586090D03*
X1019252Y1620870D03*
X1022252D03*
Y1623870D03*
Y1626870D03*
X1019252Y1623870D03*
Y1626870D03*
X1019910Y1662700D03*
Y1665200D03*
X1030942Y1586090D03*
X1033942D03*
X1024942D03*
X1027942D03*
X1025252Y1620870D03*
Y1623870D03*
Y1626870D03*
X1023580Y1662700D03*
Y1665200D03*
X1027370Y1662700D03*
Y1665200D03*
X1040120Y393962D03*
X1042720D03*
X1053612Y1586010D03*
X1050721Y1633043D03*
X1053721D03*
Y1624043D03*
Y1627043D03*
Y1630043D03*
X1050721Y1624043D03*
Y1627043D03*
Y1630043D03*
X1053721Y1621043D03*
X1050721D03*
X1044850Y1665050D03*
Y1662550D03*
X1071179Y1294669D03*
X1062612Y1586010D03*
X1065612D03*
X1056612D03*
X1059612D03*
X1056721Y1633043D03*
Y1624043D03*
Y1627043D03*
Y1630043D03*
Y1621043D03*
X1077634Y1294869D03*
X1074387Y1294652D03*
X1092302Y1585650D03*
X1089302D03*
X1098302D03*
X1095302D03*
X1095900Y1646935D03*
X1095649Y1638875D03*
X1099457D03*
X1104457Y1675490D03*
X1159930Y1645632D03*
X1164830D03*
X1161613Y1669112D03*
X1173100Y186962D03*
X1172925Y202174D03*
X1172835Y218174D03*
X1181500Y211962D03*
Y218462D03*
Y215962D03*
X1181930Y1645632D03*
X1186830D03*
X1175830D03*
X1170930D03*
X1183613Y1669112D03*
X1172613D03*
X1188300Y189062D03*
X1187300Y217862D03*
X1192500Y1645942D03*
X1197400D03*
X1194183Y1669422D03*
X1192340Y1691422D03*
X1197240D03*
X1194023Y1714902D03*
X1214534Y157462D03*
X1214693Y174962D03*
X1214134Y180972D03*
X1210457Y1658415D03*
X1218810Y1691732D03*
X1213910D03*
X1203110Y1691467D03*
X1208010D03*
X1215593Y1715212D03*
X1204793Y1714947D03*
X1224614Y116962D03*
X1219534Y116492D03*
X1226400Y125200D03*
X1226093Y134262D03*
Y140962D03*
X1222593D03*
X1226093Y156962D03*
X1222594Y154242D03*
X1225874Y163462D03*
X1222720Y163362D03*
X1240904Y151592D03*
X1238604Y150062D03*
X1243184Y182422D03*
X1239874Y182322D03*
X1236220Y189362D03*
X1245514Y224302D03*
X1264663Y158946D03*
X1254994Y157382D03*
X1264584Y226592D03*
X1256593Y221462D03*
X1282824Y108872D03*
X1267289Y192167D03*
X1269904Y192692D03*
X1287795Y-29033D03*
Y-33989D03*
Y-9033D03*
Y-13989D03*
Y-19033D03*
Y-23989D03*
Y967D03*
Y-3989D03*
X1291704Y109427D03*
X1291071Y275543D03*
Y278543D03*
X1298836Y1358387D03*
X1296506Y1357637D03*
X1300990Y121812D03*
X1303496Y1358387D03*
X1301166Y1357637D03*
X1329646Y104954D03*
X1328514Y1334603D03*
X1330844Y1335353D03*
X1336549Y105970D03*
X1344631Y127244D03*
X1333174Y1334603D03*
X1335504Y1335353D03*
X1349570Y104147D03*
X1353394Y131812D03*
X1349220Y140362D03*
X1360593Y1321872D03*
X1363098Y1320951D03*
X1366714Y109506D03*
X1365376Y1321938D03*
X1367635Y1320904D03*
X1392770Y1321177D03*
X1395100Y1321927D03*
X1397430Y1321177D03*
X1399760Y1321927D03*
X1424898Y1321177D03*
X1427228Y1321927D03*
X1429558Y1321177D03*
X1431888Y1321927D03*
X1449777Y362021D03*
X1457026Y1321177D03*
X1461686D03*
X1459356Y1321927D03*
X1464016D03*
X1480154Y-29033D03*
Y-33989D03*
Y-9033D03*
Y-13989D03*
Y-19033D03*
Y-23989D03*
Y967D03*
Y-3989D03*
X1489154Y1334603D03*
X1493814D03*
X1491484Y1335353D03*
X1496144D03*
X1521282Y1357401D03*
X1525942D03*
X1523612Y1358151D03*
X1528272D03*
X1545668Y305266D03*
X1545768Y302766D03*
X1543858Y310056D03*
X1692883Y703943D03*
X1749450Y293862D03*
X1761936Y310709D03*
X1769165Y1301422D03*
X1766165D03*
X1763165D03*
X1759987Y1325375D03*
Y1328275D03*
X1766829Y1343348D03*
X1769829Y1346248D03*
Y1343348D03*
Y1349148D03*
Y1351858D03*
X1778165Y1301422D03*
X1775165D03*
X1772165D03*
X1784165Y1304422D03*
X1781165D03*
X1784165Y1301422D03*
X1781165D03*
X1781829Y1346248D03*
Y1343348D03*
Y1349148D03*
Y1351858D03*
Y1354758D03*
X1772829Y1346248D03*
X1775829D03*
X1778829D03*
X1772829Y1343348D03*
X1775829D03*
X1778829D03*
X1772829Y1349148D03*
X1775829D03*
X1778829D03*
X1772829Y1351858D03*
X1775829D03*
X1778829D03*
X1772829Y1354758D03*
X1775829D03*
X1778829D03*
X1829695Y226333D03*
X1832295D03*
X1827095D03*
X1824095D03*
X1834895D03*
Y223733D03*
X1824095D03*
X1827095D03*
X1832295D03*
X1829695D03*
X1832295Y233933D03*
X1829695D03*
X1827095D03*
X1824095D03*
X1829695Y231433D03*
X1832295D03*
X1829695Y228933D03*
X1832295D03*
X1827095Y231433D03*
X1824095D03*
X1827095Y228933D03*
X1824095D03*
X1834895Y233933D03*
Y231433D03*
Y228933D03*
X1837895Y226333D03*
Y223733D03*
Y233933D03*
Y231433D03*
Y228933D03*
G54D23*
X58658Y754145D03*
X72981Y466385D03*
X74340Y663422D03*
X76365Y699244D03*
X76565Y717949D03*
X72315Y717414D03*
X64325Y715674D03*
X80460Y655672D03*
X83100Y649762D03*
X82735Y717949D03*
X87865Y714394D03*
X85165D03*
X81225Y715854D03*
X79635Y717949D03*
X85835Y718049D03*
X93295Y762019D03*
X110937Y285495D03*
Y302854D03*
X98134Y722501D03*
X129394Y278875D03*
X129375Y274800D03*
X129394Y306236D03*
X130057Y636103D03*
X129600Y669400D03*
X132967Y760525D03*
X147141Y698811D03*
X147435Y690807D03*
X149861Y698831D03*
X150155Y690807D03*
X156685Y706836D03*
X153965Y706816D03*
X153879Y721660D03*
X156469D03*
X147031Y706835D03*
X149621D03*
X149669Y721660D03*
X147079D03*
X156477Y1339183D03*
Y1346883D03*
Y1349383D03*
X176077Y1333783D03*
X173477D03*
X176077Y1336383D03*
X173477D03*
X176107Y1339233D03*
X173507D03*
X176077Y1341883D03*
X173477D03*
Y1349383D03*
Y1346883D03*
Y1344383D03*
X176077D03*
Y1346883D03*
Y1349383D03*
X170877D03*
Y1346883D03*
Y1344383D03*
X187532Y421387D03*
X190977Y669718D03*
X191976Y684326D03*
X191977Y1333783D03*
X199149Y425755D03*
Y420255D03*
Y414755D03*
Y436755D03*
Y442255D03*
Y431255D03*
Y453255D03*
Y447755D03*
Y468255D03*
X195888Y581071D03*
X194515Y583433D03*
X195888Y615071D03*
X194515Y617433D03*
Y651433D03*
X195888Y649071D03*
X205320Y667562D03*
X207856Y686443D03*
X203043Y686483D03*
X207824Y681560D03*
X203044Y684036D03*
X207834Y684006D03*
X203237Y681549D03*
X199720Y732862D03*
X206720Y731862D03*
X199220Y739362D03*
X207602Y756855D03*
X199602D03*
X194577Y1333783D03*
Y1349383D03*
Y1346883D03*
X208977Y1344383D03*
Y1346883D03*
Y1349383D03*
X225407Y321831D03*
X211220Y740362D03*
X214177Y1336383D03*
X211577D03*
X214177Y1333783D03*
X211577D03*
X214207Y1339263D03*
X211607D03*
X214177Y1341883D03*
X211577D03*
X214177Y1349383D03*
Y1346883D03*
Y1344383D03*
X211577D03*
Y1346883D03*
Y1349383D03*
X248097Y92143D03*
X247897Y100543D03*
X243892Y140912D03*
X253819Y675567D03*
X253849Y678077D03*
X256419Y675567D03*
X256449Y678077D03*
X251219Y675567D03*
X251249Y678077D03*
X248649D03*
X248989Y698827D03*
X249019Y693767D03*
X251589Y698827D03*
X251649Y696277D03*
X254189Y698827D03*
X251619Y693767D03*
X256849Y696277D03*
X256789Y698827D03*
X256819Y693767D03*
X254249Y696277D03*
X254219Y693767D03*
X248300Y703862D03*
X272529Y111053D03*
X265442D03*
X261899D03*
Y108553D03*
X265442D03*
X268985Y111053D03*
Y108553D03*
X272529D03*
X265500Y227862D03*
X263000D03*
X271821Y251962D03*
X267759D03*
X259224Y419532D03*
X259869Y431039D03*
X259049Y678077D03*
X259019Y675567D03*
X259419Y693767D03*
X259389Y698827D03*
X259449Y696277D03*
X286481Y251962D03*
X281077D03*
X276491D03*
X289274Y290662D03*
X284515D03*
X276500Y444862D03*
X274850Y442562D03*
X279500Y455362D03*
X277578Y509039D03*
X292942Y71499D03*
X296478Y149203D03*
X304651Y251962D03*
X291759D03*
X306736Y290662D03*
X302765D03*
X298184D03*
X293763D03*
X303647Y1307981D03*
X303807Y1342225D03*
X303831Y1344866D03*
X304047Y1368565D03*
X313357Y89503D03*
X313457Y96803D03*
X317129Y251962D03*
X316463Y290662D03*
X312301Y1345539D03*
Y1342432D03*
X309701Y1345539D03*
Y1342432D03*
X316655Y1352295D03*
X314175D03*
X311695D03*
X320101Y1342432D03*
X317701Y1348646D03*
X315101D03*
X314901Y1345539D03*
X317501D03*
X314901Y1342432D03*
X317501D03*
X316655Y1357895D03*
X311695D03*
X314175D03*
X317979Y1371248D03*
X315221Y1372445D03*
X326900Y162287D03*
X329002Y290662D03*
X331515Y1337104D03*
Y1331904D03*
Y1329304D03*
Y1334504D03*
X328915Y1339704D03*
X326145Y1348651D03*
X326245Y1345555D03*
Y1342448D03*
X323301Y1342432D03*
X338917Y1349488D03*
X336347Y1348353D03*
X332475Y1357945D03*
X327875Y1363945D03*
Y1361045D03*
X330041Y1362315D03*
X329941Y1359315D03*
X332475Y1363345D03*
Y1360445D03*
X353145Y219362D03*
X344264Y1272455D03*
X341754Y1272485D03*
X344252Y1269948D03*
X341742Y1269978D03*
X341754Y1274985D03*
X344264Y1274955D03*
Y1277455D03*
X341754Y1277485D03*
X344429Y1322741D03*
X347029D03*
X341829D03*
X347029Y1319634D03*
X344429D03*
X341829D03*
X349629Y1322741D03*
Y1319634D03*
X352229D03*
X355429D03*
X346303Y1335097D03*
X343823D03*
Y1329497D03*
X346303D03*
X347229Y1325848D03*
X348783Y1329497D03*
X349829Y1325848D03*
X348783Y1335097D03*
X348804Y1346877D03*
X350470Y1349030D03*
X354850Y1371908D03*
X351850D03*
X349260Y1373418D03*
X351850Y1375408D03*
X354850D03*
X351850Y1378408D03*
X354850D03*
X351850Y1381408D03*
X354850D03*
X349260Y1376918D03*
Y1379918D03*
X367939Y1305919D03*
Y1308519D03*
X358373Y1322757D03*
Y1319650D03*
X361043Y1316906D03*
X362393Y1319406D03*
X363643Y1316906D03*
Y1314306D03*
Y1309106D03*
Y1311706D03*
X358273Y1325853D03*
X370874Y1335876D03*
X367490Y1332568D03*
X362147Y1336553D03*
X360003Y1338247D03*
X364269Y1338017D03*
X364073Y1334903D03*
X360003Y1341147D03*
X362147Y1339653D03*
X364347Y1340853D03*
X364647Y1371990D03*
X361647D03*
X358647D03*
X367647D03*
X370552Y1372073D03*
X364647Y1375490D03*
X361647D03*
X358647D03*
Y1378490D03*
X370552Y1375573D03*
X367647Y1375490D03*
X379860Y252162D03*
X373823Y1256896D03*
X376333Y1256866D03*
X373835Y1259403D03*
X376345Y1259373D03*
X373835Y1261903D03*
Y1264403D03*
X376345Y1261873D03*
Y1264373D03*
X373957Y1306208D03*
X381757D03*
X379157D03*
X376557D03*
X384357D03*
X387557D03*
X375951Y1321671D03*
X380911Y1316071D03*
X378431D03*
Y1321671D03*
X380911D03*
X373957Y1309315D03*
X381957Y1312422D03*
X381757Y1309315D03*
X379357Y1312422D03*
X379157Y1309315D03*
X376557D03*
X375951Y1316071D03*
X380842Y1334095D03*
X383549Y1333998D03*
X373552Y1372073D03*
X377025Y1371990D03*
X380025D03*
X373532Y1378598D03*
X373552Y1375573D03*
X380025Y1378490D03*
X377025D03*
X380025Y1375490D03*
X377025D03*
Y1381490D03*
X392616Y252162D03*
X398796Y1161570D03*
Y1153070D03*
Y1170070D03*
X394521Y1305980D03*
X390501Y1306224D03*
X400067Y1305919D03*
Y1308519D03*
X390401Y1312427D03*
X390501Y1309331D03*
X392131Y1324821D03*
X396397Y1324591D03*
X394197Y1323091D03*
X396397Y1321691D03*
X399673Y1332653D03*
X403130Y1335963D03*
X394297Y1326091D03*
X392131Y1327721D03*
X396397Y1327491D03*
X408284Y163662D03*
X417765Y252162D03*
X404985D03*
X416220Y364062D03*
X419460Y1161570D03*
Y1153370D03*
Y1169597D03*
X408511Y1256866D03*
X406001Y1256896D03*
X408523Y1259373D03*
X406013Y1259403D03*
X408523Y1264373D03*
X406013Y1264403D03*
Y1261903D03*
X408523Y1261873D03*
X416485Y1306208D03*
X419685D03*
X413885D03*
X406085D03*
X411285D03*
X408685D03*
X414085Y1312422D03*
X413885Y1309315D03*
X411485Y1312422D03*
X408685Y1309315D03*
X406085D03*
X411285D03*
X413039Y1316071D03*
X408079D03*
X410559D03*
X413039Y1321671D03*
X408079D03*
X410559D03*
X416099Y1335568D03*
X414617Y1333473D03*
X421200Y232562D03*
X423145Y227862D03*
X434343Y504233D03*
Y509733D03*
Y498733D03*
X421960Y1161570D03*
Y1153370D03*
Y1169597D03*
X422629Y1306224D03*
X432195Y1305919D03*
X426649Y1305980D03*
X432195Y1308519D03*
X422529Y1312427D03*
X422629Y1309331D03*
X428525Y1321691D03*
X426325Y1323091D03*
X424259Y1324821D03*
X428525Y1324591D03*
X434983Y1335924D03*
X431578Y1332560D03*
X424259Y1327721D03*
X426425Y1326091D03*
X428525Y1327491D03*
X448276Y1161570D03*
X445776D03*
X443276D03*
X445776Y1153370D03*
X448276D03*
X443276D03*
X440858Y1256866D03*
X438348Y1256896D03*
X440870Y1259373D03*
X438360Y1259403D03*
Y1261903D03*
X440870Y1261873D03*
Y1264373D03*
X438360Y1264403D03*
X448613Y1306208D03*
X446013D03*
X443413D03*
X440813D03*
X438213D03*
X451813D03*
X443613Y1312422D03*
X443413Y1309315D03*
X440813D03*
X438213D03*
X446213Y1312422D03*
X446013Y1309315D03*
X440207Y1316071D03*
X445167D03*
X442687D03*
X440207Y1321671D03*
X445167D03*
X442687D03*
X446944Y1335928D03*
X445153Y1334095D03*
X453346Y149864D03*
X468323Y254562D03*
X464427Y1305380D03*
X454757Y1306224D03*
X460927Y1306580D03*
X458327D03*
X464423Y1308519D03*
X454657Y1312427D03*
X454757Y1309331D03*
X458453Y1323091D03*
X460653Y1321691D03*
Y1324591D03*
X456387Y1324821D03*
X464738Y1333085D03*
X467644Y1335981D03*
X458553Y1326091D03*
X460653Y1327491D03*
X456387Y1327721D03*
X481246Y161364D03*
X470900Y234787D03*
X478995Y293787D03*
X473698Y1161570D03*
X471198D03*
X473698Y1153370D03*
X471198D03*
X473698Y1170070D03*
X471198D03*
X473035Y1256866D03*
X470525Y1256896D03*
X473047Y1259373D03*
X470537Y1259403D03*
Y1261903D03*
X473047Y1261873D03*
Y1264373D03*
X470537Y1264403D03*
X480741Y1306208D03*
X478141D03*
X475541D03*
X472941D03*
X470341D03*
X483941D03*
X472941Y1309315D03*
X478141D03*
X470341D03*
X478341Y1312422D03*
X475741D03*
X475541Y1309315D03*
X472335Y1316071D03*
X477295D03*
X474815D03*
X472335Y1321671D03*
X477295D03*
X474815D03*
X477162Y1334095D03*
X478909Y1336038D03*
X498730Y128592D03*
X500925Y231262D03*
X499096Y252462D03*
X500150Y1278104D03*
X486885Y1306224D03*
X496451Y1306345D03*
X490905Y1305980D03*
X486785Y1312427D03*
X486885Y1309331D03*
X496220Y1322440D03*
X496451Y1316745D03*
Y1308945D03*
Y1314145D03*
Y1311545D03*
X492878Y1322618D03*
X490678Y1324018D03*
X488539Y1325772D03*
X492878Y1325518D03*
X488539Y1328672D03*
X490778Y1327018D03*
X492878Y1328418D03*
X499458Y1349468D03*
X503270Y128592D03*
X507320D03*
X508000Y241862D03*
X503040Y287928D03*
X502239Y315404D03*
X505220Y1280054D03*
X502680D03*
X515960D03*
X516069Y1319634D03*
X502469D03*
Y1322741D03*
X512869Y1319634D03*
X510269D03*
X507669D03*
X505069D03*
X507669Y1322741D03*
X505069D03*
X510269D03*
X504463Y1329497D03*
Y1335097D03*
X509423Y1329497D03*
X506943D03*
X509423Y1335097D03*
X506943D03*
X510469Y1325848D03*
X507869D03*
X509382Y1347521D03*
X511149Y1349468D03*
X523682Y307541D03*
Y304541D03*
X532650Y446396D03*
X521885Y452442D03*
X524425Y489112D03*
Y495112D03*
X522805Y482155D03*
X518500Y1280054D03*
X530450Y1297014D03*
X532570Y1298434D03*
X523033Y1319406D03*
X519013Y1319650D03*
Y1322757D03*
X527645Y1326076D03*
X528579Y1329143D03*
X528377Y1335982D03*
X518913Y1325853D03*
X525008Y1336287D03*
X520643Y1338247D03*
X522809Y1339517D03*
X522783Y1334882D03*
X520643Y1341147D03*
X528579Y1342143D03*
Y1344743D03*
X528975Y1369724D03*
X547395Y147302D03*
X539639Y271972D03*
X543660Y1302934D03*
X541100D03*
X538560D03*
X535110Y1298464D03*
X537650D03*
X540210D03*
X536020Y1302904D03*
X539071Y1352295D03*
X536591D03*
X541551D03*
Y1357895D03*
X542256Y1369935D03*
X536591Y1357895D03*
X539071D03*
X552395Y134340D03*
X555220Y164787D03*
X555195Y184862D03*
Y171862D03*
X552089Y253202D03*
X566730Y300992D03*
X557829Y454479D03*
X554837Y1359315D03*
X557037Y1363715D03*
Y1357915D03*
Y1360815D03*
X554937Y1362315D03*
X552771Y1361045D03*
Y1363945D03*
X573115Y161232D03*
X579481Y198378D03*
X579170Y190092D03*
X579481Y206378D03*
X575359Y265132D03*
X582510Y296657D03*
Y304052D03*
Y311571D03*
X583045Y488212D03*
X568840Y501046D03*
X588245Y132142D03*
X592220Y173862D03*
X591727Y285862D03*
X591720Y433937D03*
X599645Y479862D03*
X594090Y501957D03*
X611381Y200378D03*
X609040Y317282D03*
X615635Y317637D03*
X614220Y447862D03*
X612407Y769485D03*
X630795Y236862D03*
X629564Y253127D03*
X621060Y271066D03*
X623365Y316742D03*
X631146Y317768D03*
X628900Y431050D03*
X629220Y457862D03*
Y462862D03*
X645109Y249202D03*
Y260202D03*
X643800Y294327D03*
Y306547D03*
X644000Y438862D03*
X644220Y452862D03*
Y477862D03*
Y462862D03*
X658720Y399862D03*
X663043Y1647557D03*
X663118Y1659557D03*
X663145Y1664862D03*
Y1676862D03*
X680600Y364282D03*
X675295Y399862D03*
X676648Y1657380D03*
X671620Y1670862D03*
X674195Y1708362D03*
X669120Y1718862D03*
X674195Y1732362D03*
X681053Y104668D03*
X695055Y112678D03*
Y115178D03*
X685600Y364282D03*
X690600D03*
X695600D03*
X695220Y399862D03*
X684555Y1338896D03*
X689605Y1336396D03*
Y1338896D03*
X687105Y1336396D03*
X684555D03*
X687105Y1338896D03*
X689605Y1333896D03*
X687105D03*
X684555D03*
Y1341396D03*
Y1343896D03*
X689605Y1341396D03*
Y1343896D03*
X687105Y1341396D03*
Y1343896D03*
X689128Y1652262D03*
X692595Y1670862D03*
X698598Y115178D03*
X705685D03*
X702141D03*
X698598Y112678D03*
X705685D03*
X702141D03*
X700600Y364282D03*
X705600D03*
X710600D03*
X713220Y399862D03*
X711220Y503842D03*
X705220D03*
X704497Y1598927D03*
X697595Y1658862D03*
X704433Y1657964D03*
X697770Y1680810D03*
X714015Y-27612D03*
X720308Y-26403D03*
X714015Y-21457D03*
Y-17583D03*
X714030Y-15068D03*
X714015Y-11428D03*
X714030Y-25097D03*
X720308Y-16374D03*
X714015Y-7554D03*
X714030Y-5039D03*
X720308Y-6345D03*
X727518Y90984D03*
X729220Y503842D03*
X723220D03*
X717220D03*
X723054Y1333896D03*
X725604D03*
X728104D03*
X725604Y1338896D03*
X723054Y1336396D03*
X725604D03*
X728104Y1338896D03*
Y1336396D03*
X723054Y1338896D03*
X725604Y1343896D03*
Y1341396D03*
X728104Y1343896D03*
Y1341396D03*
X723054Y1343896D03*
Y1341396D03*
X721345Y1647300D03*
X716140Y1649895D03*
X726830Y1655380D03*
X724500Y1676500D03*
X745720Y399862D03*
X737299Y766887D03*
X733336Y1568341D03*
Y1565341D03*
Y1559341D03*
Y1562341D03*
X730336Y1559341D03*
Y1562341D03*
X745336D03*
Y1559341D03*
Y1565341D03*
Y1568341D03*
X742336Y1562341D03*
Y1559341D03*
Y1565341D03*
Y1568341D03*
X739336Y1562341D03*
Y1559341D03*
Y1565341D03*
Y1568341D03*
X736336D03*
Y1565341D03*
Y1559341D03*
Y1562341D03*
X733336Y1574341D03*
Y1571341D03*
X745336Y1574341D03*
Y1571341D03*
X742336Y1574341D03*
Y1571341D03*
X739336Y1574341D03*
Y1571341D03*
X736336D03*
Y1574341D03*
X741382Y1590691D03*
X748033Y116288D03*
X747230Y108572D03*
X757150Y280592D03*
X758720Y283262D03*
X759920Y280562D03*
X759637Y311585D03*
X760670Y317432D03*
X753137Y766625D03*
X748336Y1562341D03*
Y1559341D03*
Y1565341D03*
Y1568341D03*
X751336D03*
Y1565341D03*
Y1559341D03*
Y1562341D03*
X748336Y1574341D03*
Y1571341D03*
X761770Y1695347D03*
X762420Y280562D03*
X766195Y413212D03*
Y423212D03*
Y428212D03*
X765335Y469552D03*
X772365Y488862D03*
X775317Y764025D03*
X763747Y764335D03*
X781195Y393212D03*
X788120Y422942D03*
X780020Y441437D03*
Y445287D03*
X781205Y454402D03*
X796315Y469290D03*
X783450Y522462D03*
X784352Y1568293D03*
Y1565293D03*
Y1559293D03*
Y1562293D03*
X781352Y1568293D03*
Y1565293D03*
Y1559293D03*
Y1562293D03*
X793352D03*
Y1559293D03*
Y1565293D03*
Y1568293D03*
X790352Y1562293D03*
Y1559293D03*
Y1565293D03*
Y1568293D03*
X787352D03*
Y1565293D03*
Y1559293D03*
Y1562293D03*
X784352Y1574293D03*
Y1571293D03*
X781352Y1574293D03*
Y1571293D03*
X793352Y1574293D03*
Y1571293D03*
X790352Y1574293D03*
Y1571293D03*
X787352D03*
Y1574293D03*
X808800Y267900D03*
X806450Y310362D03*
X798400Y360600D03*
X802010Y439940D03*
X799637Y763625D03*
X799352Y1562293D03*
Y1559293D03*
Y1565293D03*
Y1568293D03*
X796352Y1562293D03*
Y1559293D03*
Y1565293D03*
Y1568293D03*
X799352Y1574293D03*
Y1571293D03*
X796352Y1574293D03*
Y1571293D03*
X818000Y378800D03*
X825003Y397276D03*
X824980Y413260D03*
X825100Y468900D03*
X822415Y479600D03*
X815650Y516807D03*
X821720Y515082D03*
X814800Y760922D03*
X822442Y762369D03*
X823352Y1565293D03*
Y1562293D03*
Y1559293D03*
Y1568293D03*
X826352Y1565293D03*
Y1562293D03*
Y1559293D03*
Y1568293D03*
X823352Y1571293D03*
Y1574293D03*
X826352Y1571293D03*
Y1574293D03*
X830975Y2388D03*
X830990Y4903D03*
X837268Y3597D03*
X830975Y22446D03*
Y8543D03*
Y12417D03*
X830990Y14932D03*
X830975Y18572D03*
X837268Y13626D03*
X830990Y24961D03*
X837268Y23655D03*
X832400Y427100D03*
X830600Y449200D03*
X838645Y492862D03*
X836847Y762495D03*
X829352Y1565293D03*
Y1562293D03*
Y1559293D03*
Y1568293D03*
X832352D03*
Y1565293D03*
Y1559293D03*
Y1562293D03*
X835352Y1568293D03*
Y1565293D03*
Y1559293D03*
Y1562293D03*
X838352Y1568293D03*
Y1565293D03*
Y1559293D03*
Y1562293D03*
X841352Y1568293D03*
Y1565293D03*
Y1559293D03*
Y1562293D03*
X829352Y1574293D03*
Y1571293D03*
X832352D03*
Y1574293D03*
X835352Y1571293D03*
Y1574293D03*
X838352Y1571293D03*
Y1574293D03*
X841352Y1571293D03*
Y1574293D03*
X846700Y476900D03*
X872320Y304936D03*
X869820D03*
X867320D03*
X864820D03*
X860531Y375826D03*
X870700Y402581D03*
X868352Y1568293D03*
Y1565293D03*
Y1559293D03*
Y1562293D03*
X865352Y1568293D03*
Y1565293D03*
Y1559293D03*
Y1562293D03*
X874352D03*
Y1559293D03*
Y1565293D03*
Y1568293D03*
X871352D03*
Y1565293D03*
Y1559293D03*
Y1562293D03*
X868352Y1574293D03*
Y1571293D03*
X865352Y1574293D03*
Y1571293D03*
X874352Y1574293D03*
Y1571293D03*
X871352D03*
Y1574293D03*
X887338Y296760D03*
X883352Y1562293D03*
Y1559293D03*
Y1565293D03*
Y1568293D03*
X880352Y1562293D03*
Y1559293D03*
Y1565293D03*
Y1568293D03*
X877352Y1562293D03*
Y1559293D03*
Y1565293D03*
Y1568293D03*
X883352Y1574293D03*
Y1571293D03*
X880352Y1574293D03*
Y1571293D03*
X877352Y1574293D03*
Y1571293D03*
X907352Y1568293D03*
Y1565293D03*
Y1559293D03*
Y1562293D03*
Y1574293D03*
Y1571293D03*
X910352Y1568293D03*
Y1565293D03*
Y1559293D03*
Y1562293D03*
X922352D03*
Y1559293D03*
Y1565293D03*
Y1568293D03*
X919352Y1562293D03*
Y1559293D03*
Y1565293D03*
Y1568293D03*
X916352Y1562293D03*
Y1559293D03*
Y1565293D03*
Y1568293D03*
X913352D03*
Y1565293D03*
Y1559293D03*
Y1562293D03*
X910352Y1574293D03*
Y1571293D03*
X922352Y1574293D03*
Y1571293D03*
X919352Y1574293D03*
Y1571293D03*
X916352Y1574293D03*
Y1571293D03*
X913352D03*
Y1574293D03*
X922320Y1660953D03*
X933217Y380693D03*
Y384693D03*
X925352Y1562293D03*
Y1559293D03*
Y1565293D03*
Y1568293D03*
Y1574293D03*
Y1571293D03*
X927122Y1661380D03*
X938220Y1661062D03*
X956980Y1536260D03*
X953980D03*
X950980D03*
X947980D03*
X944980D03*
Y1551260D03*
X947980D03*
X950980D03*
X953980D03*
X956980D03*
X944980Y1548260D03*
X947980D03*
X950980D03*
X953980D03*
X956980D03*
X944980Y1545260D03*
X947980D03*
X950980D03*
X953980D03*
X956980D03*
X944980Y1542260D03*
X947980D03*
X950980D03*
X953980D03*
X956980D03*
Y1539260D03*
X953980D03*
X950980D03*
X947980D03*
X944980D03*
Y1554260D03*
X947980D03*
X950980D03*
X953980D03*
X956980D03*
X946100Y1661100D03*
X963856Y398302D03*
X969000Y1536262D03*
X971700D03*
X969000Y1548262D03*
X971700D03*
X969000Y1545262D03*
X971700D03*
X969000Y1551262D03*
X971700D03*
Y1542262D03*
X969000D03*
X971700Y1539262D03*
X969000D03*
X971700Y1554262D03*
X965622Y1579240D03*
Y1576240D03*
Y1573240D03*
X988908Y373392D03*
X984254Y418379D03*
X974700Y1536262D03*
X980400D03*
X977700D03*
X974700Y1548262D03*
Y1545262D03*
Y1551262D03*
X980400Y1548262D03*
X977700D03*
X980400Y1545262D03*
X977700D03*
X980400Y1551262D03*
X977700D03*
Y1542262D03*
X980400D03*
X974700D03*
X977700Y1539262D03*
X980400D03*
X974700D03*
Y1554262D03*
X980400D03*
X977700D03*
X988988Y1579240D03*
Y1573240D03*
Y1576240D03*
X1006220Y160799D03*
X1002720D03*
X999220Y185299D03*
X1002720D03*
X1006220D03*
X998205Y195735D03*
Y192191D03*
X1000705Y195735D03*
Y192191D03*
X998205Y199278D03*
X1000705D03*
X998205Y202821D03*
X1000705D03*
X1006232Y343983D03*
X1001440Y359702D03*
X995066Y1536262D03*
X992466D03*
X1001066D03*
X1003766D03*
X998066D03*
X995066Y1551262D03*
X992466D03*
X995066Y1545262D03*
X992466D03*
X995066Y1548262D03*
X992466D03*
X1001066Y1551262D03*
X1003766D03*
X1001066Y1545262D03*
X1003766D03*
X1001066Y1548262D03*
X1003766D03*
X998066Y1551262D03*
Y1545262D03*
Y1548262D03*
Y1542262D03*
X1003766D03*
X1001066D03*
X992466D03*
X995066D03*
X998066Y1539262D03*
X1003766D03*
X1001066D03*
X992466D03*
X995066D03*
Y1554262D03*
X1001066D03*
X1003766D03*
X998066D03*
X1009720Y160799D03*
X1013220D03*
X1012000Y185299D03*
X1014900D03*
X1017800D03*
X1017200Y175699D03*
X1014300D03*
X1019900Y175799D03*
X1020720Y310937D03*
X1009009Y419948D03*
X1021239Y416974D03*
X1021612Y1536262D03*
X1016012D03*
X1018612D03*
Y1551262D03*
X1016012D03*
X1018612Y1545262D03*
X1016012D03*
X1018612Y1548262D03*
X1016012D03*
X1021612Y1551262D03*
Y1545262D03*
Y1548262D03*
X1018612Y1542262D03*
X1016012D03*
X1021612D03*
Y1539262D03*
X1016012D03*
X1018612D03*
Y1554262D03*
X1021612D03*
X1012354Y1579240D03*
Y1573240D03*
Y1576240D03*
X1023407Y-27681D03*
X1029700Y-26472D03*
X1023407Y-32055D03*
X1029700Y-37001D03*
X1023407Y-17652D03*
X1023422Y-15137D03*
X1023407Y-11497D03*
X1029700Y-16443D03*
X1023422Y-25166D03*
X1023407Y-21526D03*
X1029700Y3615D03*
X1023422Y4921D03*
X1023407Y2406D03*
X1023422Y-5108D03*
X1023407Y-7623D03*
Y-1468D03*
X1029700Y-6414D03*
X1023407Y22464D03*
Y18590D03*
Y8561D03*
X1023422Y14950D03*
X1023407Y12435D03*
X1029700Y13644D03*
Y23673D03*
X1023422Y24979D03*
X1022800Y175799D03*
X1033285Y353627D03*
X1038320Y407062D03*
Y404462D03*
X1027212Y1536262D03*
X1024612D03*
Y1551262D03*
X1027212D03*
X1024612Y1545262D03*
X1027212D03*
X1024612Y1548262D03*
X1027212D03*
X1024612Y1542262D03*
X1027212D03*
Y1539262D03*
X1024612D03*
Y1554262D03*
X1027212D03*
X1035720Y1579240D03*
Y1573240D03*
Y1576240D03*
X1054820Y370162D03*
X1053354Y1286714D03*
Y1291714D03*
X1039510Y1296655D03*
X1049510D03*
X1044510D03*
X1039510Y1293155D03*
X1049510D03*
X1044510D03*
X1053354Y1296714D03*
X1041798Y1536262D03*
X1047798D03*
X1050498D03*
X1044798D03*
X1039298D03*
X1041798Y1551262D03*
X1039298D03*
X1041798Y1545262D03*
X1039298D03*
X1041798Y1548262D03*
X1039298D03*
X1047798Y1551262D03*
X1050498D03*
X1047798Y1545262D03*
X1050498D03*
X1047798Y1548262D03*
X1050498D03*
X1044798Y1551262D03*
Y1545262D03*
Y1548262D03*
X1039298Y1542262D03*
X1044798D03*
X1050498D03*
X1047798D03*
X1041798D03*
X1044798Y1539262D03*
X1050498D03*
X1047798D03*
X1039298D03*
X1041798D03*
Y1554262D03*
X1047798D03*
X1050498D03*
X1044798D03*
X1063354Y1286714D03*
X1058354D03*
X1063354Y1291714D03*
X1058354D03*
X1063354Y1296714D03*
X1058290Y1296302D03*
X1065164Y1536262D03*
X1062464D03*
X1071164D03*
X1068164D03*
X1065164Y1551262D03*
X1062464D03*
X1065164Y1545262D03*
X1062464D03*
X1065164Y1548262D03*
X1062464D03*
X1071164Y1551262D03*
Y1545262D03*
Y1548262D03*
X1068164Y1551262D03*
Y1545262D03*
Y1548262D03*
Y1542262D03*
X1071164D03*
X1062464D03*
X1065164D03*
X1068164Y1539262D03*
X1071164D03*
X1062464D03*
X1065164D03*
Y1554262D03*
X1071164D03*
X1068164D03*
X1059086Y1579240D03*
Y1573240D03*
Y1576240D03*
X1087330Y369061D03*
Y374131D03*
Y379251D03*
X1073589Y506461D03*
X1083714Y1285144D03*
Y1288144D03*
Y1291144D03*
X1073864Y1536262D03*
X1085830D03*
X1073864Y1551262D03*
Y1545262D03*
Y1548262D03*
X1085830Y1551262D03*
Y1545262D03*
Y1548262D03*
Y1542262D03*
X1073864D03*
X1085830Y1539262D03*
X1073864D03*
Y1554262D03*
X1090279Y126524D03*
X1089714Y1285144D03*
X1088530Y1536262D03*
X1091530D03*
X1088530Y1551262D03*
Y1545262D03*
Y1548262D03*
X1094530Y1551262D03*
X1097230D03*
X1094530Y1545262D03*
X1097230D03*
X1094530Y1548262D03*
X1097230D03*
X1091530Y1551262D03*
Y1545262D03*
Y1548262D03*
Y1542262D03*
X1097230D03*
X1094530D03*
X1088530D03*
X1091530Y1539262D03*
X1094530D03*
X1088530D03*
Y1554262D03*
X1094530D03*
X1097230D03*
X1091530D03*
X1102930Y1668690D03*
X1116338Y1711380D03*
X1113055Y1718338D03*
X1130841Y1462953D03*
X1128341Y1465453D03*
Y1462953D03*
X1130841Y1465453D03*
X1133841Y1462953D03*
Y1465453D03*
X1128341Y1468453D03*
X1130841D03*
X1133841D03*
X1128341Y1460453D03*
X1130841D03*
X1133841D03*
Y1471453D03*
X1130841D03*
X1128341D03*
X1137315Y379592D03*
X1144247Y1372700D03*
Y1370200D03*
X1146797Y1372700D03*
X1149297D03*
X1146797Y1370200D03*
X1149297D03*
X1144247Y1375200D03*
X1146797D03*
X1149297D03*
X1144247Y1377700D03*
Y1380200D03*
Y1382700D03*
X1146797D03*
X1149297D03*
X1146797Y1380200D03*
Y1377700D03*
X1149297Y1380200D03*
Y1377700D03*
X1156790Y363231D03*
X1170595Y170056D03*
X1181476Y172247D03*
X1181369Y199234D03*
X1182747Y1372700D03*
X1185297D03*
X1182747Y1370200D03*
X1185297D03*
X1182747Y1375200D03*
X1185297D03*
X1182747Y1380200D03*
Y1377700D03*
Y1382700D03*
X1185297D03*
Y1377700D03*
Y1380200D03*
X1186340Y204492D03*
X1188500Y205772D03*
X1187797Y1372700D03*
Y1370200D03*
Y1375200D03*
Y1382700D03*
Y1377700D03*
Y1380200D03*
X1201700Y110000D03*
X1213980Y1676500D03*
X1232182Y110659D03*
X1223650Y520672D03*
X1230650D03*
X1227150D03*
X1250010Y117121D03*
X1246878Y248615D03*
X1248150Y520672D03*
X1244650D03*
X1241150D03*
X1237650D03*
X1234150D03*
X1258539Y100900D03*
X1255150Y306211D03*
X1251650Y520672D03*
X1255150D03*
X1266722Y101005D03*
X1271150Y305792D03*
X1280135Y1345202D03*
Y1342602D03*
X1280312Y1365689D03*
X1290005Y290268D03*
X1291205Y1345875D03*
X1286005Y1342768D03*
Y1345875D03*
X1296405Y1342768D03*
X1293805D03*
X1288605D03*
X1291205D03*
X1288605Y1345875D03*
X1293805D03*
X1291405Y1348982D03*
X1294005D03*
X1292916Y1352531D03*
X1290436D03*
X1287956D03*
X1292916Y1358131D03*
X1290436D03*
X1287956D03*
X1283280Y1372301D03*
X1293887Y1370043D03*
X1294477Y1372651D03*
X1311952Y1321945D03*
X1307656Y1337104D03*
Y1334504D03*
Y1329304D03*
Y1331904D03*
X1305056Y1339704D03*
X1312488Y1348353D03*
X1299605Y1342768D03*
X1302549Y1345891D03*
X1302520Y1348762D03*
X1315058Y1349488D03*
X1302549Y1342784D03*
X1308616Y1363345D03*
Y1360445D03*
X1306082Y1359315D03*
X1306182Y1362315D03*
X1304016Y1363945D03*
Y1361045D03*
X1308616Y1357945D03*
X1317883Y1269978D03*
X1317895Y1272485D03*
X1320393Y1269948D03*
X1320405Y1272455D03*
X1317895Y1274985D03*
X1320405Y1274955D03*
X1317895Y1277485D03*
X1320405Y1277455D03*
X1317970Y1322741D03*
Y1319634D03*
X1325770Y1322741D03*
X1323170D03*
X1331570Y1319634D03*
X1323170D03*
X1325770D03*
X1328370D03*
X1320570Y1322741D03*
Y1319634D03*
X1322444Y1329497D03*
X1324924D03*
X1319964D03*
X1322444Y1335097D03*
X1324924D03*
X1319964D03*
X1323370Y1325848D03*
X1325970D03*
X1324945Y1346877D03*
X1327196Y1349068D03*
X1331288Y1372440D03*
X1327491Y1372358D03*
X1324491Y1372658D03*
X1327491Y1375858D03*
X1331288Y1375940D03*
X1324491Y1375858D03*
X1327491Y1381478D03*
Y1378478D03*
X1331288Y1378560D03*
X1324491Y1381478D03*
Y1378478D03*
X1322270Y1422454D03*
X1331428Y1422584D03*
X1328050D03*
X1325126Y1422630D03*
X1332726Y-27681D03*
X1339019Y-26472D03*
X1332726Y-32055D03*
X1339019Y-37001D03*
X1332726Y-11497D03*
X1339019Y-16443D03*
X1332741Y-15137D03*
X1332726Y-17652D03*
Y-21526D03*
X1332741Y-25166D03*
X1332726Y2406D03*
X1332741Y4921D03*
X1339019Y3615D03*
X1332726Y-1468D03*
X1339019Y-6414D03*
X1332726Y-7623D03*
X1332741Y-5108D03*
X1332726Y18590D03*
Y22464D03*
X1339019Y13644D03*
X1332726Y12435D03*
X1332741Y14950D03*
X1332726Y8561D03*
X1332741Y24979D03*
X1339019Y23673D03*
X1344080Y1305919D03*
Y1308519D03*
X1334514Y1322757D03*
Y1319650D03*
X1339784Y1309106D03*
X1338534Y1319406D03*
X1339784Y1316906D03*
Y1314306D03*
Y1311706D03*
X1337184Y1316906D03*
X1334414Y1325853D03*
X1347015Y1335876D03*
X1343631Y1332568D03*
X1336144Y1341147D03*
X1338288Y1339653D03*
X1340488Y1340853D03*
X1336144Y1338247D03*
X1340214Y1334853D03*
X1340410Y1338017D03*
X1338288Y1336553D03*
X1334288Y1372440D03*
X1340288D03*
X1346193Y1372523D03*
X1343193D03*
X1337288Y1372440D03*
Y1375940D03*
X1334288D03*
X1343193Y1376023D03*
X1346193D03*
X1340288Y1375940D03*
X1352474Y1256866D03*
X1349964Y1256896D03*
X1352486Y1259373D03*
X1349976Y1259403D03*
Y1261903D03*
X1352486Y1261873D03*
Y1264373D03*
X1349976Y1264403D03*
X1350098Y1306208D03*
X1352698D03*
X1355298D03*
X1360498D03*
X1363698D03*
X1357898D03*
X1352698Y1309315D03*
X1350098D03*
X1355498Y1312422D03*
X1358098D03*
X1355298Y1309315D03*
X1357898D03*
X1352092Y1316071D03*
Y1321671D03*
X1357052Y1316071D03*
X1354572D03*
X1357052Y1321671D03*
X1354572D03*
X1356983Y1334095D03*
X1359516Y1334058D03*
X1352666Y1378560D03*
X1349666D03*
X1352666Y1381560D03*
X1349666D03*
X1352666Y1375940D03*
X1349666D03*
X1352126Y1401986D03*
Y1404986D03*
X1352166Y1420456D03*
Y1414456D03*
Y1411456D03*
Y1408456D03*
Y1417456D03*
X1374938Y1161569D03*
Y1170069D03*
X1370662Y1305980D03*
X1376208Y1305919D03*
X1366642Y1306224D03*
X1376208Y1308519D03*
X1366542Y1312427D03*
X1366642Y1309331D03*
X1368272Y1324821D03*
X1372538Y1324591D03*
X1370338Y1323091D03*
X1372538Y1321691D03*
X1379271Y1335963D03*
X1375814Y1332653D03*
X1368272Y1327721D03*
X1370438Y1326091D03*
X1372538Y1327491D03*
X1390600Y248262D03*
X1396081Y1161569D03*
Y1170069D03*
X1384652Y1256866D03*
X1382142Y1256896D03*
X1384664Y1259373D03*
X1382154Y1259403D03*
Y1261903D03*
X1384664Y1261873D03*
Y1264373D03*
X1382154Y1264403D03*
X1382226Y1306208D03*
X1384826D03*
X1387426D03*
X1390026D03*
X1392626D03*
X1395826D03*
X1386700Y1321671D03*
X1389180D03*
X1382226Y1309315D03*
X1384826D03*
X1390226Y1312422D03*
X1387626D03*
X1390026Y1309315D03*
X1387426D03*
X1384220Y1316071D03*
Y1321671D03*
X1389180Y1316071D03*
X1386700D03*
X1390758Y1333473D03*
X1392076Y1335658D03*
X1398831Y1161569D03*
Y1170069D03*
X1398770Y1306224D03*
X1408336Y1305919D03*
X1402790Y1305980D03*
X1408336Y1308519D03*
X1398670Y1312427D03*
X1398770Y1309331D03*
X1400400Y1324821D03*
X1404666Y1324591D03*
X1402466Y1323091D03*
X1404666Y1321691D03*
X1411124Y1335924D03*
X1407719Y1332560D03*
X1402566Y1326091D03*
X1400400Y1327721D03*
X1404666Y1327491D03*
X1416999Y1256866D03*
X1414489Y1256896D03*
X1417011Y1259373D03*
X1414501Y1259403D03*
Y1261903D03*
X1417011Y1261873D03*
Y1264373D03*
X1414501Y1264403D03*
X1414354Y1306208D03*
X1416954D03*
X1419554D03*
X1422154D03*
X1424754D03*
X1427954D03*
X1418828Y1316071D03*
X1416348D03*
X1418828Y1321671D03*
X1416348D03*
X1421308Y1316071D03*
Y1321671D03*
X1414354Y1309315D03*
X1416954D03*
X1419554D03*
X1422354Y1312422D03*
X1419754D03*
X1422154Y1309315D03*
X1421294Y1334095D03*
X1423656Y1335468D03*
X1430898Y1306224D03*
X1434582Y1306791D03*
X1440507Y1305430D03*
X1440464Y1308519D03*
X1437182Y1306791D03*
X1430798Y1312427D03*
X1430898Y1309331D03*
X1432528Y1324821D03*
X1436794Y1324591D03*
X1434594Y1323091D03*
X1436794Y1321691D03*
X1443785Y1335981D03*
X1440879Y1333085D03*
X1434694Y1326091D03*
X1432528Y1327721D03*
X1436794Y1327491D03*
X1458720Y145362D03*
X1449600Y402322D03*
X1447149Y1161569D03*
X1449649D03*
X1447149Y1170069D03*
X1449649D03*
X1449176Y1256866D03*
X1446666Y1256896D03*
X1449188Y1259373D03*
X1446678Y1259403D03*
Y1261903D03*
X1449188Y1261873D03*
Y1264373D03*
X1446678Y1264403D03*
X1446482Y1306208D03*
X1449082D03*
X1451682D03*
X1456882D03*
X1460082D03*
X1454282D03*
X1450956Y1321671D03*
X1448476D03*
X1453436Y1316071D03*
Y1321671D03*
X1446482Y1309315D03*
X1451882Y1312422D03*
X1449082Y1309315D03*
X1451682D03*
X1454482Y1312422D03*
X1454282Y1309315D03*
X1450956Y1316071D03*
X1448476D03*
X1453303Y1334095D03*
X1455436Y1335598D03*
X1470220Y169862D03*
X1463808Y244948D03*
X1463510Y273878D03*
X1476291Y1278104D03*
X1472592Y1306345D03*
X1463026Y1306224D03*
X1467046Y1305980D03*
X1472361Y1322440D03*
X1472592Y1308945D03*
Y1316745D03*
Y1314145D03*
Y1311545D03*
X1462926Y1312427D03*
X1463026Y1309331D03*
X1466819Y1324018D03*
X1469019Y1322618D03*
Y1325518D03*
X1464680Y1325772D03*
X1469019Y1328418D03*
X1466919Y1327018D03*
X1464680Y1328672D03*
X1475599Y1349468D03*
X1481361Y1280054D03*
X1492101D03*
X1478821D03*
X1486410Y1322741D03*
X1483810D03*
X1486410Y1319634D03*
X1483810D03*
X1481210Y1322741D03*
Y1319634D03*
X1492210D03*
X1489010D03*
X1478610Y1322741D03*
Y1319634D03*
X1484010Y1325848D03*
X1486610D03*
X1485564Y1335097D03*
X1483084D03*
X1485564Y1329497D03*
X1483084D03*
X1480604Y1335097D03*
Y1329497D03*
X1485523Y1347521D03*
X1487386Y1349258D03*
X1508049Y280056D03*
X1495150Y369842D03*
X1503450Y385843D03*
X1494641Y1280054D03*
X1506591Y1297014D03*
X1508711Y1298434D03*
X1495154Y1322757D03*
Y1319650D03*
X1499048Y1319946D03*
X1504720Y1329143D03*
X1495054Y1325853D03*
X1503786Y1326076D03*
X1504518Y1335982D03*
X1496784Y1341147D03*
X1498924Y1334882D03*
X1498950Y1339517D03*
X1501149Y1336287D03*
X1496784Y1338247D03*
X1504720Y1342143D03*
Y1344743D03*
X1505116Y1369724D03*
X1514593Y235116D03*
X1522258Y288956D03*
X1513791Y1298464D03*
X1516351D03*
X1511251D03*
X1515212Y1352295D03*
X1512732D03*
X1517692D03*
X1515212Y1357895D03*
X1512732D03*
X1517692D03*
X1518451Y1369919D03*
X1535520Y151562D03*
X1540958Y307756D03*
X1541211Y646178D03*
X1533178Y1360815D03*
X1530978Y1359315D03*
X1528912Y1361045D03*
X1531078Y1362315D03*
X1533178Y1363715D03*
X1528912Y1363945D03*
X1533178Y1357915D03*
X1557320Y203297D03*
X1543958Y307556D03*
X1546458Y307856D03*
X1570675Y267857D03*
X1591368Y628727D03*
X1591428Y626177D03*
X1588928D03*
X1588868Y628727D03*
X1591398Y631237D03*
X1588898D03*
X1591368Y650877D03*
X1591338Y648367D03*
X1591398Y645817D03*
X1588868Y650877D03*
X1588838Y648367D03*
X1588898Y645817D03*
X1591368Y653377D03*
X1588868D03*
X1591448Y657677D03*
X1588948D03*
Y660177D03*
X1591448D03*
X1588968Y665237D03*
X1591468D03*
X1588938Y662727D03*
X1591438D03*
X1588938Y679807D03*
X1588878Y682357D03*
X1588908Y684867D03*
X1591438Y679807D03*
X1591378Y682357D03*
X1591408Y684867D03*
X1591328Y696727D03*
X1591388Y694177D03*
X1588888D03*
X1588828Y696727D03*
X1591358Y699277D03*
X1588858D03*
X1591358Y718837D03*
X1591328Y716327D03*
X1591388Y713777D03*
X1588858Y718837D03*
X1588828Y716327D03*
X1588888Y713777D03*
X1603706Y211526D03*
X1604270Y231490D03*
X1601830Y590685D03*
X1604430D03*
X1601830Y615201D03*
X1604430D03*
X1598868Y628727D03*
X1598928Y626177D03*
X1593868Y628727D03*
X1593928Y626177D03*
X1596428D03*
X1596368Y628727D03*
X1598898Y631237D03*
X1593898D03*
X1596398D03*
X1598868Y650877D03*
X1598838Y648367D03*
X1596368Y650877D03*
X1593868D03*
X1596338Y648367D03*
X1593838D03*
X1598898Y645817D03*
X1596398D03*
X1593898D03*
X1598868Y653377D03*
X1596368D03*
X1593868D03*
X1598948Y657677D03*
X1593948D03*
X1596448D03*
Y660177D03*
X1593948D03*
X1598948D03*
X1596468Y665237D03*
X1593968D03*
X1598968D03*
X1596438Y662727D03*
X1593938D03*
X1598938D03*
X1593938Y679807D03*
X1596438D03*
X1593878Y682357D03*
X1596378D03*
X1593908Y684867D03*
X1596408D03*
X1598878Y682357D03*
X1598908Y684867D03*
X1598938Y679807D03*
X1596288Y688902D03*
X1598888D03*
X1598828Y696727D03*
X1593828D03*
X1593888Y694177D03*
X1596388D03*
X1596328Y696727D03*
X1593858Y699277D03*
X1596358D03*
X1598888Y694177D03*
X1596288Y691502D03*
X1598858Y699277D03*
X1598888Y691502D03*
X1598858Y718837D03*
X1598828Y716327D03*
X1596358Y718837D03*
X1593858D03*
X1596328Y716327D03*
X1593828D03*
X1596388Y713777D03*
X1593888D03*
X1598888D03*
X1596250Y721452D03*
X1598850D03*
X1599010Y724002D03*
X1631203Y1367492D03*
X1628653D03*
X1626153D03*
X1628653Y1372492D03*
X1631203D03*
X1626153D03*
X1631203Y1369992D03*
X1628653D03*
X1626153D03*
X1628653Y1379992D03*
Y1382492D03*
Y1377492D03*
Y1374992D03*
X1631203Y1377492D03*
Y1374992D03*
Y1379992D03*
Y1382492D03*
X1626153Y1379992D03*
Y1382492D03*
Y1374992D03*
Y1377492D03*
X1651851Y532057D03*
X1649220Y620662D03*
X1650771Y1367492D03*
X1648271D03*
X1645721D03*
X1648271Y1372492D03*
X1650771D03*
X1645721D03*
X1650771Y1369992D03*
X1648271D03*
X1645721D03*
X1648271Y1379992D03*
Y1382492D03*
X1650771Y1379992D03*
Y1382492D03*
X1648271Y1377492D03*
Y1374992D03*
X1650771Y1377492D03*
Y1374992D03*
X1645721Y1377492D03*
Y1374992D03*
Y1379992D03*
Y1382492D03*
X1669303Y1372492D03*
X1664253D03*
X1666753D03*
X1669303Y1367492D03*
Y1369992D03*
X1666753Y1367492D03*
X1664253D03*
Y1369992D03*
X1666753D03*
X1669303Y1379992D03*
Y1382492D03*
Y1377492D03*
Y1374992D03*
X1666753Y1379992D03*
X1664253D03*
X1666753Y1382492D03*
X1664253D03*
X1666753Y1377492D03*
X1664253D03*
Y1374992D03*
X1666753D03*
X1688301Y722158D03*
X1683121D03*
X1680401D03*
X1688912Y1372492D03*
X1686362D03*
Y1367492D03*
Y1369992D03*
X1688912Y1367492D03*
Y1369992D03*
Y1377492D03*
Y1374992D03*
Y1382492D03*
Y1379992D03*
X1686362D03*
Y1382492D03*
Y1374992D03*
Y1377492D03*
X1703452Y639381D03*
X1700852Y655141D03*
X1703452Y647341D03*
Y649941D03*
Y652541D03*
Y644741D03*
X1698232Y655200D03*
X1703452Y641981D03*
X1700922Y657781D03*
X1698302Y657840D03*
X1698920Y698562D03*
X1695227Y722325D03*
X1699307Y722465D03*
X1698137Y718345D03*
X1701087Y719055D03*
X1695367Y719345D03*
X1691021Y722158D03*
X1698537Y766015D03*
X1714490Y142920D03*
X1718110Y159040D03*
X1706720Y703762D03*
X1709107Y728449D03*
X1723018Y101667D03*
X1723218Y93267D03*
X1737020Y112177D03*
Y109677D03*
X1723090Y173072D03*
Y177072D03*
X1734857Y184865D03*
X1738014Y1287344D03*
X1747650Y109677D03*
Y112177D03*
X1744106Y109677D03*
Y112177D03*
X1740563Y109677D03*
Y112177D03*
X1747814Y1287344D03*
X1742714Y1287244D03*
X1754165Y1304422D03*
Y1307422D03*
Y1301422D03*
Y1295422D03*
Y1298422D03*
Y1310422D03*
X1758063Y72623D03*
X1763435Y166862D03*
X1757165Y1304422D03*
X1760165D03*
Y1307422D03*
X1757165D03*
Y1301422D03*
X1760165D03*
X1769165Y1295422D03*
X1766165D03*
X1763165D03*
X1760165D03*
X1757165D03*
X1760165Y1298422D03*
X1757165D03*
X1763165D03*
X1766165D03*
X1769165D03*
X1757165Y1310422D03*
X1760165D03*
X1778578Y97927D03*
X1778478Y90627D03*
X1778165Y1295422D03*
X1775165D03*
X1772165D03*
Y1298422D03*
X1775165D03*
X1778165D03*
X1784165Y1295422D03*
Y1298422D03*
X1781165Y1295422D03*
Y1298422D03*
X1778165Y1312922D03*
X1784165D03*
X1781165D03*
G54D53*
X828780Y1694890D03*
Y1684890D03*
X818780Y1694890D03*
Y1684890D03*
X828780Y1704890D03*
X818780D03*
X828780Y1714890D03*
X818780D03*
X853780Y1694890D03*
Y1684890D03*
Y1704890D03*
Y1714890D03*
X863780Y1694890D03*
Y1684890D03*
Y1704890D03*
Y1714890D03*
X888780Y1684890D03*
Y1694890D03*
Y1704890D03*
Y1714890D03*
X898780Y1684890D03*
Y1694890D03*
Y1704890D03*
Y1714890D03*
X918780Y1704890D03*
X958780Y1694890D03*
Y1684890D03*
Y1704890D03*
Y1714890D03*
X968780Y1694890D03*
Y1684890D03*
Y1704890D03*
Y1714890D03*
X993780Y1684890D03*
Y1694890D03*
X1003780Y1684890D03*
Y1694890D03*
X993780Y1704890D03*
Y1714890D03*
X1003780Y1704890D03*
Y1714890D03*
X1028780Y1684890D03*
Y1694890D03*
X1038780Y1684890D03*
Y1694890D03*
X1028780Y1704890D03*
Y1714890D03*
X1038780Y1704890D03*
Y1714890D03*
G54D68*
X1879155Y592848D03*
Y840748D03*
X1889155Y592848D03*
Y840748D03*
X1900275Y964708D03*
X1910275D03*
X1931395Y592868D03*
X1921395D03*
X1952395Y1205248D03*
X1942395D03*
X1963362Y593010D03*
X1973362D03*
X1984482Y1205220D03*
X1994482D03*
X2015452Y593020D03*
X2005452D03*
X2026452Y1205400D03*
X2047419Y593162D03*
X2036452Y1205400D03*
X2057419Y593162D03*
X2078539Y1205372D03*
X2068539D03*
G54D13*
X27699Y770144D03*
Y783530D03*
Y776837D03*
Y800263D03*
Y793570D03*
Y820341D03*
Y813648D03*
Y806955D03*
Y830381D03*
Y850459D03*
Y843766D03*
Y837074D03*
Y867192D03*
Y857152D03*
Y880577D03*
Y873885D03*
Y893963D03*
Y887270D03*
Y917389D03*
Y910696D03*
Y904003D03*
Y930774D03*
Y924081D03*
Y947507D03*
Y940814D03*
Y964239D03*
Y954200D03*
Y977625D03*
Y970932D03*
Y991011D03*
Y984318D03*
Y1031168D03*
Y1024475D03*
Y1017782D03*
Y1044554D03*
Y1037861D03*
Y1057940D03*
Y1051247D03*
Y1078018D03*
Y1071326D03*
Y1064633D03*
Y1094751D03*
Y1088058D03*
Y1108137D03*
Y1101444D03*
Y1124869D03*
Y1114829D03*
Y1144948D03*
Y1138255D03*
Y1131562D03*
Y1161680D03*
Y1151641D03*
Y1175066D03*
Y1168373D03*
Y1188452D03*
Y1181759D03*
Y1205184D03*
Y1198491D03*
Y1225263D03*
Y1218570D03*
Y1211877D03*
Y1241995D03*
Y1235302D03*
Y1248688D03*
Y1265420D03*
X43841Y766798D03*
X36399Y770144D03*
X43841Y780184D03*
Y773491D03*
X36399Y783530D03*
Y776837D03*
X43841Y803609D03*
Y796916D03*
Y790223D03*
X36399Y800263D03*
Y793570D03*
X43841Y816995D03*
Y810302D03*
X36399Y820341D03*
Y813648D03*
Y806955D03*
X43841Y833727D03*
Y827034D03*
X36399Y830381D03*
X43841Y847113D03*
Y840420D03*
X36399Y850459D03*
Y843766D03*
Y837074D03*
X43841Y863845D03*
Y853806D03*
X36399Y867192D03*
Y857152D03*
X43841Y883924D03*
Y877231D03*
Y870538D03*
X36399Y880577D03*
Y873885D03*
X43841Y900656D03*
Y890617D03*
X36399Y893963D03*
Y887270D03*
X43841Y914042D03*
Y907349D03*
X36399Y917389D03*
Y910696D03*
Y904003D03*
X43841Y927428D03*
Y920735D03*
X36399Y930774D03*
Y924081D03*
X43841Y944160D03*
Y937467D03*
X36399Y947507D03*
Y940814D03*
X43841Y960892D03*
Y950853D03*
X36399Y964239D03*
Y954200D03*
X43841Y980971D03*
Y974278D03*
Y967585D03*
X36399Y977625D03*
Y970932D03*
X43841Y987664D03*
X36399Y991011D03*
Y984318D03*
X43841Y1027822D03*
Y1017782D03*
X36399Y1031168D03*
Y1024475D03*
Y1017782D03*
X43841Y1047900D03*
Y1041207D03*
Y1034515D03*
X36399Y1044554D03*
Y1037861D03*
X43841Y1061286D03*
Y1054593D03*
X36399Y1057940D03*
Y1051247D03*
X43841Y1074672D03*
Y1067979D03*
X36399Y1078018D03*
Y1071326D03*
Y1064633D03*
X43841Y1091404D03*
Y1084711D03*
X36399Y1094751D03*
Y1088058D03*
X43841Y1111483D03*
Y1104790D03*
Y1098097D03*
X36399Y1108137D03*
Y1101444D03*
X43841Y1128215D03*
Y1121522D03*
X36399Y1124869D03*
Y1114829D03*
X43841Y1141601D03*
Y1134908D03*
X36399Y1144948D03*
Y1138255D03*
Y1131562D03*
X43841Y1158333D03*
Y1148294D03*
X36399Y1161680D03*
Y1151641D03*
X43841Y1171719D03*
Y1165026D03*
X36399Y1175066D03*
Y1168373D03*
X43841Y1185105D03*
Y1178412D03*
X36399Y1188452D03*
Y1181759D03*
X43841Y1208530D03*
Y1201837D03*
Y1195144D03*
X36399Y1205184D03*
Y1198491D03*
X43841Y1221916D03*
Y1215223D03*
X36399Y1225263D03*
Y1218570D03*
Y1211877D03*
X43841Y1238648D03*
Y1231955D03*
X36399Y1241995D03*
Y1235302D03*
X43841Y1245341D03*
X36399Y1248688D03*
X43841Y1262074D03*
Y1265420D03*
X57399Y770144D03*
X52541Y766798D03*
X57399Y783530D03*
Y776837D03*
X52541Y780184D03*
Y773491D03*
X57399Y800263D03*
Y793570D03*
X52541Y803609D03*
Y796916D03*
Y790223D03*
X57399Y820341D03*
Y813648D03*
Y806955D03*
X52541Y816995D03*
Y810302D03*
X57399Y830381D03*
X52541Y833727D03*
Y827034D03*
X57399Y850459D03*
Y843766D03*
Y837074D03*
X52541Y847113D03*
Y840420D03*
X57399Y867192D03*
Y857152D03*
X52541Y863845D03*
Y853806D03*
X57399Y880577D03*
Y873885D03*
X52541Y883924D03*
Y877231D03*
Y870538D03*
X57399Y893963D03*
Y887270D03*
X52541Y900656D03*
Y890617D03*
X57399Y917389D03*
Y910696D03*
Y904003D03*
X52541Y914042D03*
Y907349D03*
X57399Y930774D03*
Y924081D03*
X52541Y927428D03*
Y920735D03*
X57399Y947507D03*
Y940814D03*
X52541Y944160D03*
Y937467D03*
X57399Y964239D03*
Y954200D03*
X52541Y960892D03*
Y950853D03*
X57399Y977625D03*
Y970932D03*
X52541Y980971D03*
Y974278D03*
Y967585D03*
X57399Y991011D03*
Y984318D03*
X52541Y987664D03*
X57399Y1031168D03*
Y1024475D03*
Y1017782D03*
X52541Y1027822D03*
Y1017782D03*
X57399Y1044554D03*
Y1037861D03*
X52541Y1047900D03*
Y1041207D03*
Y1034515D03*
X57399Y1057940D03*
Y1051247D03*
X52541Y1061286D03*
Y1054593D03*
X57399Y1078018D03*
Y1071326D03*
Y1064633D03*
X52541Y1074672D03*
Y1067979D03*
X57399Y1094751D03*
Y1088058D03*
X52541Y1091404D03*
Y1084711D03*
X57399Y1108137D03*
Y1101444D03*
X52541Y1111483D03*
Y1104790D03*
Y1098097D03*
X57399Y1124869D03*
Y1114829D03*
X52541Y1128215D03*
Y1121522D03*
X57399Y1144948D03*
Y1138255D03*
Y1131562D03*
X52541Y1141601D03*
Y1134908D03*
X57399Y1161680D03*
Y1151641D03*
X52541Y1158333D03*
Y1148294D03*
X57399Y1175066D03*
Y1168373D03*
X52541Y1171719D03*
Y1165026D03*
X57399Y1188452D03*
Y1181759D03*
X52541Y1185105D03*
Y1178412D03*
X57399Y1205184D03*
Y1198491D03*
X52541Y1208530D03*
Y1201837D03*
Y1195144D03*
X57399Y1225263D03*
Y1218570D03*
Y1211877D03*
X52541Y1221916D03*
Y1215223D03*
X57399Y1241995D03*
Y1235302D03*
X52541Y1238648D03*
Y1231955D03*
Y1248688D03*
X57399D03*
X52541Y1245341D03*
X57399Y1265420D03*
X73541Y766798D03*
X66099Y770144D03*
X73541Y780184D03*
Y773491D03*
X66099Y783530D03*
Y776837D03*
X73541Y803609D03*
Y796916D03*
Y790223D03*
X66099Y800263D03*
Y793570D03*
X73541Y816995D03*
Y810302D03*
X66099Y820341D03*
Y813648D03*
Y806955D03*
X73541Y833727D03*
Y827034D03*
X66099Y830381D03*
X73541Y847113D03*
Y840420D03*
X66099Y850459D03*
Y843766D03*
Y837074D03*
X73541Y863845D03*
Y853806D03*
X66099Y867192D03*
Y857152D03*
X73541Y883924D03*
Y877231D03*
Y870538D03*
X66099Y880577D03*
Y873885D03*
X73541Y900656D03*
Y890617D03*
X66099Y893963D03*
Y887270D03*
X73541Y914042D03*
Y907349D03*
X66099Y917389D03*
Y910696D03*
Y904003D03*
X73541Y927428D03*
Y920735D03*
X66099Y930774D03*
Y924081D03*
X73541Y944160D03*
Y937467D03*
X66099Y947507D03*
Y940814D03*
X73541Y960892D03*
Y950853D03*
X66099Y964239D03*
Y954200D03*
X73541Y980971D03*
Y974278D03*
Y967585D03*
X66099Y977625D03*
Y970932D03*
X73541Y987664D03*
X66099Y991011D03*
Y984318D03*
X73541Y1027822D03*
Y1017782D03*
X66099Y1031168D03*
Y1024475D03*
Y1017782D03*
X73541Y1047900D03*
Y1041207D03*
Y1034515D03*
X66099Y1044554D03*
Y1037861D03*
X73541Y1061286D03*
Y1054593D03*
X66099Y1057940D03*
Y1051247D03*
X73541Y1074672D03*
Y1067979D03*
X66099Y1078018D03*
Y1071326D03*
Y1064633D03*
X73541Y1091404D03*
Y1084711D03*
X66099Y1094751D03*
Y1088058D03*
X73541Y1111483D03*
Y1104790D03*
Y1098097D03*
X66099Y1108137D03*
Y1101444D03*
X73541Y1128215D03*
Y1121522D03*
X66099Y1124869D03*
Y1114829D03*
X73541Y1141601D03*
Y1134908D03*
X66099Y1144948D03*
Y1138255D03*
Y1131562D03*
X73541Y1158333D03*
Y1148294D03*
X66099Y1161680D03*
Y1151641D03*
X73541Y1171719D03*
Y1165026D03*
X66099Y1175066D03*
Y1168373D03*
X73541Y1185105D03*
Y1178412D03*
X66099Y1188452D03*
Y1181759D03*
X73541Y1208530D03*
Y1201837D03*
Y1195144D03*
X66099Y1205184D03*
Y1198491D03*
X73541Y1221916D03*
Y1215223D03*
X66099Y1225263D03*
Y1218570D03*
Y1211877D03*
X73541Y1238648D03*
Y1231955D03*
X66099Y1241995D03*
Y1235302D03*
X73541Y1245341D03*
X66099Y1248688D03*
X73541Y1265420D03*
Y1262074D03*
X87099Y770144D03*
X82241Y766798D03*
X87099Y783530D03*
Y776837D03*
X82241Y780184D03*
Y773491D03*
X87099Y800263D03*
Y793570D03*
X82241Y803609D03*
Y796916D03*
Y790223D03*
X87099Y820341D03*
Y813648D03*
Y806955D03*
X82241Y816995D03*
Y810302D03*
X87099Y830381D03*
X82241Y833727D03*
Y827034D03*
X87099Y850459D03*
Y843766D03*
Y837074D03*
X82241Y847113D03*
Y840420D03*
X87099Y867192D03*
Y857152D03*
X82241Y863845D03*
Y853806D03*
X87099Y880577D03*
Y873885D03*
X82241Y883924D03*
Y877231D03*
Y870538D03*
X87099Y893963D03*
Y887270D03*
X82241Y900656D03*
Y890617D03*
X87099Y917389D03*
Y910696D03*
Y904003D03*
X82241Y914042D03*
Y907349D03*
X87099Y930774D03*
Y924081D03*
X82241Y927428D03*
Y920735D03*
X87099Y947507D03*
Y940814D03*
X82241Y944160D03*
Y937467D03*
X87099Y964239D03*
Y954200D03*
X82241Y960892D03*
Y950853D03*
X87099Y977625D03*
Y970932D03*
X82241Y980971D03*
Y974278D03*
Y967585D03*
X87099Y991011D03*
Y984318D03*
X82241Y987664D03*
X87099Y1031168D03*
Y1024475D03*
Y1017782D03*
X82241Y1027822D03*
Y1017782D03*
X87099Y1044554D03*
Y1037861D03*
X82241Y1047900D03*
Y1041207D03*
Y1034515D03*
X87099Y1057940D03*
Y1051247D03*
X82241Y1061286D03*
Y1054593D03*
X87099Y1078018D03*
Y1071326D03*
Y1064633D03*
X82241Y1074672D03*
Y1067979D03*
X87099Y1094751D03*
Y1088058D03*
X82241Y1091404D03*
Y1084711D03*
X87099Y1108137D03*
Y1101444D03*
X82241Y1111483D03*
Y1104790D03*
Y1098097D03*
X87099Y1124869D03*
Y1114829D03*
X82241Y1128215D03*
Y1121522D03*
X87099Y1144948D03*
Y1138255D03*
Y1131562D03*
X82241Y1141601D03*
Y1134908D03*
X87099Y1161680D03*
Y1151641D03*
X82241Y1158333D03*
Y1148294D03*
X87099Y1175066D03*
Y1168373D03*
X82241Y1171719D03*
Y1165026D03*
X87099Y1188452D03*
Y1181759D03*
X82241Y1185105D03*
Y1178412D03*
X87099Y1205184D03*
Y1198491D03*
X82241Y1208530D03*
Y1201837D03*
Y1195144D03*
X87099Y1225263D03*
Y1218570D03*
Y1211877D03*
X82241Y1221916D03*
Y1215223D03*
X87099Y1241995D03*
Y1235302D03*
X82241Y1238648D03*
Y1231955D03*
X87099Y1248688D03*
X82241Y1245341D03*
X87099Y1265420D03*
X103241Y766798D03*
X95799Y770144D03*
X103241Y780184D03*
Y773491D03*
X95799Y783530D03*
Y776837D03*
X103241Y803609D03*
Y796916D03*
Y790223D03*
X95799Y800263D03*
Y793570D03*
X103241Y816995D03*
Y810302D03*
X95799Y820341D03*
Y813648D03*
Y806955D03*
X103241Y833727D03*
Y827034D03*
X95799Y830381D03*
X103241Y847113D03*
Y840420D03*
X95799Y850459D03*
Y843766D03*
Y837074D03*
X103241Y863845D03*
Y853806D03*
X95799Y867192D03*
Y857152D03*
X103241Y883924D03*
Y877231D03*
Y870538D03*
X95799Y880577D03*
Y873885D03*
X103241Y900656D03*
Y890617D03*
X95799Y893963D03*
Y887270D03*
X103241Y914042D03*
Y907349D03*
X95799Y917389D03*
Y910696D03*
Y904003D03*
X103241Y927428D03*
Y920735D03*
X95799Y930774D03*
Y924081D03*
X103241Y944160D03*
Y937467D03*
X95799Y947507D03*
Y940814D03*
X103241Y960892D03*
Y950853D03*
X95799Y964239D03*
Y954200D03*
X103241Y980971D03*
Y974278D03*
Y967585D03*
X95799Y977625D03*
Y970932D03*
X103241Y987664D03*
X95799Y991011D03*
Y984318D03*
X103241Y1027822D03*
Y1017782D03*
X95799Y1031168D03*
Y1024475D03*
Y1017782D03*
X103241Y1047900D03*
Y1041207D03*
Y1034515D03*
X95799Y1044554D03*
Y1037861D03*
X103241Y1061286D03*
Y1054593D03*
X95799Y1057940D03*
Y1051247D03*
X103241Y1074672D03*
Y1067979D03*
X95799Y1078018D03*
Y1071326D03*
Y1064633D03*
X103241Y1091404D03*
Y1084711D03*
X95799Y1094751D03*
Y1088058D03*
X103241Y1111483D03*
Y1104790D03*
Y1098097D03*
X95799Y1108137D03*
Y1101444D03*
X103241Y1128215D03*
Y1121522D03*
X95799Y1124869D03*
Y1114829D03*
X103241Y1141601D03*
Y1134908D03*
X95799Y1144948D03*
Y1138255D03*
Y1131562D03*
X103241Y1158333D03*
Y1148294D03*
X95799Y1161680D03*
Y1151641D03*
X103241Y1171719D03*
Y1165026D03*
X95799Y1175066D03*
Y1168373D03*
X103241Y1185105D03*
Y1178412D03*
X95799Y1188452D03*
Y1181759D03*
X103241Y1208530D03*
Y1201837D03*
Y1195144D03*
X95799Y1205184D03*
Y1198491D03*
X103241Y1221916D03*
Y1215223D03*
X95799Y1225263D03*
Y1218570D03*
Y1211877D03*
X103241Y1238648D03*
Y1231955D03*
X95799Y1241995D03*
Y1235302D03*
X103241Y1245341D03*
X95799Y1248688D03*
X103241Y1265420D03*
Y1262074D03*
X125499Y770144D03*
X116799D03*
X111941Y766798D03*
X125499Y783530D03*
X116799D03*
X125499Y776837D03*
X116799D03*
X111941Y780184D03*
Y773491D03*
X125499Y800263D03*
X116799D03*
X125499Y793570D03*
X116799D03*
X111941Y803609D03*
Y796916D03*
Y790223D03*
X125499Y820341D03*
X116799D03*
X125499Y813648D03*
X116799D03*
X125499Y806955D03*
X116799D03*
X111941Y816995D03*
Y810302D03*
X125499Y830381D03*
X116799D03*
X111941Y833727D03*
Y827034D03*
X125499Y850459D03*
X116799D03*
X125499Y843766D03*
X116799D03*
X125499Y837074D03*
X116799D03*
X111941Y847113D03*
Y840420D03*
X116799Y867192D03*
X125499Y857152D03*
X116799D03*
X111941Y863845D03*
Y853806D03*
X116799Y880577D03*
Y873885D03*
X111941Y883924D03*
Y877231D03*
Y870538D03*
X116799Y893963D03*
Y887270D03*
X111941Y900656D03*
Y890617D03*
X116799Y917389D03*
Y910696D03*
Y904003D03*
X111941Y914042D03*
Y907349D03*
X116799Y930774D03*
Y924081D03*
X111941Y927428D03*
Y920735D03*
X116799Y947507D03*
Y940814D03*
X111941Y944160D03*
Y937467D03*
X116799Y964239D03*
Y954200D03*
X111941Y960892D03*
Y950853D03*
X116799Y977625D03*
Y970932D03*
X111941Y980971D03*
Y974278D03*
Y967585D03*
X116799Y991011D03*
Y984318D03*
X111941Y987664D03*
X116799Y1031168D03*
Y1024475D03*
Y1017782D03*
X111941Y1027822D03*
Y1017782D03*
X116799Y1044554D03*
Y1037861D03*
X111941Y1047900D03*
Y1041207D03*
Y1034515D03*
X116799Y1057940D03*
Y1051247D03*
X111941Y1061286D03*
Y1054593D03*
X116799Y1078018D03*
Y1071326D03*
Y1064633D03*
X111941Y1074672D03*
Y1067979D03*
X116799Y1094751D03*
Y1088058D03*
X111941Y1091404D03*
Y1084711D03*
X116799Y1108137D03*
Y1101444D03*
X111941Y1111483D03*
Y1104790D03*
Y1098097D03*
X116799Y1124869D03*
Y1114829D03*
X111941Y1128215D03*
Y1121522D03*
X116799Y1144948D03*
Y1138255D03*
Y1131562D03*
X111941Y1141601D03*
Y1134908D03*
X116799Y1161680D03*
Y1151641D03*
X111941Y1158333D03*
Y1148294D03*
X116799Y1175066D03*
Y1168373D03*
X111941Y1171719D03*
Y1165026D03*
X116799Y1188452D03*
Y1181759D03*
X111941Y1185105D03*
Y1178412D03*
X116799Y1205184D03*
Y1198491D03*
X111941Y1208530D03*
Y1201837D03*
Y1195144D03*
X116799Y1225263D03*
Y1218570D03*
Y1211877D03*
X111941Y1221916D03*
Y1215223D03*
X116799Y1241995D03*
Y1235302D03*
X111941Y1238648D03*
Y1231955D03*
X116799Y1248688D03*
X111941Y1245341D03*
X116799Y1265420D03*
X141641Y766798D03*
X132941D03*
X141641Y773491D03*
X132941D03*
X141641Y780184D03*
X132941D03*
X141641Y803609D03*
X132941D03*
X141641Y790223D03*
X132941D03*
X141641Y796916D03*
X132941D03*
X141641Y816995D03*
X132941D03*
X141641Y810302D03*
X132941D03*
X141641Y833727D03*
X132941D03*
X141641Y827034D03*
X132941D03*
X141641Y840420D03*
X132941D03*
X141641Y847113D03*
X132941D03*
X141641Y853806D03*
X132941D03*
Y1265420D03*
X146499Y770144D03*
X155199D03*
X146499Y783530D03*
X155199D03*
X146499Y776837D03*
X155199D03*
X146499Y800263D03*
X155199D03*
X146499Y793570D03*
X155199D03*
X146499Y820341D03*
X155199D03*
X146499Y813648D03*
X155199D03*
X146499Y806955D03*
X155199D03*
X146499Y830381D03*
X155199D03*
X146499Y850459D03*
X155199D03*
X146499Y843766D03*
X155199D03*
X146499Y837074D03*
X155199D03*
X146499Y857152D03*
X155199D03*
X176199Y770144D03*
X162641Y766798D03*
X171341D03*
X176199Y783530D03*
Y776837D03*
X162641Y780184D03*
X171341D03*
Y773491D03*
X162641D03*
X176199Y800263D03*
X162641Y803609D03*
X171341D03*
X176199Y793570D03*
X162641Y796916D03*
X171341D03*
X162641Y790223D03*
X171341D03*
X176199Y820341D03*
X162641Y816995D03*
X171341D03*
X176199Y813648D03*
Y806955D03*
X162641Y810302D03*
X171341D03*
X162641Y833727D03*
X171341D03*
X176199Y830381D03*
X162641Y827034D03*
X171341D03*
X176199Y850459D03*
Y843766D03*
Y837074D03*
X162641Y847113D03*
X171341D03*
X162641Y840420D03*
X171341D03*
X176199Y857152D03*
X162641Y853806D03*
X171341D03*
X192341Y766798D03*
X184899Y770144D03*
X192341Y780184D03*
Y773491D03*
X184899Y783530D03*
Y776837D03*
X192341Y803609D03*
Y796916D03*
Y790223D03*
X184899Y800263D03*
Y793570D03*
X192341Y816995D03*
Y810302D03*
X184899Y820341D03*
Y813648D03*
Y806955D03*
X192341Y833727D03*
X191491Y827034D03*
X184899Y830381D03*
X192341Y847113D03*
Y840420D03*
X184899Y850459D03*
Y843766D03*
Y837074D03*
X192341Y853806D03*
X184899Y857152D03*
X205899Y770144D03*
X201041Y766798D03*
X205899Y783530D03*
Y776837D03*
X201041Y780184D03*
Y773491D03*
X205899Y800263D03*
Y793570D03*
X201041Y803609D03*
Y796916D03*
Y790223D03*
X205899Y813648D03*
Y806955D03*
X205049Y820341D03*
X201041Y816995D03*
Y810302D03*
X205049Y830381D03*
X201041Y833727D03*
Y827034D03*
X205899Y850459D03*
Y837074D03*
Y843766D03*
X201041Y847113D03*
Y840420D03*
X205049Y857152D03*
X201041Y853806D03*
X222041Y766798D03*
X214599Y770144D03*
X222041Y780184D03*
Y773491D03*
X214599Y783530D03*
Y776837D03*
X222041Y803609D03*
Y796916D03*
Y790223D03*
X214599Y800263D03*
Y793570D03*
X222041Y810302D03*
X221191Y816995D03*
X214599Y813648D03*
Y806955D03*
X215449Y820341D03*
X222041Y833727D03*
X221191Y827034D03*
X215449Y830381D03*
X222041Y847113D03*
Y840420D03*
X214599Y850459D03*
Y837074D03*
Y843766D03*
X222041Y853806D03*
X215449Y857152D03*
X235599Y770144D03*
X230741Y766798D03*
X235599Y783530D03*
Y776837D03*
X230741Y780184D03*
Y773491D03*
X235599Y800263D03*
Y793570D03*
X230741Y803609D03*
Y796916D03*
Y790223D03*
X234749Y820341D03*
Y813648D03*
X235599Y806955D03*
X230741Y810302D03*
X231006Y817554D03*
X235599Y830381D03*
X230741Y833727D03*
X231591Y827034D03*
X235599Y850459D03*
Y837074D03*
Y843766D03*
X230741Y847113D03*
Y840420D03*
X234749Y857152D03*
X230741Y853806D03*
X236391Y1002557D03*
X240521Y1000395D03*
X237841Y1000437D03*
X233891Y1002557D03*
X231391D03*
X228891D03*
X254881Y999650D03*
X257561Y999608D03*
X348879Y873810D03*
X393278Y848176D03*
X415185Y956620D03*
X411685D03*
X409385D03*
X417685D03*
X412365Y985610D03*
X410065D03*
X420145Y985550D03*
X409385Y1014540D03*
X407085D03*
X411685D03*
X420405Y1014470D03*
X414461Y1028855D03*
X411961D03*
X416961D03*
X419461D03*
X432130Y941101D03*
X435830D03*
Y947510D03*
X422685Y956620D03*
X425185D03*
X422685Y985580D03*
X423015Y1014470D03*
X421961Y1028855D03*
X437680Y944305D03*
X441380D03*
X443230Y941101D03*
X445079Y944305D03*
X439530Y941101D03*
X439529Y947510D03*
X467278Y899445D03*
X453585Y942238D03*
Y939938D03*
Y944538D03*
X453403Y956999D03*
X461424Y956620D03*
X458404D03*
X453403Y959299D03*
X468904Y956620D03*
Y971100D03*
X458404D03*
X461424Y971140D03*
X453403Y973099D03*
Y970799D03*
Y986899D03*
X461424Y985580D03*
X458404D03*
X453403Y984599D03*
X468904Y985580D03*
X453403Y998399D03*
Y1012199D03*
X458404Y1000080D03*
X461424D03*
X453403Y1000699D03*
X468904Y1000080D03*
X458404Y1014540D03*
X461295Y1014510D03*
X453403Y1014499D03*
X465680Y1028855D03*
X463180D03*
X460680D03*
X458180D03*
X471404Y956620D03*
Y971100D03*
X473904D03*
X471404Y985580D03*
Y1000080D03*
X629599Y770144D03*
X620899D03*
X629599Y783530D03*
X620899D03*
X629599Y776837D03*
X620899D03*
X620846Y800263D03*
X629599D03*
Y793570D03*
X620899D03*
Y820341D03*
X629599D03*
X620076Y813648D03*
X630593D03*
X619632Y806955D03*
X630792D03*
X620899Y830381D03*
X629599D03*
X620899Y843766D03*
X629599D03*
Y837074D03*
X620899D03*
X623347Y999665D03*
X625780Y1000198D03*
X637041Y766798D03*
X645741D03*
Y773491D03*
X637041D03*
X645741Y780184D03*
X637041D03*
Y803609D03*
X645741D03*
X637041Y796916D03*
X645741D03*
Y790223D03*
X637041D03*
X636221Y810302D03*
X646844D03*
X646774Y816995D03*
X637041D03*
X645741Y833727D03*
X637041D03*
Y827034D03*
X645741D03*
X637041Y840420D03*
X645741D03*
X644347Y1003135D03*
X640327D03*
X640467Y1000735D03*
X647447Y1002865D03*
X647397Y1000135D03*
X650599Y770144D03*
X659299D03*
X650599Y783530D03*
X659299D03*
X650599Y776837D03*
X659299D03*
Y800263D03*
X650599D03*
Y793570D03*
X659299D03*
Y806955D03*
X650599D03*
X660432Y813648D03*
X650599D03*
X660199Y820341D03*
X650599D03*
X659299Y830381D03*
X650599D03*
X659299Y843766D03*
X650599D03*
Y837074D03*
X659299D03*
X650107Y1002825D03*
X680299Y770144D03*
X675441Y766798D03*
X666741D03*
X680299Y783530D03*
Y776837D03*
X666741Y773491D03*
X675441D03*
X666741Y780184D03*
X675441D03*
Y803609D03*
X666741D03*
X680299Y800263D03*
Y793570D03*
X666741Y796916D03*
X675441D03*
X666741Y790223D03*
X675441D03*
X676403Y816995D03*
X665803D03*
X675441Y810302D03*
X666741D03*
X680299Y820341D03*
Y813648D03*
Y806955D03*
X675441Y833727D03*
X666741D03*
X676625Y827034D03*
X665876D03*
X680299Y830381D03*
Y843766D03*
Y837074D03*
X666741Y840420D03*
X675441D03*
X696441Y766798D03*
X688999Y770144D03*
X696441Y773491D03*
Y780184D03*
X688999Y783530D03*
Y776837D03*
X696441Y803609D03*
Y796916D03*
Y790223D03*
X688999Y800263D03*
Y793570D03*
X696441Y816995D03*
Y810302D03*
X689888Y820341D03*
X688999Y813648D03*
Y806955D03*
X696441Y833727D03*
Y827034D03*
X688999Y830381D03*
X696441Y840420D03*
X688999Y843766D03*
Y837074D03*
X709999Y770144D03*
X705141Y766798D03*
X709999Y783530D03*
Y776837D03*
X705141Y773491D03*
Y780184D03*
X709999Y800263D03*
Y793570D03*
X705141Y803609D03*
Y796916D03*
Y790223D03*
X709999Y820341D03*
Y813648D03*
Y806955D03*
X705141Y816995D03*
Y810302D03*
X709999Y830381D03*
X705141Y833727D03*
Y827034D03*
X709999Y843766D03*
Y837074D03*
X705141Y840420D03*
X726141Y766798D03*
X718699Y770144D03*
X726141Y773491D03*
Y780184D03*
X718699Y783530D03*
Y776837D03*
X726141Y803609D03*
Y796916D03*
Y790223D03*
X718699Y800263D03*
Y793570D03*
X726141Y816995D03*
Y810302D03*
X718699Y820341D03*
Y813648D03*
Y806955D03*
X726141Y833727D03*
Y827034D03*
X718699Y830381D03*
X726141Y847113D03*
Y840420D03*
X718699Y850459D03*
Y843766D03*
Y837074D03*
X726141Y863845D03*
Y853806D03*
X718699Y867192D03*
Y857152D03*
X726141Y883924D03*
Y877231D03*
Y870538D03*
X718699Y880577D03*
Y873885D03*
X726141Y900656D03*
Y890617D03*
X718699Y893963D03*
Y887270D03*
X726141Y914042D03*
Y907349D03*
X718699Y917389D03*
Y910696D03*
Y904003D03*
X726141Y927428D03*
Y920735D03*
X718699Y930774D03*
Y924081D03*
X726141Y944160D03*
Y937467D03*
X718699Y947507D03*
Y940814D03*
X726141Y960892D03*
Y950853D03*
X718699Y964239D03*
Y954200D03*
X726141Y980971D03*
Y974278D03*
Y967585D03*
X718699Y977625D03*
Y970932D03*
X726141Y987664D03*
X718699Y991011D03*
Y984318D03*
X726141Y1027822D03*
Y1017782D03*
X718699Y1031168D03*
Y1024475D03*
Y1017782D03*
X726141Y1047900D03*
Y1041207D03*
Y1034515D03*
X718699Y1044554D03*
Y1037861D03*
X726141Y1061286D03*
Y1054593D03*
X718699Y1057940D03*
Y1051247D03*
X726141Y1074672D03*
Y1067979D03*
X718699Y1078018D03*
Y1071326D03*
Y1064633D03*
X726141Y1091404D03*
Y1084711D03*
X718699Y1094751D03*
Y1088058D03*
X726141Y1111483D03*
Y1104790D03*
Y1098097D03*
X718699Y1108137D03*
Y1101444D03*
X726141Y1128215D03*
Y1121522D03*
X718699Y1124869D03*
Y1114829D03*
X726141Y1141601D03*
Y1134908D03*
X718699Y1144948D03*
Y1138255D03*
Y1131562D03*
X726141Y1158333D03*
Y1148294D03*
X718699Y1161680D03*
Y1151641D03*
X726141Y1171719D03*
Y1165026D03*
X718699Y1175066D03*
Y1168373D03*
X726141Y1185105D03*
Y1178412D03*
X718699Y1188452D03*
Y1181759D03*
X726141Y1208530D03*
Y1201837D03*
Y1195144D03*
X718699Y1205184D03*
Y1198491D03*
X726141Y1221916D03*
Y1215223D03*
X718699Y1225263D03*
Y1218570D03*
Y1211877D03*
X726141Y1238648D03*
Y1231955D03*
X718699Y1241995D03*
Y1235302D03*
X726141Y1245341D03*
X719046Y1257064D03*
X718699Y1248688D03*
X726141Y1262074D03*
X726107Y1265420D03*
X739699Y770144D03*
X734841Y766798D03*
X739699Y783530D03*
Y776837D03*
X734841Y773491D03*
Y780184D03*
X739699Y800263D03*
Y793570D03*
X734841Y803609D03*
Y796916D03*
Y790223D03*
X739699Y820341D03*
Y813648D03*
Y806955D03*
X734841Y816995D03*
Y810302D03*
X739699Y830381D03*
X734841Y833727D03*
Y827034D03*
X739699Y850459D03*
Y843766D03*
Y837074D03*
X734841Y847113D03*
Y840420D03*
X739699Y867192D03*
Y857152D03*
X734841Y863845D03*
Y853806D03*
X739699Y880577D03*
Y873885D03*
X734841Y883924D03*
Y877231D03*
Y870538D03*
X739699Y893963D03*
Y887270D03*
X734841Y900656D03*
Y890617D03*
X739699Y917389D03*
Y910696D03*
Y904003D03*
X734841Y914042D03*
Y907349D03*
X739699Y930774D03*
Y924081D03*
X734841Y927428D03*
Y920735D03*
X739699Y947507D03*
Y940814D03*
X734841Y944160D03*
Y937467D03*
X739699Y964239D03*
Y954200D03*
X734841Y960892D03*
Y950853D03*
X739699Y977625D03*
Y970932D03*
X734841Y980971D03*
Y974278D03*
Y967585D03*
X739699Y991011D03*
Y984318D03*
X734841Y987664D03*
X739699Y1031168D03*
Y1024475D03*
Y1017782D03*
X734841Y1027822D03*
Y1017782D03*
X739699Y1044554D03*
Y1037861D03*
X734841Y1047900D03*
Y1041207D03*
Y1034515D03*
X739699Y1057940D03*
Y1051247D03*
X734841Y1061286D03*
Y1054593D03*
X739699Y1078018D03*
Y1071326D03*
Y1064633D03*
X734841Y1074672D03*
Y1067979D03*
X739699Y1094751D03*
Y1088058D03*
X734841Y1091404D03*
Y1084711D03*
X739699Y1108137D03*
Y1101444D03*
X734841Y1111483D03*
Y1104790D03*
Y1098097D03*
X739699Y1124869D03*
Y1114829D03*
X734841Y1128215D03*
Y1121522D03*
X739699Y1144948D03*
Y1138255D03*
Y1131562D03*
X734841Y1141601D03*
Y1134908D03*
X739699Y1161680D03*
Y1151641D03*
X734841Y1158333D03*
Y1148294D03*
X739699Y1175066D03*
Y1168373D03*
X734841Y1171719D03*
Y1165026D03*
X739699Y1188452D03*
Y1181759D03*
X734841Y1185105D03*
Y1178412D03*
X739699Y1205184D03*
Y1198491D03*
X734841Y1208530D03*
Y1201837D03*
Y1195144D03*
X739699Y1225263D03*
Y1218570D03*
Y1211877D03*
X734841Y1221916D03*
Y1215223D03*
X739699Y1241995D03*
Y1235302D03*
X734841Y1238648D03*
Y1231955D03*
X739699Y1248688D03*
X734841Y1245341D03*
X739697Y1265420D03*
X755841Y766798D03*
X748399Y770144D03*
X755841Y780184D03*
Y773491D03*
X748399Y783530D03*
Y776837D03*
X755841Y803609D03*
Y796916D03*
Y790223D03*
X748399Y800263D03*
Y793570D03*
X755841Y816995D03*
Y810302D03*
X748399Y820341D03*
Y813648D03*
Y806955D03*
X755841Y833727D03*
Y827034D03*
X748399Y830381D03*
X755841Y847113D03*
Y840420D03*
X748399Y850459D03*
Y843766D03*
Y837074D03*
X755841Y863845D03*
Y853806D03*
X748399Y867192D03*
Y857152D03*
X755841Y883924D03*
Y877231D03*
Y870538D03*
X748399Y880577D03*
Y873885D03*
X755841Y900656D03*
Y890617D03*
X748399Y893963D03*
Y887270D03*
X755841Y914042D03*
Y907349D03*
X748399Y917389D03*
Y910696D03*
Y904003D03*
X755841Y927428D03*
Y920735D03*
X748399Y930774D03*
Y924081D03*
X755841Y944160D03*
Y937467D03*
X748399Y947507D03*
Y940814D03*
X755841Y960892D03*
Y950853D03*
X748399Y964239D03*
Y954200D03*
X755841Y980971D03*
Y974278D03*
Y967585D03*
X748399Y977625D03*
Y970932D03*
X755841Y987664D03*
X748399Y991011D03*
Y984318D03*
X755841Y1027822D03*
Y1017782D03*
X748399Y1031168D03*
Y1024475D03*
Y1017782D03*
X755841Y1047900D03*
Y1041207D03*
Y1034515D03*
X748399Y1044554D03*
Y1037861D03*
X755841Y1054593D03*
Y1061286D03*
X748399Y1057940D03*
X755841Y1067979D03*
Y1074672D03*
X748399Y1078018D03*
Y1071326D03*
Y1064633D03*
X755841Y1084711D03*
Y1091404D03*
X748399Y1094751D03*
Y1088058D03*
X755841Y1111483D03*
Y1104790D03*
Y1098097D03*
X748399Y1108137D03*
Y1101444D03*
X755841Y1128215D03*
Y1121522D03*
X748399Y1124869D03*
Y1114829D03*
X755841Y1141601D03*
Y1134908D03*
X748399Y1144948D03*
Y1138255D03*
Y1131562D03*
X755841Y1158333D03*
Y1148294D03*
X748399Y1161680D03*
Y1151641D03*
X755841Y1171719D03*
Y1165026D03*
X748399Y1175066D03*
Y1168373D03*
X755841Y1185105D03*
Y1178412D03*
X748399Y1188452D03*
Y1181759D03*
X755841Y1208530D03*
Y1201837D03*
Y1195144D03*
X748399Y1205184D03*
Y1198491D03*
X755841Y1221916D03*
Y1215223D03*
X748399Y1225263D03*
Y1218570D03*
Y1211877D03*
X755841Y1238648D03*
Y1231955D03*
X748399Y1241995D03*
Y1235302D03*
X755841Y1245341D03*
X748283Y1256964D03*
X748399Y1248688D03*
X755841Y1262074D03*
X755797Y1265420D03*
X769399Y770144D03*
X778099D03*
X764541Y766798D03*
X769399Y783530D03*
X778099D03*
X769399Y776837D03*
X778099D03*
X764541Y780184D03*
Y773491D03*
X769399Y800263D03*
X778099D03*
X769399Y793570D03*
X778099D03*
X764541Y803609D03*
Y796916D03*
Y790223D03*
X769399Y820341D03*
X778099D03*
X769399Y813648D03*
X778099D03*
X769399Y806955D03*
X778099D03*
X764541Y816995D03*
Y810302D03*
X769399Y830381D03*
X778099D03*
X764541Y833727D03*
Y827034D03*
X769399Y850459D03*
X778099D03*
Y843766D03*
X769399D03*
Y837074D03*
X778099D03*
X764541Y847113D03*
Y840420D03*
X778099Y867192D03*
X769399D03*
Y857152D03*
X778099D03*
X764541Y863845D03*
Y853806D03*
X769399Y880577D03*
X778099D03*
X769399Y873885D03*
X778099D03*
X764541Y883924D03*
Y877231D03*
Y870538D03*
X778099Y893963D03*
X769399D03*
Y887270D03*
X778099D03*
X764541Y900656D03*
Y890617D03*
X769399Y917389D03*
X778099D03*
X769399Y910696D03*
X778099D03*
X769399Y904003D03*
X778099D03*
X764541Y914042D03*
Y907349D03*
X769399Y930774D03*
X778099D03*
X769399Y924081D03*
X778099D03*
X764541Y927428D03*
Y920735D03*
X769399Y947507D03*
X778099D03*
X769399Y940814D03*
X778099D03*
X764541Y944160D03*
Y937467D03*
X769399Y964239D03*
X778099D03*
X769399Y954200D03*
X778099D03*
X764541Y960892D03*
Y950853D03*
X769399Y977625D03*
X778099D03*
X769399Y970932D03*
X778099D03*
X764541Y980971D03*
Y974278D03*
Y967585D03*
X769399Y991011D03*
X778099D03*
X769399Y984318D03*
X778099D03*
X764541Y987664D03*
X769399Y1031168D03*
X778099D03*
X769399Y1024475D03*
X778099D03*
X769399Y1017782D03*
X778099D03*
X764541Y1027822D03*
Y1017782D03*
X778099Y1044554D03*
X769399D03*
Y1037861D03*
X778099D03*
X764541Y1047900D03*
Y1041207D03*
Y1034515D03*
X769399Y1057940D03*
X778099D03*
X769399Y1051247D03*
X778099D03*
X764541Y1054593D03*
Y1061286D03*
X778099Y1078018D03*
X769399D03*
X778099Y1071326D03*
X769399D03*
Y1064633D03*
X778099D03*
X764541Y1067979D03*
Y1074672D03*
X778099Y1094751D03*
X769399D03*
X778099Y1088058D03*
X769399D03*
X764541Y1084711D03*
Y1091404D03*
X778099Y1108137D03*
X769399D03*
X778099Y1101444D03*
X769399D03*
X764541Y1111483D03*
Y1104790D03*
Y1098097D03*
X778099Y1124869D03*
X769399D03*
X778099Y1114829D03*
X769399D03*
X764541Y1128215D03*
Y1121522D03*
X778099Y1144948D03*
X769399D03*
X778099Y1138255D03*
X769399D03*
X778099Y1131562D03*
X769399D03*
X764541Y1141601D03*
Y1134908D03*
X778099Y1161680D03*
X769399D03*
X778099Y1151641D03*
X769399D03*
X764541Y1158333D03*
Y1148294D03*
X778099Y1175066D03*
X769399D03*
X778099Y1168373D03*
X769399D03*
X764541Y1171719D03*
Y1165026D03*
X778099Y1188452D03*
X769399D03*
X778099Y1181759D03*
X769399D03*
X764541Y1185105D03*
Y1178412D03*
X769399Y1205184D03*
X778099D03*
Y1198491D03*
X769399D03*
X764541Y1208530D03*
Y1201837D03*
Y1195144D03*
X778099Y1225263D03*
X769399D03*
X778099Y1218570D03*
X769399D03*
Y1211877D03*
X778099D03*
X764541Y1221916D03*
Y1215223D03*
X778099Y1241995D03*
X769399D03*
X778099Y1235302D03*
X769399D03*
X764541Y1238648D03*
Y1231955D03*
X778346Y1257264D03*
X778099Y1248688D03*
X769399D03*
X764541Y1245341D03*
X769399Y1265420D03*
X785541Y766798D03*
X794241D03*
X785541Y773491D03*
X794241D03*
X785541Y780184D03*
X794241D03*
X785541Y803609D03*
X794241D03*
X785541Y790223D03*
X794241D03*
X785541Y796916D03*
X794241D03*
X785541Y816995D03*
X794241D03*
X785541Y810302D03*
X794241D03*
X785541Y833727D03*
X794241D03*
X785541Y827034D03*
X794241D03*
X785541Y840420D03*
X794241D03*
X785541Y847113D03*
X794241D03*
X785541Y853806D03*
X794241D03*
X785541Y863845D03*
X794241D03*
X785541Y883924D03*
X794241D03*
X785541Y870538D03*
X794241D03*
X785541Y877231D03*
X794241D03*
X785541Y900656D03*
X794241D03*
X785541Y890617D03*
X794241D03*
X785541Y907349D03*
X794241D03*
X785541Y914042D03*
X794241D03*
X785541Y920735D03*
X794241D03*
X785541Y927428D03*
X794241D03*
X785541Y937467D03*
X794241D03*
X785541Y944160D03*
X794241D03*
X785541Y960892D03*
X794241D03*
X785541Y950853D03*
X794241D03*
X785541Y980971D03*
X794241D03*
X785541Y974278D03*
X794241D03*
X785541Y967585D03*
X794241D03*
X785541Y987664D03*
X794241D03*
X785541Y1027822D03*
X794241D03*
X785541Y1017782D03*
X794241D03*
X785541Y1047900D03*
X794241D03*
X785541Y1041207D03*
X794241D03*
X785541Y1034515D03*
X794241D03*
X785541Y1054593D03*
X794241D03*
X785541Y1061286D03*
X794241D03*
X785541Y1074672D03*
X794241D03*
X785541Y1067979D03*
X794241D03*
X785541Y1091404D03*
X794241D03*
X785541Y1084711D03*
X794241D03*
X785541Y1111483D03*
X794241D03*
X785541Y1104790D03*
X794241D03*
X785541Y1098097D03*
X794241D03*
X785541Y1128215D03*
X794241D03*
X785541Y1121522D03*
X794241D03*
X785541Y1141601D03*
X794241D03*
X785541Y1134908D03*
X794241D03*
X785541Y1158333D03*
X794241D03*
X785541Y1148294D03*
X794241D03*
X785541Y1171719D03*
X794241D03*
X785541Y1165026D03*
X794241D03*
X785541Y1178412D03*
X794241D03*
X785541Y1185105D03*
X794241D03*
X785541Y1208530D03*
X794241D03*
X785541Y1195144D03*
X794241D03*
X785541Y1201837D03*
X794241D03*
X785541Y1221916D03*
X794241D03*
X785541Y1215223D03*
X794241D03*
X785541Y1238648D03*
X794241D03*
X785541Y1231955D03*
X794241D03*
X785541Y1245341D03*
X794241D03*
X785541Y1265420D03*
Y1262074D03*
X799099Y770144D03*
X807799D03*
X799099Y783530D03*
X807799D03*
X799099Y776837D03*
X807799D03*
X799099Y800263D03*
X807799D03*
X799099Y793570D03*
X807799D03*
X799099Y820341D03*
X807799D03*
X799099Y806955D03*
X807799D03*
X799099Y813648D03*
X807799D03*
X799099Y830381D03*
X807799D03*
X799099Y850459D03*
X807799D03*
X799099Y837074D03*
X807799D03*
X799099Y843766D03*
X807799D03*
X799099Y867192D03*
X807799D03*
X799099Y857152D03*
X807799D03*
X799099Y873885D03*
X807799D03*
X799099Y880577D03*
X807799D03*
X799099Y887270D03*
X807799D03*
X799099Y893963D03*
X807799D03*
X799099Y917389D03*
X807799D03*
X799099Y904003D03*
X807799D03*
X799099Y910696D03*
X807799D03*
X799099Y930774D03*
X807799D03*
X799099Y924081D03*
X807799D03*
X799099Y947507D03*
X807799D03*
X799099Y940814D03*
X807799D03*
X799099Y964239D03*
X807799D03*
X799099Y954200D03*
X807799D03*
X799099Y970932D03*
X807799D03*
X799099Y977625D03*
X807799D03*
X799099Y991011D03*
X807799D03*
X799099Y984318D03*
X807799D03*
X799099Y1031168D03*
X807799D03*
X799099Y1024475D03*
X807799D03*
X799099Y1017782D03*
X807799D03*
X799099Y1037861D03*
X807799D03*
X799099Y1044554D03*
X807799D03*
X799099Y1057940D03*
X807799D03*
X799099Y1051247D03*
X807799D03*
X799099Y1078018D03*
X807799D03*
X799099Y1071326D03*
X807799D03*
X799099Y1064633D03*
X807799D03*
X799099Y1094751D03*
X807799D03*
X799099Y1088058D03*
X807799D03*
X799099Y1108137D03*
X807799D03*
X799099Y1101444D03*
X807799D03*
X799099Y1124869D03*
X807799D03*
X799099Y1114829D03*
X807799D03*
X799099Y1144948D03*
X807799D03*
X799099Y1138255D03*
X807799D03*
X799099Y1131562D03*
X807799D03*
X799099Y1161680D03*
X807799D03*
X799099Y1151641D03*
X807799D03*
X799099Y1175066D03*
X807799D03*
X799099Y1168373D03*
X807799D03*
X799099Y1188452D03*
X807799D03*
X799099Y1181759D03*
X807799D03*
X799099Y1205184D03*
X807799D03*
X799099Y1198491D03*
X807799D03*
X799099Y1225263D03*
X807799D03*
X799099Y1211877D03*
X807799D03*
X799099Y1218570D03*
X807799D03*
X799099Y1241995D03*
X807799D03*
X799099Y1235302D03*
X807799D03*
X799099Y1248688D03*
X807799D03*
X808046Y1257664D03*
X799099Y1265420D03*
X815241Y766798D03*
X823941D03*
X815241Y773491D03*
X823941D03*
X815241Y780184D03*
X823941D03*
X815241Y803609D03*
X823941D03*
X815241Y790223D03*
X823941D03*
X815241Y796916D03*
X823941D03*
X815241Y816995D03*
X823941D03*
X815241Y810302D03*
X823941D03*
X815241Y833727D03*
X823941D03*
X815241Y827034D03*
X823941D03*
X815241Y840420D03*
X823941D03*
X815241Y847113D03*
X823941D03*
X815241Y853806D03*
X823941D03*
X815241Y863845D03*
X823941D03*
X815241Y883924D03*
X823941D03*
X815241Y870538D03*
X823941D03*
X815241Y877231D03*
X823941D03*
X815241Y900656D03*
X823941D03*
X815241Y890617D03*
X823941D03*
X815241Y907349D03*
X823941D03*
X815241Y914042D03*
X823941D03*
X815241Y920735D03*
X823941D03*
X815241Y927428D03*
X823941D03*
X815241Y937467D03*
X823941D03*
X815241Y944160D03*
X823941D03*
X815241Y960892D03*
X823941D03*
X815241Y950853D03*
X823941D03*
X815241Y980971D03*
X823941D03*
X815241Y974278D03*
X823941D03*
X815241Y967585D03*
X823941D03*
X815241Y987664D03*
X823941D03*
X815241Y1027822D03*
X823941D03*
X815241Y1017782D03*
X823941D03*
X815241Y1047900D03*
X823941D03*
X815241Y1041207D03*
X823941D03*
X815241Y1034515D03*
X823941D03*
X815241Y1054593D03*
X823941D03*
X815241Y1061286D03*
X823941D03*
X815241Y1074672D03*
X823941D03*
X815241Y1067979D03*
X823941D03*
X815241Y1091404D03*
X823941D03*
X815241Y1084711D03*
X823941D03*
X815241Y1111483D03*
X823941D03*
X815241Y1104790D03*
X823941D03*
X815241Y1098097D03*
X823941D03*
X815241Y1128215D03*
X823941D03*
X815241Y1121522D03*
X823941D03*
X815241Y1141601D03*
X823941D03*
X815241Y1134908D03*
X823941D03*
X815241Y1158333D03*
X823941D03*
X815241Y1148294D03*
X823941D03*
X815241Y1171719D03*
X823941D03*
X815241Y1165026D03*
X823941D03*
X815241Y1178412D03*
X823941D03*
X815241Y1185105D03*
X823941D03*
X815241Y1208530D03*
X823941D03*
X815241Y1195144D03*
X823941D03*
X815241Y1201837D03*
X823941D03*
X815241Y1221916D03*
X823941D03*
X815241Y1215223D03*
X823941D03*
X815241Y1238648D03*
X823941D03*
X815241Y1231955D03*
X823941D03*
X815241Y1245341D03*
X823941D03*
X815241Y1265420D03*
Y1262074D03*
X828799Y770144D03*
X837499D03*
X828799Y783530D03*
X837499D03*
X828799Y776837D03*
X837499D03*
Y800263D03*
X828799D03*
X837499Y793570D03*
X828799D03*
Y820341D03*
X837499D03*
X828799Y813648D03*
X837499D03*
X828799Y806955D03*
X837499D03*
X828799Y830381D03*
X837499D03*
X828799Y850459D03*
X837499D03*
X828799Y843766D03*
X837499D03*
X828799Y837074D03*
X837499D03*
X828799Y867192D03*
X837499D03*
X828799Y857152D03*
X837499D03*
X828799Y880577D03*
X837499D03*
X828799Y873885D03*
X837499D03*
X828799Y893963D03*
X837499D03*
X828799Y887270D03*
X837499D03*
X828799Y917389D03*
X837499D03*
Y904003D03*
X828799D03*
X837499Y910696D03*
X828799D03*
Y930774D03*
X837499D03*
X828799Y924081D03*
X837499D03*
X828799Y947507D03*
X837499D03*
X828799Y940814D03*
X837499D03*
X828799Y964239D03*
X837499D03*
X828799Y954200D03*
X837499D03*
X828799Y977625D03*
X837499D03*
X828799Y970932D03*
X837499D03*
X828799Y991011D03*
X837499D03*
X828799Y984318D03*
X837499D03*
X828799Y1031168D03*
X837499D03*
X828799Y1024475D03*
X837499D03*
X828799Y1017782D03*
X837499D03*
X828799Y1044554D03*
X837499D03*
X828799Y1037861D03*
X837499D03*
X828799Y1057940D03*
X837499D03*
X828799Y1051247D03*
X837499D03*
X828799Y1078018D03*
X837499D03*
X828799Y1071326D03*
X837499D03*
X828799Y1064633D03*
X837499D03*
X828799Y1094751D03*
X837499D03*
Y1088058D03*
X828799D03*
X837499Y1108137D03*
X828799D03*
Y1101444D03*
X837499D03*
Y1124869D03*
X828799D03*
X837499Y1114829D03*
X828799D03*
X837499Y1144948D03*
X828799D03*
X837499Y1138255D03*
X828799D03*
X837499Y1131562D03*
X828799D03*
X837499Y1161680D03*
X828799D03*
X837499Y1151641D03*
X828799D03*
X837499Y1175066D03*
X828799D03*
X837499Y1168373D03*
X828799D03*
Y1188452D03*
X837499D03*
Y1181759D03*
X828799D03*
X837499Y1205184D03*
X828799D03*
X837499Y1198491D03*
X828799D03*
X837499Y1225263D03*
X828799D03*
X837499Y1218570D03*
X828799D03*
X837499Y1211877D03*
X828799D03*
X837499Y1241995D03*
X828799D03*
X837499Y1235302D03*
X828799D03*
X837499Y1248688D03*
X828799D03*
X837846Y1256964D03*
X828799Y1265420D03*
X844941Y766798D03*
X853641D03*
X844941Y780184D03*
X853641D03*
X844941Y773491D03*
X853641D03*
X844941Y803609D03*
X853641D03*
X844941Y796916D03*
X853641D03*
X844941Y790223D03*
X853641D03*
X844941Y816995D03*
X853641D03*
X844941Y810302D03*
X853641D03*
X844941Y833727D03*
X853641D03*
X844941Y827034D03*
X853641D03*
X844941Y847113D03*
X853641D03*
X844941Y840420D03*
X853641D03*
X844941Y863845D03*
X853641D03*
X844941Y853806D03*
X853641D03*
X844941Y883924D03*
X853641D03*
X844941Y877231D03*
X853641D03*
X844941Y870538D03*
X853641D03*
X844941Y900656D03*
X853641D03*
X844941Y890617D03*
X853641D03*
X844941Y914042D03*
X853641D03*
X844941Y907349D03*
X853641D03*
X844941Y927428D03*
X853641D03*
X844941Y920735D03*
X853641D03*
X844941Y944160D03*
X853641D03*
X844941Y937467D03*
X853641D03*
X844941Y960892D03*
X853641D03*
X844941Y950853D03*
X853641D03*
X844941Y980971D03*
X853641D03*
X844941Y974278D03*
X853641D03*
X844941Y967585D03*
X853641D03*
X844941Y987664D03*
X853641D03*
X844941Y1027822D03*
X853641D03*
X844941Y1017782D03*
X853641D03*
X844941Y1047900D03*
X853641D03*
X844941Y1041207D03*
X853641D03*
X844941Y1034515D03*
X853641D03*
X844941Y1061286D03*
X853641D03*
X844941Y1054593D03*
X853641D03*
X844941Y1074672D03*
X853641D03*
X844941Y1067979D03*
X853641D03*
X844941Y1091404D03*
X853641D03*
X844941Y1084711D03*
X853641D03*
X844941Y1111483D03*
X853641D03*
X844941Y1104790D03*
X853641D03*
X844941Y1098097D03*
X853641D03*
X844941Y1128215D03*
X853641D03*
X844941Y1121522D03*
X853641D03*
X844941Y1141601D03*
X853641D03*
X844941Y1134908D03*
X853641D03*
X844941Y1158333D03*
X853641D03*
X844941Y1148294D03*
X853641D03*
X844941Y1171719D03*
X853641D03*
X844941Y1165026D03*
X853641D03*
X844941Y1185105D03*
X853641D03*
X844941Y1178412D03*
X853641D03*
X844941Y1208530D03*
X853641D03*
X844941Y1201837D03*
X853641D03*
X844941Y1195144D03*
X853641D03*
X844941Y1221916D03*
X853641D03*
X844941Y1215223D03*
X853641D03*
X844941Y1238648D03*
X853641D03*
X844941Y1231955D03*
X853641D03*
X844941Y1245341D03*
X853641D03*
X844941Y1265420D03*
Y1262074D03*
X1003841Y770144D03*
Y783530D03*
Y776837D03*
Y800263D03*
Y793570D03*
Y820341D03*
Y813648D03*
Y806955D03*
Y830381D03*
Y850459D03*
Y843766D03*
Y837074D03*
Y867192D03*
Y857152D03*
Y880577D03*
Y873885D03*
Y893963D03*
Y887270D03*
Y917389D03*
Y910696D03*
Y904003D03*
Y930774D03*
Y924081D03*
Y947507D03*
Y940814D03*
Y964239D03*
Y954200D03*
Y977625D03*
Y970932D03*
Y991011D03*
Y984318D03*
Y1031168D03*
Y1024475D03*
Y1017782D03*
Y1044554D03*
Y1037861D03*
Y1057940D03*
Y1051247D03*
Y1078018D03*
Y1071326D03*
Y1064633D03*
Y1094751D03*
Y1088058D03*
Y1108137D03*
Y1101444D03*
Y1124869D03*
Y1114829D03*
Y1144948D03*
Y1138255D03*
Y1131562D03*
Y1161680D03*
Y1151641D03*
Y1175066D03*
Y1168373D03*
Y1188452D03*
Y1181759D03*
Y1205184D03*
Y1198491D03*
Y1225263D03*
Y1218570D03*
Y1211877D03*
Y1241995D03*
Y1235302D03*
Y1248688D03*
Y1265420D03*
X1019983Y766798D03*
X1012541Y770144D03*
X1019983Y780184D03*
Y773491D03*
X1012541Y783530D03*
Y776837D03*
X1019983Y803609D03*
Y796916D03*
Y790223D03*
X1012541Y800263D03*
Y793570D03*
X1019983Y816995D03*
Y810302D03*
X1012541Y820341D03*
Y813648D03*
Y806955D03*
X1019983Y833727D03*
Y827034D03*
X1012541Y830381D03*
X1019983Y847113D03*
Y840420D03*
X1012541Y850459D03*
Y843766D03*
Y837074D03*
X1019983Y863845D03*
Y853806D03*
X1012541Y867192D03*
Y857152D03*
X1019983Y883924D03*
Y877231D03*
Y870538D03*
X1012541Y880577D03*
Y873885D03*
X1019983Y900656D03*
Y890617D03*
X1012541Y893963D03*
Y887270D03*
X1019983Y914042D03*
Y907349D03*
X1012541Y917389D03*
Y910696D03*
Y904003D03*
X1019983Y927428D03*
Y920735D03*
X1012541Y930774D03*
Y924081D03*
X1019983Y944160D03*
Y937467D03*
X1012541Y947507D03*
Y940814D03*
X1019983Y960892D03*
Y950853D03*
X1012541Y964239D03*
Y954200D03*
X1019983Y980971D03*
Y974278D03*
Y967585D03*
X1012541Y977625D03*
Y970932D03*
X1019983Y987664D03*
X1012541Y991011D03*
Y984318D03*
X1019983Y1027822D03*
Y1017782D03*
X1012541Y1031168D03*
Y1024475D03*
Y1017782D03*
X1019983Y1047900D03*
Y1041207D03*
Y1034515D03*
X1012541Y1044554D03*
Y1037861D03*
X1019983Y1061286D03*
Y1054593D03*
X1012541Y1057940D03*
Y1051247D03*
X1019983Y1067979D03*
Y1074672D03*
X1012541Y1078018D03*
Y1071326D03*
Y1064633D03*
X1019983Y1091404D03*
Y1084711D03*
X1012541Y1094751D03*
Y1088058D03*
X1019983Y1111483D03*
Y1104790D03*
Y1098097D03*
X1012541Y1108137D03*
Y1101444D03*
X1019983Y1128215D03*
Y1121522D03*
X1012541Y1124869D03*
Y1114829D03*
X1019983Y1141601D03*
Y1134908D03*
X1012541Y1144948D03*
Y1138255D03*
Y1131562D03*
X1019983Y1158333D03*
Y1148294D03*
X1012541Y1161680D03*
Y1151641D03*
X1019983Y1171719D03*
Y1165026D03*
X1012541Y1175066D03*
Y1168373D03*
X1019983Y1185105D03*
Y1178412D03*
X1012541Y1188452D03*
Y1181759D03*
X1019983Y1208530D03*
Y1201837D03*
Y1195144D03*
X1012541Y1205184D03*
Y1198491D03*
X1019983Y1221916D03*
Y1215223D03*
X1012541Y1225263D03*
Y1218570D03*
Y1211877D03*
X1019983Y1238648D03*
Y1231955D03*
X1012541Y1241995D03*
Y1235302D03*
X1019983Y1245341D03*
X1012541Y1248688D03*
X1019983Y1262074D03*
Y1265420D03*
X1033541Y770144D03*
X1028683Y766798D03*
X1033541Y783530D03*
Y776837D03*
X1028683Y780184D03*
Y773491D03*
X1033541Y800263D03*
Y793570D03*
X1028683Y803609D03*
Y796916D03*
Y790223D03*
X1033541Y820341D03*
Y813648D03*
Y806955D03*
X1028683Y816995D03*
Y810302D03*
X1033541Y830381D03*
X1028683Y833727D03*
Y827034D03*
X1033541Y850459D03*
Y843766D03*
Y837074D03*
X1028683Y847113D03*
Y840420D03*
X1033541Y867192D03*
Y857152D03*
X1028683Y863845D03*
Y853806D03*
X1033541Y880577D03*
Y873885D03*
X1028683Y883924D03*
Y877231D03*
Y870538D03*
X1033541Y893963D03*
Y887270D03*
X1028683Y900656D03*
Y890617D03*
X1033541Y917389D03*
Y910696D03*
Y904003D03*
X1028683Y914042D03*
Y907349D03*
X1033541Y930774D03*
Y924081D03*
X1028683Y927428D03*
Y920735D03*
X1033541Y947507D03*
Y940814D03*
X1028683Y944160D03*
Y937467D03*
X1033541Y964239D03*
Y954200D03*
X1028683Y960892D03*
Y950853D03*
X1033541Y977625D03*
Y970932D03*
X1028683Y980971D03*
Y974278D03*
Y967585D03*
X1033541Y991011D03*
Y984318D03*
X1028683Y987664D03*
X1033541Y1031168D03*
Y1017782D03*
Y1024475D03*
X1028683Y1027822D03*
Y1017782D03*
X1033541Y1044554D03*
Y1037861D03*
X1028683Y1047900D03*
Y1041207D03*
Y1034515D03*
X1033541Y1057940D03*
Y1051247D03*
X1028683Y1061286D03*
Y1054593D03*
X1033541Y1078018D03*
Y1071326D03*
Y1064633D03*
X1028683Y1067979D03*
Y1074672D03*
X1033541Y1094751D03*
Y1088058D03*
X1028683Y1091404D03*
Y1084711D03*
X1033541Y1108137D03*
Y1101444D03*
X1028683Y1111483D03*
Y1104790D03*
Y1098097D03*
X1033541Y1114829D03*
Y1124869D03*
X1028683Y1128215D03*
Y1121522D03*
X1033541Y1144948D03*
Y1138255D03*
Y1131562D03*
X1028683Y1141601D03*
Y1134908D03*
X1033541Y1161680D03*
Y1151641D03*
X1028683Y1158333D03*
Y1148294D03*
X1033541Y1175066D03*
Y1168373D03*
X1028683Y1171719D03*
Y1165026D03*
X1033541Y1188452D03*
Y1181759D03*
X1028683Y1185105D03*
Y1178412D03*
X1033541Y1205184D03*
Y1198491D03*
X1028683Y1208530D03*
Y1201837D03*
Y1195144D03*
X1033541Y1225263D03*
Y1218570D03*
Y1211877D03*
X1028683Y1221916D03*
Y1215223D03*
X1033541Y1241995D03*
Y1235302D03*
X1028683Y1238648D03*
Y1231955D03*
X1033541Y1248688D03*
X1028683Y1245341D03*
X1033541Y1265420D03*
X1049683Y766798D03*
X1042241Y770144D03*
X1049683Y780184D03*
Y773491D03*
X1042241Y783530D03*
Y776837D03*
X1049683Y803609D03*
Y796916D03*
Y790223D03*
X1042241Y800263D03*
Y793570D03*
X1049683Y816995D03*
Y810302D03*
X1042241Y820341D03*
Y813648D03*
Y806955D03*
X1049683Y833727D03*
Y827034D03*
X1042241Y830381D03*
X1049683Y847113D03*
Y840420D03*
X1042241Y850459D03*
Y843766D03*
Y837074D03*
X1049683Y863845D03*
Y853806D03*
X1042241Y867192D03*
Y857152D03*
X1049683Y883924D03*
Y877231D03*
Y870538D03*
X1042241Y880577D03*
Y873885D03*
X1049683Y900656D03*
Y890617D03*
X1042241Y893963D03*
Y887270D03*
X1049683Y914042D03*
Y907349D03*
X1042241Y917389D03*
Y910696D03*
Y904003D03*
X1049683Y927428D03*
Y920735D03*
X1042241Y930774D03*
Y924081D03*
X1049683Y944160D03*
Y937467D03*
X1042241Y947507D03*
Y940814D03*
X1049683Y960892D03*
Y950853D03*
X1042241Y964239D03*
Y954200D03*
X1049683Y980971D03*
Y974278D03*
Y967585D03*
X1042241Y977625D03*
Y970932D03*
X1049683Y987664D03*
X1042241Y991011D03*
Y984318D03*
X1049683Y1027822D03*
Y1017782D03*
X1042241Y1031168D03*
Y1017782D03*
Y1024475D03*
X1049683Y1047900D03*
Y1041207D03*
Y1034515D03*
X1042241Y1044554D03*
Y1037861D03*
X1049683Y1061286D03*
Y1054593D03*
X1042241Y1057940D03*
Y1051247D03*
X1049683Y1074672D03*
Y1067979D03*
X1042241Y1078018D03*
Y1071326D03*
Y1064633D03*
X1049683Y1091404D03*
Y1084711D03*
X1042241Y1094751D03*
Y1088058D03*
X1049683Y1111483D03*
Y1104790D03*
Y1098097D03*
X1042241Y1108137D03*
Y1101444D03*
Y1114829D03*
X1049683Y1128215D03*
Y1121522D03*
X1042241Y1124869D03*
X1049683Y1141601D03*
Y1134908D03*
X1042241Y1144948D03*
Y1138255D03*
Y1131562D03*
Y1161680D03*
X1049683Y1158333D03*
Y1148294D03*
X1042241Y1151641D03*
X1049683Y1171719D03*
Y1165026D03*
X1042241Y1175066D03*
Y1168373D03*
X1049683Y1185105D03*
Y1178412D03*
X1042241Y1188452D03*
Y1181759D03*
X1049683Y1208530D03*
Y1201837D03*
Y1195144D03*
X1042241Y1205184D03*
Y1198491D03*
X1049683Y1215223D03*
Y1221916D03*
X1042241Y1225263D03*
Y1218570D03*
Y1211877D03*
X1049683Y1238648D03*
Y1231955D03*
X1042241Y1241995D03*
Y1235302D03*
X1049683Y1245341D03*
X1042241Y1248688D03*
X1049683Y1265420D03*
Y1262074D03*
X1063241Y770144D03*
X1058383Y766798D03*
X1063241Y783530D03*
Y776837D03*
X1058383Y780184D03*
Y773491D03*
X1063241Y800263D03*
Y793570D03*
X1058383Y803609D03*
Y796916D03*
Y790223D03*
X1063241Y820341D03*
Y813648D03*
Y806955D03*
X1058383Y816995D03*
Y810302D03*
X1063241Y830381D03*
X1058383Y833727D03*
Y827034D03*
X1063241Y850459D03*
Y843766D03*
Y837074D03*
X1058383Y847113D03*
Y840420D03*
X1063241Y867192D03*
Y857152D03*
X1058383Y863845D03*
Y853806D03*
X1063241Y880577D03*
Y873885D03*
X1058383Y883924D03*
Y877231D03*
Y870538D03*
X1063241Y893963D03*
Y887270D03*
X1058383Y900656D03*
Y890617D03*
X1063241Y917389D03*
Y910696D03*
Y904003D03*
X1058383Y914042D03*
Y907349D03*
X1063241Y930774D03*
Y924081D03*
X1058383Y927428D03*
Y920735D03*
X1063241Y947507D03*
Y940814D03*
X1058383Y944160D03*
Y937467D03*
X1063241Y964239D03*
Y954200D03*
X1058383Y960892D03*
Y950853D03*
X1063241Y977625D03*
Y970932D03*
X1058383Y980971D03*
Y974278D03*
Y967585D03*
X1063241Y991011D03*
Y984318D03*
X1058383Y987664D03*
X1063241Y1031168D03*
Y1024475D03*
Y1017782D03*
X1058383Y1027822D03*
Y1017782D03*
X1063241Y1044554D03*
Y1037861D03*
X1058383Y1047900D03*
Y1041207D03*
Y1034515D03*
X1063241Y1057940D03*
Y1051247D03*
X1058383Y1061286D03*
Y1054593D03*
X1063241Y1078018D03*
Y1071326D03*
Y1064633D03*
X1058383Y1074672D03*
Y1067979D03*
X1063241Y1094751D03*
Y1088058D03*
X1058383Y1091404D03*
Y1084711D03*
X1063241Y1108137D03*
Y1101444D03*
X1058383Y1111483D03*
Y1104790D03*
Y1098097D03*
X1063241Y1124869D03*
Y1114829D03*
X1058383Y1128215D03*
Y1121522D03*
X1063241Y1144948D03*
Y1138255D03*
Y1131562D03*
X1058383Y1141601D03*
Y1134908D03*
X1063241Y1161680D03*
Y1151641D03*
X1058383Y1158333D03*
Y1148294D03*
X1063241Y1175066D03*
Y1168373D03*
X1058383Y1171719D03*
Y1165026D03*
X1063241Y1188452D03*
Y1181759D03*
X1058383Y1185105D03*
Y1178412D03*
X1063241Y1205184D03*
Y1198491D03*
X1058383Y1208530D03*
Y1201837D03*
Y1195144D03*
X1063241Y1225263D03*
Y1218570D03*
Y1211877D03*
X1058383Y1215223D03*
Y1221916D03*
X1063241Y1241995D03*
Y1235302D03*
X1058383Y1238648D03*
Y1231955D03*
X1063241Y1248688D03*
X1058383Y1245341D03*
X1063241Y1265420D03*
X1079383Y766798D03*
X1071941Y770144D03*
X1079383Y780184D03*
Y773491D03*
X1071941Y783530D03*
Y776837D03*
X1079383Y803609D03*
Y796916D03*
Y790223D03*
X1071941Y800263D03*
Y793570D03*
X1079383Y816995D03*
Y810302D03*
X1071941Y820341D03*
Y813648D03*
Y806955D03*
X1079383Y833727D03*
Y827034D03*
X1071941Y830381D03*
X1079383Y847113D03*
Y840420D03*
X1071941Y850459D03*
Y843766D03*
Y837074D03*
X1079383Y863845D03*
Y853806D03*
X1071941Y867192D03*
Y857152D03*
X1079383Y883924D03*
Y877231D03*
Y870538D03*
X1071941Y880577D03*
Y873885D03*
X1079383Y900656D03*
Y890617D03*
X1071941Y893963D03*
Y887270D03*
X1079383Y914042D03*
Y907349D03*
X1071941Y917389D03*
Y910696D03*
Y904003D03*
X1079383Y927428D03*
Y920735D03*
X1071941Y930774D03*
Y924081D03*
X1079383Y944160D03*
Y937467D03*
X1071941Y947507D03*
Y940814D03*
X1079383Y960892D03*
Y950853D03*
X1071941Y964239D03*
Y954200D03*
X1079383Y980971D03*
Y974278D03*
Y967585D03*
X1071941Y977625D03*
Y970932D03*
X1079383Y987664D03*
X1071941Y991011D03*
Y984318D03*
X1079383Y1027822D03*
Y1017782D03*
X1071941Y1031168D03*
Y1024475D03*
Y1017782D03*
X1079383Y1047900D03*
Y1041207D03*
Y1034515D03*
X1071941Y1044554D03*
Y1037861D03*
X1079383Y1061286D03*
Y1054593D03*
X1071941Y1057940D03*
Y1051247D03*
X1079383Y1074672D03*
Y1067979D03*
X1071941Y1078018D03*
Y1071326D03*
Y1064633D03*
X1079383Y1091404D03*
Y1084711D03*
X1071941Y1094751D03*
Y1088058D03*
X1079383Y1111483D03*
Y1104790D03*
Y1098097D03*
X1071941Y1108137D03*
Y1101444D03*
X1079383Y1128215D03*
Y1121522D03*
X1071941Y1124869D03*
Y1114829D03*
X1079383Y1141601D03*
Y1134908D03*
X1071941Y1144948D03*
Y1138255D03*
Y1131562D03*
X1079383Y1158333D03*
Y1148294D03*
X1071941Y1161680D03*
Y1151641D03*
X1079383Y1171719D03*
Y1165026D03*
X1071941Y1175066D03*
Y1168373D03*
X1079383Y1185105D03*
Y1178412D03*
X1071941Y1188452D03*
Y1181759D03*
X1079383Y1208530D03*
Y1201837D03*
Y1195144D03*
X1071941Y1205184D03*
Y1198491D03*
X1079383Y1221916D03*
Y1215223D03*
X1071941Y1225263D03*
Y1218570D03*
Y1211877D03*
X1079383Y1238648D03*
Y1231955D03*
X1071941Y1241995D03*
Y1235302D03*
X1079383Y1245341D03*
X1071941Y1248688D03*
X1079383Y1265420D03*
Y1262074D03*
X1092941Y770144D03*
X1101641D03*
X1088083Y766798D03*
X1092941Y783530D03*
X1101641D03*
X1092941Y776837D03*
X1101641D03*
X1088083Y780184D03*
Y773491D03*
X1101641Y800263D03*
X1092941D03*
X1101641Y793570D03*
X1092941D03*
X1088083Y803609D03*
Y796916D03*
Y790223D03*
X1101641Y820341D03*
X1092941D03*
X1101641Y813648D03*
X1092941D03*
X1101641Y806955D03*
X1092941D03*
X1088083Y816995D03*
Y810302D03*
X1101641Y830381D03*
X1092941D03*
X1088083Y833727D03*
Y827034D03*
X1101641Y850459D03*
X1092941D03*
X1101641Y843766D03*
X1092941D03*
X1101641Y837074D03*
X1092941D03*
X1088083Y847113D03*
Y840420D03*
X1101641Y867192D03*
X1092941D03*
X1101641Y857152D03*
X1092941D03*
X1088083Y863845D03*
Y853806D03*
X1101641Y880577D03*
X1092941D03*
X1101641Y873885D03*
X1092941D03*
X1088083Y883924D03*
Y877231D03*
Y870538D03*
X1101641Y893963D03*
X1092941D03*
X1101641Y887270D03*
X1092941D03*
X1088083Y900656D03*
Y890617D03*
X1101641Y917389D03*
X1092941D03*
X1101641Y910696D03*
X1092941D03*
X1101641Y904003D03*
X1092941D03*
X1088083Y914042D03*
Y907349D03*
X1101641Y930774D03*
X1092941D03*
X1101641Y924081D03*
X1092941D03*
X1088083Y927428D03*
Y920735D03*
X1101641Y947507D03*
X1092941D03*
X1101641Y940814D03*
X1092941D03*
X1088083Y944160D03*
Y937467D03*
X1101641Y964239D03*
X1092941D03*
X1101641Y954200D03*
X1092941D03*
X1088083Y960892D03*
Y950853D03*
X1101641Y977625D03*
X1092941D03*
X1101641Y970932D03*
X1092941D03*
X1088083Y980971D03*
Y974278D03*
Y967585D03*
X1101641Y991011D03*
X1092941D03*
X1101641Y984318D03*
X1092941D03*
X1088083Y987664D03*
X1101641Y1031168D03*
X1092941D03*
X1101641Y1024475D03*
X1092941D03*
X1101641Y1017782D03*
X1092941D03*
X1088083Y1027822D03*
Y1017782D03*
X1101641Y1044554D03*
X1092941D03*
X1101641Y1037861D03*
X1092941D03*
X1088083Y1047900D03*
Y1041207D03*
Y1034515D03*
X1101641Y1057940D03*
X1092941D03*
X1101641Y1051247D03*
X1092941D03*
X1088083Y1061286D03*
Y1054593D03*
X1101641Y1078018D03*
X1092941D03*
X1101641Y1071326D03*
X1092941D03*
X1101641Y1064633D03*
X1092941D03*
X1088083Y1074672D03*
Y1067979D03*
X1101641Y1094751D03*
X1092941D03*
X1101641Y1088058D03*
X1092941D03*
X1088083Y1091404D03*
Y1084711D03*
X1101641Y1108137D03*
X1092941D03*
X1101641Y1101444D03*
X1092941D03*
X1088083Y1111483D03*
Y1104790D03*
Y1098097D03*
X1101641Y1124869D03*
X1092941D03*
X1101641Y1114829D03*
X1092941D03*
X1088083Y1128215D03*
Y1121522D03*
X1101641Y1144948D03*
X1092941D03*
X1101641Y1138255D03*
X1092941D03*
X1101641Y1131562D03*
X1092941D03*
X1088083Y1141601D03*
Y1134908D03*
X1092941Y1161680D03*
X1101641D03*
Y1151641D03*
X1092941D03*
X1088083Y1158333D03*
Y1148294D03*
X1101641Y1175066D03*
X1092941D03*
X1101641Y1168373D03*
X1092941D03*
X1088083Y1171719D03*
Y1165026D03*
X1101641Y1181759D03*
X1092941D03*
Y1188452D03*
X1101641D03*
X1088083Y1185105D03*
Y1178412D03*
X1092941Y1205184D03*
X1101641D03*
X1092941Y1198491D03*
X1101641D03*
X1088083Y1208530D03*
Y1201837D03*
Y1195144D03*
X1101641Y1225263D03*
X1092941D03*
X1101641Y1218570D03*
X1092941D03*
Y1211877D03*
X1101641D03*
X1088083Y1221916D03*
Y1215223D03*
X1101641Y1241995D03*
X1092941D03*
X1101641Y1235302D03*
X1092941D03*
X1088083Y1238648D03*
Y1231955D03*
X1101641Y1248688D03*
X1092941D03*
X1088083Y1245341D03*
X1092941Y1265420D03*
X1109083Y766798D03*
X1117783D03*
Y780184D03*
X1109083D03*
X1117783Y773491D03*
X1109083D03*
X1117783Y803609D03*
X1109083D03*
X1117783Y796916D03*
X1109083D03*
Y790223D03*
X1117783D03*
Y816995D03*
X1109083D03*
X1117783Y810302D03*
X1109083D03*
X1117783Y833727D03*
X1109083D03*
X1117783Y827034D03*
X1109083D03*
X1117783Y847113D03*
X1109083D03*
X1117783Y840420D03*
X1109083D03*
X1117783Y863845D03*
X1109083D03*
X1117783Y853806D03*
X1109083D03*
X1117783Y883924D03*
X1109083D03*
X1117783Y877231D03*
X1109083D03*
X1117783Y870538D03*
X1109083D03*
X1117783Y900656D03*
X1109083D03*
X1117783Y890617D03*
X1109083D03*
X1117783Y914042D03*
X1109083D03*
X1117783Y907349D03*
X1109083D03*
X1117783Y927428D03*
X1109083D03*
X1117783Y920735D03*
X1109083D03*
X1117783Y944160D03*
X1109083D03*
X1117783Y937467D03*
X1109083D03*
X1117783Y960892D03*
X1109083D03*
X1117783Y950853D03*
X1109083D03*
X1117783Y980971D03*
X1109083D03*
X1117783Y974278D03*
X1109083D03*
X1117783Y967585D03*
X1109083D03*
X1117783Y987664D03*
X1109083D03*
X1117783Y1027822D03*
X1109083D03*
X1117783Y1017782D03*
X1109083D03*
X1117783Y1047900D03*
X1109083D03*
X1117783Y1041207D03*
X1109083D03*
X1117783Y1034515D03*
X1109083D03*
X1117783Y1061286D03*
X1109083D03*
X1117783Y1054593D03*
X1109083D03*
X1117783Y1074672D03*
X1109083D03*
X1117783Y1067979D03*
X1109083D03*
X1117783Y1091404D03*
X1109083D03*
X1117783Y1084711D03*
X1109083D03*
X1117783Y1111483D03*
X1109083D03*
X1117783Y1104790D03*
X1109083D03*
X1117783Y1098097D03*
X1109083D03*
X1117783Y1128215D03*
X1109083D03*
X1117783Y1121522D03*
X1109083D03*
X1117783Y1141601D03*
X1109083D03*
X1117783Y1134908D03*
X1109083D03*
X1117783Y1158333D03*
X1109083D03*
X1117783Y1148294D03*
X1109083D03*
X1117783Y1171719D03*
X1109083D03*
X1117783Y1165026D03*
X1109083D03*
X1117783Y1185105D03*
X1109083D03*
X1117783Y1178412D03*
X1109083D03*
X1117783Y1208530D03*
X1109083D03*
X1117783Y1201837D03*
X1109083D03*
X1117783Y1195144D03*
X1109083D03*
X1117783Y1221916D03*
X1109083D03*
X1117783Y1215223D03*
X1109083D03*
X1117783Y1238648D03*
X1109083D03*
X1117783Y1231955D03*
X1109083D03*
X1117783Y1245341D03*
X1109083D03*
Y1265420D03*
X1109050Y1262972D03*
X1131341Y770144D03*
X1122641D03*
X1131341Y783530D03*
X1122641D03*
X1131341Y776837D03*
X1122641D03*
X1131341Y800263D03*
X1122641D03*
X1131341Y793570D03*
X1122641D03*
X1131341Y820341D03*
X1122641D03*
X1131341Y813648D03*
X1122641D03*
X1131341Y806955D03*
X1122641D03*
X1131341Y830381D03*
X1122641D03*
X1131341Y850459D03*
X1122641D03*
X1131341Y843766D03*
X1122641D03*
X1131341Y837074D03*
X1122641D03*
X1131341Y857152D03*
X1122641D03*
X1152341Y770144D03*
X1147483Y766798D03*
X1138783D03*
X1152341Y783530D03*
Y776837D03*
X1147483Y780184D03*
X1138783D03*
Y773491D03*
X1147483D03*
X1152341Y800263D03*
X1147483Y803609D03*
X1138783D03*
X1152341Y793570D03*
X1147483Y796916D03*
X1138783D03*
X1147483Y790223D03*
X1138783D03*
X1152341Y820341D03*
X1147483Y816995D03*
X1138783D03*
X1152341Y813648D03*
Y806955D03*
X1147483Y810302D03*
X1138783D03*
X1147483Y833727D03*
X1138783D03*
X1152341Y830381D03*
X1147483Y827034D03*
X1138783D03*
X1152341Y850459D03*
Y843766D03*
Y837074D03*
X1147483Y847113D03*
X1138783D03*
X1147483Y840420D03*
X1138783D03*
X1152341Y857152D03*
X1147483Y853806D03*
X1138783D03*
X1168483Y766798D03*
X1161041Y770144D03*
X1168483Y780184D03*
Y773491D03*
X1161041Y783530D03*
Y776837D03*
X1168483Y803609D03*
Y796916D03*
Y790223D03*
X1161041Y800263D03*
Y793570D03*
X1168483Y816995D03*
Y810302D03*
X1161041Y820341D03*
Y813648D03*
Y806955D03*
X1168483Y833727D03*
X1167633Y827034D03*
X1161041Y830381D03*
X1168483Y847113D03*
Y840420D03*
X1161041Y850459D03*
Y843766D03*
Y837074D03*
X1168483Y853806D03*
X1161041Y857152D03*
X1182041Y770144D03*
X1177183Y766798D03*
X1182041Y783530D03*
Y776837D03*
X1177183Y780184D03*
Y773491D03*
X1182041Y800263D03*
Y793570D03*
X1177183Y803609D03*
Y796916D03*
Y790223D03*
X1182041Y813648D03*
Y806955D03*
X1181191Y820341D03*
X1177183Y816995D03*
Y810302D03*
X1181191Y830381D03*
X1177183Y833727D03*
Y827034D03*
X1182041Y850459D03*
Y837074D03*
Y843766D03*
X1177183Y847113D03*
Y840420D03*
X1181191Y857152D03*
X1177183Y853806D03*
X1198183Y766798D03*
X1190741Y770144D03*
X1198183Y780184D03*
Y773491D03*
X1190741Y783530D03*
Y776837D03*
X1198183Y803609D03*
Y796916D03*
Y790223D03*
X1190741Y800263D03*
Y793570D03*
X1197333Y816995D03*
X1198183Y810302D03*
X1190741Y813648D03*
Y806955D03*
X1191591Y820341D03*
X1198183Y833727D03*
X1197333Y827034D03*
X1191591Y830381D03*
X1198183Y847113D03*
Y840420D03*
X1190741Y850459D03*
Y837074D03*
Y843766D03*
X1198183Y853806D03*
X1191591Y857152D03*
X1211741Y770144D03*
X1206883Y766798D03*
X1211741Y783530D03*
Y776837D03*
X1206883Y780184D03*
Y773491D03*
X1211741Y800263D03*
Y793570D03*
X1206883Y803609D03*
Y796916D03*
Y790223D03*
X1210891Y820341D03*
Y813648D03*
X1211741Y806955D03*
X1207148Y817554D03*
X1206883Y810302D03*
X1211741Y830381D03*
X1206883Y833727D03*
X1207733Y827034D03*
X1211741Y850459D03*
Y837074D03*
Y843766D03*
X1206883Y847113D03*
Y840420D03*
X1210891Y857152D03*
X1206883Y853806D03*
X1213983Y1000437D03*
X1216663Y1000395D03*
X1212533Y1002557D03*
X1205033D03*
X1207533D03*
X1210033D03*
X1227883Y766798D03*
X1220441Y770144D03*
X1227883Y780184D03*
Y773491D03*
X1220441Y783530D03*
Y776837D03*
X1227883Y803609D03*
Y796916D03*
Y790223D03*
X1220441Y800263D03*
Y793570D03*
X1227033Y816995D03*
X1227883Y810302D03*
X1221291Y820341D03*
Y813648D03*
X1220441Y806955D03*
X1227883Y833727D03*
X1227033Y827034D03*
X1220441Y830381D03*
X1227883Y847113D03*
Y840420D03*
X1220441Y850459D03*
Y837074D03*
Y843766D03*
X1227033Y853806D03*
X1221291Y857152D03*
X1233703Y999608D03*
X1231023Y999650D03*
X1236583Y766798D03*
Y780184D03*
Y773491D03*
Y803609D03*
Y796916D03*
Y790223D03*
X1237433Y816995D03*
X1236583Y810302D03*
Y833727D03*
X1237433Y827034D03*
X1236583Y847113D03*
Y840420D03*
X1237433Y853806D03*
X1314353Y1118243D03*
X1325085Y176402D03*
X1325020Y873810D03*
X1393826Y956619D03*
X1387826D03*
X1391326D03*
X1385526D03*
X1396286Y985549D03*
X1388506Y985609D03*
X1386206D03*
X1385526Y1014539D03*
X1387826D03*
X1383226D03*
X1396546Y1014469D03*
X1388102Y1028854D03*
X1390602D03*
X1393102D03*
X1395602D03*
X1401326Y956619D03*
X1398826D03*
Y985579D03*
X1399156Y1014469D03*
X1398102Y1028854D03*
X1399453Y1079791D03*
X1443420Y899445D03*
X1429726Y944537D03*
Y939937D03*
Y942237D03*
X1429544Y959298D03*
Y956998D03*
X1437565Y956619D03*
X1434545D03*
X1445045D03*
X1429544Y970798D03*
Y973098D03*
X1437565Y971139D03*
X1434545Y971099D03*
X1429544Y986898D03*
Y984598D03*
X1437565Y985579D03*
X1434545D03*
X1445045D03*
X1429544Y998398D03*
Y1012198D03*
Y1000698D03*
X1437565Y1000079D03*
X1434545D03*
X1445045D03*
X1429544Y1014498D03*
X1437436Y1014509D03*
X1434545Y1014539D03*
X1445036Y1014549D03*
X1439321Y1028854D03*
X1436821D03*
X1434321D03*
X1441821D03*
X1447545Y956619D03*
X1450045Y971099D03*
X1445445D03*
X1447745D03*
X1447545Y985579D03*
Y1000079D03*
X1447345Y1014539D03*
X1601922Y1000198D03*
X1599489Y999665D03*
X1621883Y766798D03*
Y773491D03*
Y780184D03*
Y790223D03*
Y796916D03*
Y803609D03*
X1622916Y816995D03*
X1622986Y810302D03*
X1621883Y827034D03*
Y833727D03*
Y840420D03*
X1616609Y1000735D03*
X1616469Y1003135D03*
X1623539Y1000135D03*
X1620489Y1003135D03*
X1623589Y1002865D03*
X1626741Y770144D03*
X1635441D03*
X1626741Y776837D03*
X1635441D03*
X1626741Y783530D03*
X1635441D03*
X1626741Y793570D03*
X1635441D03*
Y800263D03*
X1626741D03*
X1636341Y820341D03*
X1626741D03*
X1636574Y813648D03*
X1626741D03*
X1635441Y806955D03*
X1626741D03*
X1635441Y830381D03*
X1626741D03*
X1635441Y837074D03*
X1626741D03*
Y843766D03*
X1635441D03*
X1626249Y1002825D03*
X1651583Y766798D03*
X1642883D03*
X1656441Y770144D03*
Y776837D03*
X1642883Y773491D03*
X1651583D03*
X1642883Y780184D03*
X1651583D03*
X1656441Y783530D03*
Y793570D03*
X1642883Y790223D03*
X1651583D03*
X1642883Y796916D03*
X1651583D03*
X1656441Y800263D03*
X1651583Y803609D03*
X1642883D03*
X1656441Y806955D03*
Y813648D03*
Y820341D03*
X1651583Y810302D03*
X1642883D03*
X1652545Y816995D03*
X1641945D03*
X1656441Y830381D03*
X1652767Y827034D03*
X1642018D03*
X1651583Y833727D03*
X1642883D03*
X1656441Y837074D03*
Y843766D03*
X1642883Y840420D03*
X1651583D03*
X1665141Y770144D03*
X1672583Y766798D03*
X1665141Y776837D03*
Y783530D03*
X1672583Y773491D03*
Y780184D03*
X1665141Y793570D03*
Y800263D03*
X1672583Y790223D03*
Y796916D03*
Y803609D03*
X1665141Y806955D03*
Y813648D03*
X1666030Y820341D03*
X1672583Y810302D03*
Y816995D03*
X1665141Y830381D03*
X1672583Y827034D03*
Y833727D03*
X1665141Y837074D03*
Y843766D03*
X1672583Y840420D03*
X1681283Y766798D03*
X1686141Y770144D03*
X1681283Y773491D03*
Y780184D03*
X1686141Y776837D03*
Y783530D03*
X1681283Y790223D03*
Y796916D03*
Y803609D03*
X1686141Y793570D03*
Y800263D03*
X1681283Y810302D03*
Y816995D03*
X1686141Y806955D03*
Y813648D03*
Y820341D03*
X1681283Y827034D03*
Y833727D03*
X1686141Y830381D03*
X1681283Y840420D03*
X1686141Y837074D03*
Y843766D03*
X1694841Y770144D03*
X1702283Y766798D03*
X1694841Y776837D03*
Y783530D03*
X1702283Y773491D03*
Y780184D03*
X1694841Y793570D03*
Y800263D03*
X1702283Y790223D03*
Y796916D03*
Y803609D03*
X1694841Y806955D03*
Y813648D03*
Y820341D03*
X1702283Y810302D03*
Y816995D03*
X1694841Y830381D03*
X1702283Y827034D03*
Y833727D03*
X1694841Y837074D03*
Y843766D03*
Y850459D03*
X1702283Y840420D03*
Y847113D03*
X1694841Y857152D03*
Y867192D03*
X1702283Y853806D03*
Y863845D03*
X1694841Y873885D03*
Y880577D03*
X1702283Y870538D03*
Y877231D03*
Y883924D03*
X1694841Y887270D03*
Y893963D03*
X1702283Y890617D03*
Y900656D03*
X1694841Y904003D03*
Y910696D03*
Y917389D03*
X1702283Y907349D03*
Y914042D03*
X1694841Y924081D03*
Y930774D03*
X1702283Y920735D03*
Y927428D03*
X1694841Y940814D03*
Y947507D03*
X1702283Y937467D03*
Y944160D03*
X1694841Y954200D03*
Y964239D03*
X1702283Y950853D03*
Y960892D03*
X1694841Y970932D03*
Y977625D03*
X1702283Y967585D03*
Y974278D03*
Y980971D03*
X1694841Y984318D03*
Y991011D03*
X1702283Y987664D03*
X1694841Y1017782D03*
Y1024475D03*
Y1031168D03*
X1702283Y1017782D03*
Y1027822D03*
X1694841Y1037861D03*
Y1044554D03*
X1702283Y1034515D03*
Y1041207D03*
Y1047900D03*
X1694841Y1051247D03*
Y1057940D03*
X1702283Y1054593D03*
Y1061286D03*
X1694841Y1064633D03*
Y1071326D03*
Y1078018D03*
X1702283Y1067979D03*
Y1074672D03*
X1694841Y1088058D03*
Y1094751D03*
X1702283Y1084711D03*
Y1091404D03*
X1694841Y1101444D03*
Y1108137D03*
X1702283Y1098097D03*
Y1104790D03*
Y1111483D03*
X1694841Y1114829D03*
Y1124869D03*
X1702283Y1121522D03*
Y1128215D03*
X1694841Y1131562D03*
Y1138255D03*
Y1144948D03*
X1702283Y1134908D03*
Y1141601D03*
X1694841Y1151641D03*
Y1161680D03*
X1702283Y1148294D03*
Y1158333D03*
X1694841Y1168373D03*
Y1175066D03*
X1702283Y1165026D03*
Y1171719D03*
X1694841Y1181759D03*
Y1188452D03*
X1702283Y1178412D03*
Y1185105D03*
X1694841Y1198491D03*
Y1205184D03*
X1702283Y1195144D03*
Y1201837D03*
Y1208530D03*
X1694841Y1211877D03*
Y1218570D03*
Y1225263D03*
X1702283Y1215223D03*
Y1221916D03*
X1710983Y766798D03*
X1715841Y770144D03*
X1710983Y773491D03*
Y780184D03*
X1715841Y783530D03*
Y776837D03*
X1710983Y790223D03*
Y796916D03*
Y803609D03*
X1715841Y793570D03*
Y800263D03*
X1710983Y810302D03*
Y816995D03*
X1715841Y806955D03*
Y813648D03*
Y820341D03*
X1710983Y827034D03*
Y833727D03*
X1715841Y830381D03*
X1710983Y840420D03*
Y847113D03*
X1715841Y837074D03*
Y843766D03*
Y850459D03*
X1710983Y853806D03*
Y863845D03*
X1715841Y857152D03*
Y867192D03*
X1710983Y870538D03*
Y877231D03*
Y883924D03*
X1715841Y873885D03*
Y880577D03*
X1710983Y890617D03*
Y900656D03*
X1715841Y893963D03*
Y887270D03*
X1710983Y907349D03*
Y914042D03*
X1715841Y904003D03*
Y910696D03*
Y917389D03*
X1710983Y920735D03*
Y927428D03*
X1715841Y924081D03*
Y930774D03*
X1710983Y937467D03*
Y944160D03*
X1715841Y940814D03*
Y947507D03*
X1710983Y950853D03*
Y960892D03*
X1715841Y954200D03*
Y964239D03*
X1710983Y967585D03*
Y974278D03*
Y980971D03*
X1715841Y970932D03*
Y977625D03*
X1710983Y987664D03*
X1715841Y984318D03*
Y991011D03*
X1710983Y1017782D03*
Y1027822D03*
X1715841Y1017782D03*
Y1024475D03*
Y1031168D03*
X1710983Y1034515D03*
Y1041207D03*
Y1047900D03*
X1715841Y1037861D03*
Y1044554D03*
X1710983Y1054593D03*
Y1061286D03*
X1715841Y1051247D03*
Y1057940D03*
X1710983Y1067979D03*
Y1074672D03*
X1715841Y1071326D03*
Y1064633D03*
Y1078018D03*
X1710983Y1084711D03*
Y1091404D03*
X1715841Y1088058D03*
Y1094751D03*
X1710983Y1098097D03*
Y1104790D03*
Y1111483D03*
X1715841Y1101444D03*
Y1108137D03*
X1710983Y1121522D03*
Y1128215D03*
X1715841Y1114829D03*
Y1124869D03*
X1710983Y1134908D03*
Y1141601D03*
X1715841Y1131562D03*
Y1138255D03*
Y1144948D03*
X1710983Y1148294D03*
Y1158333D03*
X1715841Y1151641D03*
Y1161680D03*
X1710983Y1165026D03*
Y1171719D03*
X1715841Y1168373D03*
Y1175066D03*
X1710983Y1178412D03*
Y1185105D03*
X1715841Y1181759D03*
Y1188452D03*
X1710983Y1195144D03*
Y1201837D03*
Y1208530D03*
X1715841Y1198491D03*
Y1205184D03*
X1710983Y1215223D03*
Y1221916D03*
X1715841Y1211877D03*
Y1218570D03*
Y1225263D03*
X1731983Y766798D03*
X1724541Y770144D03*
X1731983Y773491D03*
Y780184D03*
X1724541Y783530D03*
Y776837D03*
Y793570D03*
Y800263D03*
X1731983Y790223D03*
Y796916D03*
Y803609D03*
X1724541Y806955D03*
Y813648D03*
Y820341D03*
X1731983Y810302D03*
Y816995D03*
X1724541Y830381D03*
X1731983Y827034D03*
Y833727D03*
X1724541Y837074D03*
Y843766D03*
Y850459D03*
X1731983Y840420D03*
Y847113D03*
X1724541Y857152D03*
Y867192D03*
X1731983Y853806D03*
Y863845D03*
X1724541Y873885D03*
Y880577D03*
X1731983Y870538D03*
Y877231D03*
Y883924D03*
X1724541Y893963D03*
Y887270D03*
X1731983Y890617D03*
Y900656D03*
X1724541Y904003D03*
Y910696D03*
Y917389D03*
X1731983Y907349D03*
Y914042D03*
X1724541Y924081D03*
Y930774D03*
X1731983Y920735D03*
Y927428D03*
X1724541Y940814D03*
Y947507D03*
X1731983Y937467D03*
Y944160D03*
X1724541Y954200D03*
Y964239D03*
X1731983Y950853D03*
Y960892D03*
X1724541Y970932D03*
Y977625D03*
X1731983Y967585D03*
Y974278D03*
Y980971D03*
X1724541Y984318D03*
Y991011D03*
X1731983Y987664D03*
X1724541Y1017782D03*
Y1024475D03*
Y1031168D03*
X1731983Y1017782D03*
Y1027822D03*
X1724541Y1037861D03*
Y1044554D03*
X1731983Y1034515D03*
Y1041207D03*
Y1047900D03*
X1724541Y1057940D03*
X1731983Y1054593D03*
Y1061286D03*
X1724541Y1071326D03*
Y1064633D03*
Y1078018D03*
X1731983Y1074672D03*
Y1067979D03*
X1724541Y1088058D03*
Y1094751D03*
X1731983Y1084711D03*
Y1091404D03*
X1724541Y1101444D03*
Y1108137D03*
X1731983Y1098097D03*
Y1104790D03*
Y1111483D03*
X1724541Y1114829D03*
Y1124869D03*
X1731983Y1121522D03*
Y1128215D03*
X1724541Y1131562D03*
Y1138255D03*
Y1144948D03*
X1731983Y1134908D03*
Y1141601D03*
X1724541Y1151641D03*
Y1161680D03*
X1731983Y1148294D03*
Y1158333D03*
X1724541Y1168373D03*
Y1175066D03*
X1731983Y1165026D03*
Y1171719D03*
X1724541Y1181759D03*
Y1188452D03*
X1731983Y1178412D03*
Y1185105D03*
X1724541Y1198491D03*
Y1205184D03*
X1731983Y1195144D03*
Y1201837D03*
Y1208530D03*
X1724541Y1211877D03*
Y1218570D03*
Y1225263D03*
X1731983Y1215223D03*
Y1221916D03*
X1740683Y766798D03*
Y773491D03*
Y780184D03*
Y790223D03*
Y796916D03*
Y803609D03*
Y810302D03*
Y816995D03*
Y827034D03*
Y833727D03*
Y840420D03*
Y847113D03*
Y853806D03*
Y863845D03*
Y870538D03*
Y877231D03*
Y883924D03*
Y890617D03*
Y900656D03*
Y907349D03*
Y914042D03*
Y920735D03*
Y927428D03*
Y937467D03*
Y944160D03*
Y950853D03*
Y960892D03*
Y967585D03*
Y974278D03*
Y980971D03*
Y987664D03*
Y1017782D03*
Y1027822D03*
Y1034515D03*
Y1041207D03*
Y1047900D03*
Y1054593D03*
Y1061286D03*
Y1074672D03*
Y1067979D03*
Y1084711D03*
Y1091404D03*
Y1098097D03*
Y1104790D03*
Y1111483D03*
Y1121522D03*
Y1128215D03*
Y1134908D03*
Y1141601D03*
Y1148294D03*
Y1158333D03*
Y1165026D03*
Y1171719D03*
Y1178412D03*
Y1185105D03*
Y1195144D03*
Y1201837D03*
Y1208530D03*
Y1215223D03*
Y1221916D03*
G54D54*
X841240Y1420330D03*
X1016240D03*
G54D59*
X986642Y-27947D03*
X986627Y-25432D03*
Y-21558D03*
X986642Y-17918D03*
X986627Y-15403D03*
Y-11529D03*
X986642Y-7889D03*
X986627Y-5374D03*
Y4655D03*
X986642Y2140D03*
X986627Y14684D03*
X986642Y12169D03*
X986627Y8529D03*
X986642Y22698D03*
X989910Y22684D03*
X986627Y19058D03*
Y25213D03*
X989895Y25199D03*
X1296019Y-35472D03*
Y-31598D03*
X1296034Y-37987D03*
Y-27958D03*
X1296019Y-25443D03*
Y-21569D03*
X1296034Y-17929D03*
X1296019Y-15414D03*
Y-11540D03*
X1296034Y-7900D03*
X1296019Y-5385D03*
Y4644D03*
X1296034Y2129D03*
X1296019Y-1511D03*
Y14673D03*
X1296034Y12158D03*
X1296019Y8518D03*
X1296034Y22687D03*
X1296019Y19047D03*
Y25202D03*
X1299302Y22673D03*
X1299287Y25188D03*
X1488393Y-27958D03*
X1488378Y-25443D03*
X1488393Y-37987D03*
X1488378Y-35472D03*
Y-31598D03*
X1488393Y-17929D03*
X1488378Y-15414D03*
Y-11540D03*
Y-21569D03*
X1488393Y2129D03*
X1488378Y4644D03*
X1488393Y-7900D03*
X1488378Y-5385D03*
Y-1511D03*
Y14673D03*
X1488393Y12158D03*
Y22687D03*
X1491661Y22673D03*
X1488378Y8518D03*
Y19047D03*
Y25202D03*
X1491646Y25188D03*
G54D64*
X1879155Y344948D03*
Y592848D03*
X1900275Y-19342D03*
X1889155Y344948D03*
Y592848D03*
X1900275Y716808D03*
X1910275Y-19342D03*
Y716808D03*
X1931395Y592868D03*
X1921395D03*
X1952395Y-19152D03*
X1942395D03*
X1963362Y593010D03*
X1984482Y-19180D03*
X1973362Y593010D03*
X1994482Y-19180D03*
X2015452Y593020D03*
X2005452D03*
X2026452Y-19000D03*
X2036452D03*
X2047419Y593162D03*
X2057419D03*
G54D73*
X1903086Y1318228D03*
X1902402Y1683256D03*
X1950484Y1683497D03*
X1993147Y1682875D03*
G54D71*
X1880836Y1317164D03*
X1881165Y1682207D03*
X1929695Y1683220D03*
X1971555Y1683130D03*
%LPC*%
G75*
G54D74*
G01X-6350Y-464479D02*
Y-539479D01*
X493650D01*
Y-464479D01*
X-6350D01*
G01X5650Y-529479D02*
Y-534479D01*
G01X4193Y-529479D02*
X7107D01*
G01X12017Y-534479D02*
X9483D01*
Y-529479D01*
X12017D01*
G01X11003Y-531896D02*
X9483D01*
G01X14583Y-529479D02*
Y-534479D01*
X17117D01*
G01X20950Y-534646D02*
X20823Y-534562D01*
Y-534396D01*
X20950Y-534312D01*
X21077Y-534396D01*
Y-534562D01*
X20950Y-534646D01*
G01Y-532396D02*
X20823Y-532312D01*
Y-532146D01*
X20950Y-532062D01*
X21077Y-532146D01*
Y-532312D01*
X20950Y-532396D01*
G01X25733Y-536146D02*
X25100Y-535312D01*
X24783Y-534479D01*
Y-531146D01*
X25100Y-530312D01*
X25733Y-529479D01*
G01X31150D02*
X30643Y-529646D01*
X30263Y-530062D01*
X30010Y-530562D01*
X29820Y-531229D01*
X29757Y-531979D01*
X29820Y-532729D01*
X30010Y-533396D01*
X30263Y-533896D01*
X30643Y-534312D01*
X31150Y-534479D01*
X31657Y-534312D01*
X32037Y-533896D01*
X32290Y-533396D01*
X32480Y-532729D01*
X32543Y-531979D01*
X32480Y-531229D01*
X32290Y-530562D01*
X32037Y-530062D01*
X31657Y-529646D01*
X31150Y-529479D01*
G01X34857Y-533479D02*
X35237Y-534062D01*
X35743Y-534396D01*
X36313Y-534479D01*
X36820Y-534396D01*
X37327Y-533979D01*
X37643Y-533479D01*
X37707Y-532979D01*
X37580Y-532396D01*
X37137Y-531979D01*
X36693Y-531812D01*
X36123D01*
G01X36693D02*
X37073Y-531562D01*
X37390Y-531146D01*
X37517Y-530646D01*
X37390Y-530146D01*
X37073Y-529729D01*
X36503Y-529479D01*
X35933Y-529562D01*
X35363Y-529896D01*
G01X41667Y-536146D02*
X42300Y-535312D01*
X42617Y-534479D01*
Y-531146D01*
X42300Y-530312D01*
X41667Y-529479D01*
G01X45057Y-533479D02*
X45437Y-534062D01*
X45943Y-534396D01*
X46513Y-534479D01*
X47020Y-534396D01*
X47527Y-533979D01*
X47843Y-533479D01*
X47907Y-532979D01*
X47780Y-532396D01*
X47337Y-531979D01*
X46893Y-531812D01*
X46323D01*
G01X46893D02*
X47273Y-531562D01*
X47590Y-531146D01*
X47717Y-530646D01*
X47590Y-530146D01*
X47273Y-529729D01*
X46703Y-529479D01*
X46133Y-529562D01*
X45563Y-529896D01*
G01X50347Y-530312D02*
X50727Y-529812D01*
X51170Y-529562D01*
X51677Y-529479D01*
X52310Y-529646D01*
X52753Y-530062D01*
X52880Y-530562D01*
X52817Y-531062D01*
X52563Y-531479D01*
X51297Y-532312D01*
X50727Y-532896D01*
X50347Y-533729D01*
X50220Y-534479D01*
X52880D01*
G01X56523D02*
X56650Y-533396D01*
X56840Y-532479D01*
X57093Y-531646D01*
X57410Y-530729D01*
X57917Y-529479D01*
X55383D01*
G01X60927Y-532812D02*
X62573D01*
G01X65647Y-530312D02*
X66027Y-529812D01*
X66470Y-529562D01*
X66977Y-529479D01*
X67610Y-529646D01*
X68053Y-530062D01*
X68180Y-530562D01*
X68117Y-531062D01*
X67863Y-531479D01*
X66597Y-532312D01*
X66027Y-532896D01*
X65647Y-533729D01*
X65520Y-534479D01*
X68180D01*
G01X70557Y-533479D02*
X70937Y-534062D01*
X71443Y-534396D01*
X72013Y-534479D01*
X72520Y-534396D01*
X73027Y-533979D01*
X73343Y-533479D01*
X73407Y-532979D01*
X73280Y-532396D01*
X72837Y-531979D01*
X72393Y-531812D01*
X71823D01*
G01X72393D02*
X72773Y-531562D01*
X73090Y-531146D01*
X73217Y-530646D01*
X73090Y-530146D01*
X72773Y-529729D01*
X72203Y-529479D01*
X71633Y-529562D01*
X71063Y-529896D01*
G01X77810Y-534479D02*
Y-529479D01*
X75467Y-533062D01*
X78633D01*
G01X80757Y-533729D02*
X81137Y-534146D01*
X81580Y-534396D01*
X82150Y-534479D01*
X82720Y-534312D01*
X83163Y-533979D01*
X83480Y-533396D01*
X83543Y-532729D01*
X83417Y-532062D01*
X83100Y-531646D01*
X82657Y-531312D01*
X82213Y-531229D01*
X81770Y-531312D01*
X81200Y-531646D01*
X81390Y-529479D01*
X83100D01*
G01X91147Y-534479D02*
Y-529479D01*
X93553D01*
G01X92667Y-531896D02*
X91147D01*
G01X95867Y-534479D02*
X97450Y-529479D01*
X99033Y-534479D01*
G01X98463Y-532729D02*
X96437D01*
G01X101220Y-534479D02*
X103880Y-529479D01*
G01X101220D02*
X103880Y-534479D01*
G01X107650Y-534646D02*
X107523Y-534562D01*
Y-534396D01*
X107650Y-534312D01*
X107777Y-534396D01*
Y-534562D01*
X107650Y-534646D01*
G01Y-532396D02*
X107523Y-532312D01*
Y-532146D01*
X107650Y-532062D01*
X107777Y-532146D01*
Y-532312D01*
X107650Y-532396D01*
G01X112433Y-536146D02*
X111800Y-535312D01*
X111483Y-534479D01*
Y-531146D01*
X111800Y-530312D01*
X112433Y-529479D01*
G01X117850D02*
X117343Y-529646D01*
X116963Y-530062D01*
X116710Y-530562D01*
X116520Y-531229D01*
X116457Y-531979D01*
X116520Y-532729D01*
X116710Y-533396D01*
X116963Y-533896D01*
X117343Y-534312D01*
X117850Y-534479D01*
X118357Y-534312D01*
X118737Y-533896D01*
X118990Y-533396D01*
X119180Y-532729D01*
X119243Y-531979D01*
X119180Y-531229D01*
X118990Y-530562D01*
X118737Y-530062D01*
X118357Y-529646D01*
X117850Y-529479D01*
G01X121557Y-533479D02*
X121937Y-534062D01*
X122443Y-534396D01*
X123013Y-534479D01*
X123520Y-534396D01*
X124027Y-533979D01*
X124343Y-533479D01*
X124407Y-532979D01*
X124280Y-532396D01*
X123837Y-531979D01*
X123393Y-531812D01*
X122823D01*
G01X123393D02*
X123773Y-531562D01*
X124090Y-531146D01*
X124217Y-530646D01*
X124090Y-530146D01*
X123773Y-529729D01*
X123203Y-529479D01*
X122633Y-529562D01*
X122063Y-529896D01*
G01X128367Y-536146D02*
X129000Y-535312D01*
X129317Y-534479D01*
Y-531146D01*
X129000Y-530312D01*
X128367Y-529479D01*
G01X131757Y-533479D02*
X132137Y-534062D01*
X132643Y-534396D01*
X133213Y-534479D01*
X133720Y-534396D01*
X134227Y-533979D01*
X134543Y-533479D01*
X134607Y-532979D01*
X134480Y-532396D01*
X134037Y-531979D01*
X133593Y-531812D01*
X133023D01*
G01X133593D02*
X133973Y-531562D01*
X134290Y-531146D01*
X134417Y-530646D01*
X134290Y-530146D01*
X133973Y-529729D01*
X133403Y-529479D01*
X132833Y-529562D01*
X132263Y-529896D01*
G01X137173Y-533896D02*
X137617Y-534312D01*
X138123Y-534479D01*
X138630Y-534312D01*
X139073Y-533812D01*
X139390Y-533062D01*
X139517Y-532312D01*
Y-531396D01*
X139390Y-530646D01*
X139073Y-529979D01*
X138693Y-529646D01*
X138250Y-529479D01*
X137743Y-529646D01*
X137363Y-529979D01*
X137110Y-530479D01*
X136983Y-531146D01*
X137110Y-531729D01*
X137427Y-532312D01*
X137807Y-532646D01*
X138250Y-532729D01*
X138757Y-532562D01*
X139137Y-532146D01*
X139517Y-531396D01*
G01X143223Y-534479D02*
X143350Y-533396D01*
X143540Y-532479D01*
X143793Y-531646D01*
X144110Y-530729D01*
X144617Y-529479D01*
X142083D01*
G01X147627Y-532812D02*
X149273D01*
G01X152157Y-533479D02*
X152537Y-534062D01*
X153043Y-534396D01*
X153613Y-534479D01*
X154120Y-534396D01*
X154627Y-533979D01*
X154943Y-533479D01*
X155007Y-532979D01*
X154880Y-532396D01*
X154437Y-531979D01*
X153993Y-531812D01*
X153423D01*
G01X153993D02*
X154373Y-531562D01*
X154690Y-531146D01*
X154817Y-530646D01*
X154690Y-530146D01*
X154373Y-529729D01*
X153803Y-529479D01*
X153233Y-529562D01*
X152663Y-529896D01*
G01X157447Y-532396D02*
X157890Y-531812D01*
X158270Y-531479D01*
X158777Y-531312D01*
X159220Y-531479D01*
X159537Y-531812D01*
X159790Y-532312D01*
X159853Y-532896D01*
X159790Y-533396D01*
X159537Y-533896D01*
X159157Y-534312D01*
X158713Y-534479D01*
X158207Y-534312D01*
X157763Y-533812D01*
X157510Y-533062D01*
X157447Y-532229D01*
X157573Y-531146D01*
X157763Y-530562D01*
X158080Y-529979D01*
X158523Y-529562D01*
X158967Y-529479D01*
X159410Y-529646D01*
X159727Y-530062D01*
G01X163750Y-534479D02*
Y-529479D01*
X162990Y-530479D01*
G01Y-534479D02*
X164510D01*
G01X169610D02*
Y-529479D01*
X167267Y-533062D01*
X170433D01*
G01X188650Y-464479D02*
Y-539479D01*
G01Y-514479D02*
X291650D01*
Y-489479D01*
G01X188650D02*
X291650D01*
G01Y-464479D02*
Y-539479D01*
G01X293650Y-464479D02*
Y-539479D01*
G01X299157Y-524479D02*
Y-519479D01*
X300423D01*
X300930Y-519729D01*
X301310Y-520062D01*
X301627Y-520562D01*
X301880Y-521146D01*
X301943Y-521979D01*
X301880Y-522812D01*
X301627Y-523396D01*
X301310Y-523896D01*
X300930Y-524229D01*
X300423Y-524479D01*
X299157D01*
G01X304067D02*
X305650Y-519479D01*
X307233Y-524479D01*
G01X306663Y-522729D02*
X304637D01*
G01X310750Y-519479D02*
Y-524479D01*
G01X309293Y-519479D02*
X312207D01*
G01X317117Y-524479D02*
X314583D01*
Y-519479D01*
X317117D01*
G01X316103Y-521896D02*
X314583D01*
G01X320950Y-524646D02*
X320823Y-524562D01*
Y-524396D01*
X320950Y-524312D01*
X321077Y-524396D01*
Y-524562D01*
X320950Y-524646D01*
G01Y-522396D02*
X320823Y-522312D01*
Y-522146D01*
X320950Y-522062D01*
X321077Y-522146D01*
Y-522312D01*
X320950Y-522396D01*
G01X299283Y-499479D02*
Y-494479D01*
X300803D01*
X301310Y-494729D01*
X301690Y-495312D01*
X301817Y-495979D01*
X301690Y-496646D01*
X301373Y-497146D01*
X300803Y-497396D01*
X299283D01*
G01X304510Y-499646D02*
X306790Y-494479D01*
G01X309293Y-499479D02*
Y-494479D01*
X312207Y-499479D01*
Y-494479D01*
G01X315850Y-499646D02*
X315723Y-499562D01*
Y-499396D01*
X315850Y-499312D01*
X315977Y-499396D01*
Y-499562D01*
X315850Y-499646D01*
G01Y-497396D02*
X315723Y-497312D01*
Y-497146D01*
X315850Y-497062D01*
X315977Y-497146D01*
Y-497312D01*
X315850Y-497396D01*
G01X293650Y-514479D02*
X493650D01*
G01X293650Y-489479D02*
X493650D01*
G01X299283Y-474479D02*
Y-469479D01*
X300803D01*
X301310Y-469729D01*
X301690Y-470312D01*
X301817Y-470979D01*
X301690Y-471646D01*
X301373Y-472146D01*
X300803Y-472396D01*
X299283D01*
G01X304383Y-474479D02*
Y-469479D01*
X305967D01*
X306473Y-469729D01*
X306790Y-470062D01*
X306917Y-470729D01*
X306790Y-471396D01*
X306410Y-471812D01*
X305967Y-472062D01*
X304383D01*
G01X305967D02*
X306917Y-474479D01*
G01X310750D02*
X310243Y-474396D01*
X309800Y-474062D01*
X309420Y-473562D01*
X309167Y-472979D01*
X309040Y-472312D01*
Y-471646D01*
X309167Y-470979D01*
X309420Y-470396D01*
X309800Y-469896D01*
X310243Y-469562D01*
X310750Y-469479D01*
X311257Y-469562D01*
X311700Y-469896D01*
X312080Y-470396D01*
X312333Y-470979D01*
X312460Y-471646D01*
Y-472312D01*
X312333Y-472979D01*
X312080Y-473562D01*
X311700Y-474062D01*
X311257Y-474396D01*
X310750Y-474479D01*
G01X314583Y-473479D02*
X314900Y-473979D01*
X315280Y-474312D01*
X315723Y-474479D01*
X316230Y-474312D01*
X316610Y-473979D01*
X316990Y-473479D01*
X317117Y-472812D01*
Y-469479D01*
G01X322217Y-474479D02*
X319683D01*
Y-469479D01*
X322217D01*
G01X321203Y-471896D02*
X319683D01*
G01X327443Y-469896D02*
X327063Y-469646D01*
X326620Y-469479D01*
X326113D01*
X325543Y-469729D01*
X325100Y-470146D01*
X324783Y-470646D01*
X324530Y-471479D01*
X324467Y-472229D01*
X324593Y-472979D01*
X324783Y-473479D01*
X325163Y-473979D01*
X325607Y-474312D01*
X326050Y-474479D01*
X326493D01*
X326937Y-474312D01*
X327317Y-474062D01*
X327633Y-473729D01*
G01X331150Y-469479D02*
Y-474479D01*
G01X329693Y-469479D02*
X332607D01*
G01X336250Y-474646D02*
X336123Y-474562D01*
Y-474396D01*
X336250Y-474312D01*
X336377Y-474396D01*
Y-474562D01*
X336250Y-474646D01*
G01Y-472396D02*
X336123Y-472312D01*
Y-472146D01*
X336250Y-472062D01*
X336377Y-472146D01*
Y-472312D01*
X336250Y-472396D01*
G01X408650Y-514479D02*
Y-539479D01*
G01X411283Y-516979D02*
Y-521979D01*
X413817D01*
G01X416890Y-516979D02*
X418410D01*
G01X417650D02*
Y-521979D01*
G01X416890D02*
X418410D01*
G01X423257Y-519312D02*
X423510Y-519062D01*
X423700Y-518646D01*
X423827Y-518062D01*
X423700Y-517562D01*
X423447Y-517229D01*
X423003Y-516979D01*
X421293D01*
Y-521979D01*
X423383D01*
X423827Y-521646D01*
X424080Y-521146D01*
X424207Y-520562D01*
X424080Y-519979D01*
X423700Y-519479D01*
X423257Y-519312D01*
X421293D01*
G01X427850Y-522146D02*
X427723Y-522062D01*
Y-521896D01*
X427850Y-521812D01*
X427977Y-521896D01*
Y-522062D01*
X427850Y-522146D01*
G01Y-519896D02*
X427723Y-519812D01*
Y-519646D01*
X427850Y-519562D01*
X427977Y-519646D01*
Y-519812D01*
X427850Y-519896D01*
G01X451650Y-514479D02*
Y-539479D01*
G01Y-489479D02*
Y-514479D01*
G01X456663Y-541646D02*
X456770Y-541521D01*
X456850Y-541312D01*
X456903Y-541021D01*
X456850Y-540771D01*
X456743Y-540604D01*
X456557Y-540479D01*
X455837D01*
Y-542979D01*
X456717D01*
X456903Y-542812D01*
X457010Y-542562D01*
X457063Y-542271D01*
X457010Y-541979D01*
X456850Y-541729D01*
X456663Y-541646D01*
X455837D01*
G01X459130Y-542979D02*
Y-541312D01*
G01Y-541604D02*
X459023Y-541437D01*
X458863Y-541354D01*
X458677Y-541312D01*
X458490Y-541396D01*
X458330Y-541562D01*
X458223Y-541812D01*
X458170Y-542146D01*
X458223Y-542479D01*
X458330Y-542729D01*
X458490Y-542896D01*
X458677Y-542979D01*
X458863Y-542937D01*
X459023Y-542812D01*
X459130Y-542646D01*
G01X460450Y-542687D02*
X460583Y-542854D01*
X460770Y-542979D01*
X460930D01*
X461090Y-542896D01*
X461197Y-542771D01*
X461250Y-542604D01*
X461223Y-542354D01*
X461117Y-542229D01*
X460637Y-541979D01*
X460530Y-541687D01*
X460583Y-541479D01*
X460690Y-541354D01*
X460850Y-541312D01*
X461010Y-541354D01*
X461170Y-541479D01*
G01X462650Y-541854D02*
X463503D01*
X463423Y-541562D01*
X463290Y-541396D01*
X463103Y-541312D01*
X462917Y-541354D01*
X462757Y-541479D01*
X462650Y-541771D01*
X462597Y-542021D01*
Y-542271D01*
X462650Y-542521D01*
X462783Y-542771D01*
X462943Y-542937D01*
X463130Y-542979D01*
X463317Y-542896D01*
X463503Y-542646D01*
G01X464770Y-542979D02*
Y-540479D01*
G01Y-541729D02*
X464903Y-541479D01*
X465063Y-541354D01*
X465223Y-541312D01*
X465463Y-541396D01*
X465623Y-541562D01*
X465730Y-541854D01*
Y-542187D01*
X465677Y-542521D01*
X465570Y-542771D01*
X465383Y-542937D01*
X465223Y-542979D01*
X465063Y-542937D01*
X464903Y-542812D01*
X464770Y-542604D01*
G01X467450Y-542979D02*
X467290Y-542937D01*
X467130Y-542771D01*
X467023Y-542479D01*
X466970Y-542146D01*
X467023Y-541812D01*
X467130Y-541521D01*
X467290Y-541354D01*
X467450Y-541312D01*
X467610Y-541354D01*
X467770Y-541521D01*
X467877Y-541812D01*
X467903Y-542146D01*
X467877Y-542479D01*
X467770Y-542771D01*
X467610Y-542937D01*
X467450Y-542979D01*
G01X470130D02*
Y-541312D01*
G01Y-541604D02*
X470023Y-541437D01*
X469863Y-541354D01*
X469677Y-541312D01*
X469490Y-541396D01*
X469330Y-541562D01*
X469223Y-541812D01*
X469170Y-542146D01*
X469223Y-542479D01*
X469330Y-542729D01*
X469490Y-542896D01*
X469677Y-542979D01*
X469863Y-542937D01*
X470023Y-542812D01*
X470130Y-542646D01*
G01X471477Y-542979D02*
Y-541312D01*
G01Y-541646D02*
X471610Y-541479D01*
X471743Y-541354D01*
X471930Y-541312D01*
X472063Y-541354D01*
X472223Y-541479D01*
G01X474530Y-540479D02*
Y-542979D01*
G01Y-542604D02*
X474423Y-542812D01*
X474263Y-542937D01*
X474077Y-542979D01*
X473863Y-542896D01*
X473703Y-542687D01*
X473597Y-542437D01*
X473570Y-542146D01*
X473597Y-541854D01*
X473703Y-541604D01*
X473863Y-541396D01*
X474077Y-541312D01*
X474263Y-541354D01*
X474397Y-541437D01*
X474530Y-541604D01*
G01X477917Y-542979D02*
Y-540479D01*
X478583D01*
X478797Y-540604D01*
X478930Y-540771D01*
X478983Y-541104D01*
X478930Y-541437D01*
X478770Y-541646D01*
X478583Y-541771D01*
X477917D01*
G01X478583D02*
X478983Y-542979D01*
G01X480250Y-541854D02*
X481103D01*
X481023Y-541562D01*
X480890Y-541396D01*
X480703Y-541312D01*
X480517Y-541354D01*
X480357Y-541479D01*
X480250Y-541771D01*
X480197Y-542021D01*
Y-542271D01*
X480250Y-542521D01*
X480383Y-542771D01*
X480543Y-542937D01*
X480730Y-542979D01*
X480917Y-542896D01*
X481103Y-542646D01*
G01X482370Y-541312D02*
X482850Y-542979D01*
X483330Y-541312D01*
G01X485050Y-543062D02*
X484997Y-543021D01*
Y-542937D01*
X485050Y-542896D01*
X485103Y-542937D01*
Y-543021D01*
X485050Y-543062D01*
G01X487250Y-542979D02*
X487437Y-542937D01*
X487650Y-542812D01*
X487783Y-542604D01*
X487837Y-542312D01*
X487783Y-542021D01*
X487623Y-541771D01*
X487383Y-541646D01*
X487117D01*
X486957Y-541562D01*
X486823Y-541354D01*
X486770Y-541062D01*
X486850Y-540771D01*
X487037Y-540562D01*
X487250Y-540479D01*
X487463Y-540562D01*
X487650Y-540771D01*
X487730Y-541062D01*
X487677Y-541354D01*
X487543Y-541562D01*
X487383Y-541646D01*
X487117D01*
X486877Y-541771D01*
X486717Y-542021D01*
X486663Y-542312D01*
X486717Y-542604D01*
X486850Y-542812D01*
X487063Y-542937D01*
X487250Y-542979D01*
G01X489663Y-541646D02*
X489770Y-541521D01*
X489850Y-541312D01*
X489903Y-541021D01*
X489850Y-540771D01*
X489743Y-540604D01*
X489557Y-540479D01*
X488837D01*
Y-542979D01*
X489717D01*
X489903Y-542812D01*
X490010Y-542562D01*
X490063Y-542271D01*
X490010Y-541979D01*
X489850Y-541729D01*
X489663Y-541646D01*
X488837D01*
G01X455550Y-516979D02*
Y-521979D01*
G01X454093Y-516979D02*
X457007D01*
G01X460650Y-521979D02*
X460270Y-521896D01*
X459890Y-521562D01*
X459637Y-520979D01*
X459510Y-520312D01*
X459637Y-519646D01*
X459890Y-519062D01*
X460270Y-518729D01*
X460650Y-518646D01*
X461030Y-518729D01*
X461410Y-519062D01*
X461663Y-519646D01*
X461727Y-520312D01*
X461663Y-520979D01*
X461410Y-521562D01*
X461030Y-521896D01*
X460650Y-521979D01*
G01X465750D02*
X465370Y-521896D01*
X464990Y-521562D01*
X464737Y-520979D01*
X464610Y-520312D01*
X464737Y-519646D01*
X464990Y-519062D01*
X465370Y-518729D01*
X465750Y-518646D01*
X466130Y-518729D01*
X466510Y-519062D01*
X466763Y-519646D01*
X466827Y-520312D01*
X466763Y-520979D01*
X466510Y-521562D01*
X466130Y-521896D01*
X465750Y-521979D01*
G01X470850D02*
Y-516979D01*
G01X475950Y-522146D02*
X475823Y-522062D01*
Y-521896D01*
X475950Y-521812D01*
X476077Y-521896D01*
Y-522062D01*
X475950Y-522146D01*
G01Y-519896D02*
X475823Y-519812D01*
Y-519646D01*
X475950Y-519562D01*
X476077Y-519646D01*
Y-519812D01*
X475950Y-519896D01*
G01X454283Y-496979D02*
Y-491979D01*
X455867D01*
X456373Y-492229D01*
X456690Y-492562D01*
X456817Y-493229D01*
X456690Y-493896D01*
X456310Y-494312D01*
X455867Y-494562D01*
X454283D01*
G01X455867D02*
X456817Y-496979D01*
G01X461917D02*
X459383D01*
Y-491979D01*
X461917D01*
G01X460903Y-494396D02*
X459383D01*
G01X464167Y-491979D02*
X465750Y-496979D01*
X467333Y-491979D01*
G01X470850Y-497146D02*
X470723Y-497062D01*
Y-496896D01*
X470850Y-496812D01*
X470977Y-496896D01*
Y-497062D01*
X470850Y-497146D01*
G01Y-494896D02*
X470723Y-494812D01*
Y-494646D01*
X470850Y-494562D01*
X470977Y-494646D01*
Y-494812D01*
X470850Y-494896D01*
G01X-984580Y-698988D02*
Y4193602D01*
X5868320D01*
Y-698988D01*
X-984580D01*
G01X7723Y-521204D02*
X7253Y-520889D01*
X6705Y-520679D01*
X6078D01*
X5373Y-520994D01*
X4825Y-521519D01*
X4433Y-522149D01*
X4120Y-523199D01*
X4042Y-524144D01*
X4198Y-525089D01*
X4433Y-525719D01*
X4903Y-526349D01*
X5452Y-526769D01*
X6000Y-526979D01*
X6548D01*
X7097Y-526769D01*
X7567Y-526454D01*
X7958Y-526034D01*
G01X11360Y-520679D02*
X13240D01*
G01X12300D02*
Y-526979D01*
G01X11360D02*
X13240D01*
G01X18600Y-520679D02*
Y-526979D01*
G01X16798Y-520679D02*
X20402D01*
G01X24900Y-526979D02*
Y-524144D01*
X23333Y-520679D01*
G01X26467D02*
X24900Y-524144D01*
G01X35777Y-525719D02*
X36247Y-526454D01*
X36873Y-526874D01*
X37578Y-526979D01*
X38205Y-526874D01*
X38832Y-526349D01*
X39223Y-525719D01*
X39302Y-525089D01*
X39145Y-524354D01*
X38597Y-523829D01*
X38048Y-523619D01*
X37343D01*
G01X38048D02*
X38518Y-523304D01*
X38910Y-522779D01*
X39067Y-522149D01*
X38910Y-521519D01*
X38518Y-520994D01*
X37813Y-520679D01*
X37108Y-520784D01*
X36403Y-521204D01*
G01X42077Y-525719D02*
X42547Y-526454D01*
X43173Y-526874D01*
X43878Y-526979D01*
X44505Y-526874D01*
X45132Y-526349D01*
X45523Y-525719D01*
X45602Y-525089D01*
X45445Y-524354D01*
X44897Y-523829D01*
X44348Y-523619D01*
X43643D01*
G01X44348D02*
X44818Y-523304D01*
X45210Y-522779D01*
X45367Y-522149D01*
X45210Y-521519D01*
X44818Y-520994D01*
X44113Y-520679D01*
X43408Y-520784D01*
X42703Y-521204D01*
G01X48377Y-525719D02*
X48847Y-526454D01*
X49473Y-526874D01*
X50178Y-526979D01*
X50805Y-526874D01*
X51432Y-526349D01*
X51823Y-525719D01*
X51902Y-525089D01*
X51745Y-524354D01*
X51197Y-523829D01*
X50648Y-523619D01*
X49943D01*
G01X50648D02*
X51118Y-523304D01*
X51510Y-522779D01*
X51667Y-522149D01*
X51510Y-521519D01*
X51118Y-520994D01*
X50413Y-520679D01*
X49708Y-520784D01*
X49003Y-521204D01*
G01X56243Y-526979D02*
X56400Y-525614D01*
X56635Y-524459D01*
X56948Y-523409D01*
X57340Y-522254D01*
X57967Y-520679D01*
X54833D01*
G01X62543Y-526979D02*
X62700Y-525614D01*
X62935Y-524459D01*
X63248Y-523409D01*
X63640Y-522254D01*
X64267Y-520679D01*
X61133D01*
G01X68843Y-528134D02*
X69157Y-526769D01*
G01X75300Y-520679D02*
Y-526979D01*
G01X73498Y-520679D02*
X77102D01*
G01X79642Y-526979D02*
X81600Y-520679D01*
X83558Y-526979D01*
G01X82853Y-524774D02*
X80347D01*
G01X86960Y-520679D02*
X88840D01*
G01X87900D02*
Y-526979D01*
G01X86960D02*
X88840D01*
G01X91850Y-520679D02*
X92947Y-526979D01*
X94200Y-520679D01*
X95453Y-526979D01*
X96550Y-520679D01*
G01X98542Y-526979D02*
X100500Y-520679D01*
X102458Y-526979D01*
G01X101753Y-524774D02*
X99247D01*
G01X104998Y-526979D02*
Y-520679D01*
X108602Y-526979D01*
Y-520679D01*
G01X119008Y-529079D02*
X118225Y-528029D01*
X117833Y-526979D01*
Y-522779D01*
X118225Y-521729D01*
X119008Y-520679D01*
G01X130433Y-526979D02*
Y-520679D01*
X132392D01*
X133018Y-520994D01*
X133410Y-521414D01*
X133567Y-522254D01*
X133410Y-523094D01*
X132940Y-523619D01*
X132392Y-523934D01*
X130433D01*
G01X132392D02*
X133567Y-526979D01*
G01X138300Y-527189D02*
X138143Y-527084D01*
Y-526874D01*
X138300Y-526769D01*
X138457Y-526874D01*
Y-527084D01*
X138300Y-527189D01*
G01X144600Y-526979D02*
X143973Y-526874D01*
X143425Y-526454D01*
X142955Y-525824D01*
X142642Y-525089D01*
X142485Y-524249D01*
Y-523409D01*
X142642Y-522569D01*
X142955Y-521834D01*
X143425Y-521204D01*
X143973Y-520784D01*
X144600Y-520679D01*
X145227Y-520784D01*
X145775Y-521204D01*
X146245Y-521834D01*
X146558Y-522569D01*
X146715Y-523409D01*
Y-524249D01*
X146558Y-525089D01*
X146245Y-525824D01*
X145775Y-526454D01*
X145227Y-526874D01*
X144600Y-526979D01*
G01X150900Y-527189D02*
X150743Y-527084D01*
Y-526874D01*
X150900Y-526769D01*
X151057Y-526874D01*
Y-527084D01*
X150900Y-527189D01*
G01X158923Y-521204D02*
X158453Y-520889D01*
X157905Y-520679D01*
X157278D01*
X156573Y-520994D01*
X156025Y-521519D01*
X155633Y-522149D01*
X155320Y-523199D01*
X155242Y-524144D01*
X155398Y-525089D01*
X155633Y-525719D01*
X156103Y-526349D01*
X156652Y-526769D01*
X157200Y-526979D01*
X157748D01*
X158297Y-526769D01*
X158767Y-526454D01*
X159158Y-526034D01*
G01X163500Y-527189D02*
X163343Y-527084D01*
Y-526874D01*
X163500Y-526769D01*
X163657Y-526874D01*
Y-527084D01*
X163500Y-527189D01*
G01X170192Y-529079D02*
X170975Y-528029D01*
X171367Y-526979D01*
Y-522779D01*
X170975Y-521729D01*
X170192Y-520679D01*
G01X6470Y-513829D02*
X8037D01*
Y-515719D01*
X7567Y-516349D01*
X7018Y-516769D01*
X6235Y-516979D01*
X5452Y-516769D01*
X4903Y-516349D01*
X4433Y-515719D01*
X4120Y-514984D01*
X3963Y-514144D01*
Y-513409D01*
X4120Y-512779D01*
X4433Y-512044D01*
X4903Y-511414D01*
X5373Y-510994D01*
X6000Y-510679D01*
X6548D01*
X7175Y-510889D01*
X7645Y-511309D01*
G01X10577Y-510679D02*
Y-515194D01*
X10890Y-516139D01*
X11517Y-516769D01*
X12300Y-516979D01*
X13083Y-516769D01*
X13710Y-516139D01*
X14023Y-515194D01*
Y-510679D01*
G01X17660D02*
X19540D01*
G01X18600D02*
Y-516979D01*
G01X17660D02*
X19540D01*
G01X23255Y-516139D02*
X23882Y-516664D01*
X24587Y-516979D01*
X25213D01*
X25840Y-516664D01*
X26310Y-516139D01*
X26545Y-515404D01*
X26388Y-514669D01*
X25997Y-514039D01*
X25292Y-513619D01*
X24352Y-513409D01*
X23803Y-512989D01*
X23568Y-512254D01*
X23725Y-511519D01*
X24117Y-510994D01*
X24665Y-510679D01*
X25213D01*
X25762Y-510889D01*
X26232Y-511414D01*
G01X29555Y-516979D02*
Y-510679D01*
G01X32845D02*
Y-516979D01*
G01Y-513829D02*
X29555D01*
G01X35542Y-516979D02*
X37500Y-510679D01*
X39458Y-516979D01*
G01X38753Y-514774D02*
X36247D01*
G01X41998Y-516979D02*
Y-510679D01*
X45602Y-516979D01*
Y-510679D01*
G01X54677Y-516979D02*
Y-510679D01*
X56243D01*
X56870Y-510994D01*
X57340Y-511414D01*
X57732Y-512044D01*
X58045Y-512779D01*
X58123Y-513829D01*
X58045Y-514879D01*
X57732Y-515614D01*
X57340Y-516244D01*
X56870Y-516664D01*
X56243Y-516979D01*
X54677D01*
G01X61760Y-510679D02*
X63640D01*
G01X62700D02*
Y-516979D01*
G01X61760D02*
X63640D01*
G01X67355Y-516139D02*
X67982Y-516664D01*
X68687Y-516979D01*
X69313D01*
X69940Y-516664D01*
X70410Y-516139D01*
X70645Y-515404D01*
X70488Y-514669D01*
X70097Y-514039D01*
X69392Y-513619D01*
X68452Y-513409D01*
X67903Y-512989D01*
X67668Y-512254D01*
X67825Y-511519D01*
X68217Y-510994D01*
X68765Y-510679D01*
X69313D01*
X69862Y-510889D01*
X70332Y-511414D01*
G01X75300Y-510679D02*
Y-516979D01*
G01X73498Y-510679D02*
X77102D01*
G01X81600Y-517189D02*
X81443Y-517084D01*
Y-516874D01*
X81600Y-516769D01*
X81757Y-516874D01*
Y-517084D01*
X81600Y-517189D01*
G01X87743Y-518134D02*
X88057Y-516769D01*
G01X94200Y-510679D02*
Y-516979D01*
G01X92398Y-510679D02*
X96002D01*
G01X98542Y-516979D02*
X100500Y-510679D01*
X102458Y-516979D01*
G01X101753Y-514774D02*
X99247D01*
G01X106800Y-516979D02*
X106173Y-516874D01*
X105625Y-516454D01*
X105155Y-515824D01*
X104842Y-515089D01*
X104685Y-514249D01*
Y-513409D01*
X104842Y-512569D01*
X105155Y-511834D01*
X105625Y-511204D01*
X106173Y-510784D01*
X106800Y-510679D01*
X107427Y-510784D01*
X107975Y-511204D01*
X108445Y-511834D01*
X108758Y-512569D01*
X108915Y-513409D01*
Y-514249D01*
X108758Y-515089D01*
X108445Y-515824D01*
X107975Y-516454D01*
X107427Y-516874D01*
X106800Y-516979D01*
G01X113100D02*
Y-514144D01*
X111533Y-510679D01*
G01X114667D02*
X113100Y-514144D01*
G01X117677Y-510679D02*
Y-515194D01*
X117990Y-516139D01*
X118617Y-516769D01*
X119400Y-516979D01*
X120183Y-516769D01*
X120810Y-516139D01*
X121123Y-515194D01*
Y-510679D01*
G01X123742Y-516979D02*
X125700Y-510679D01*
X127658Y-516979D01*
G01X126953Y-514774D02*
X124447D01*
G01X130198Y-516979D02*
Y-510679D01*
X133802Y-516979D01*
Y-510679D01*
G01X4198Y-506979D02*
Y-500679D01*
X7802Y-506979D01*
Y-500679D01*
G01X12300Y-506979D02*
X11673Y-506874D01*
X11125Y-506454D01*
X10655Y-505824D01*
X10342Y-505089D01*
X10185Y-504249D01*
Y-503409D01*
X10342Y-502569D01*
X10655Y-501834D01*
X11125Y-501204D01*
X11673Y-500784D01*
X12300Y-500679D01*
X12927Y-500784D01*
X13475Y-501204D01*
X13945Y-501834D01*
X14258Y-502569D01*
X14415Y-503409D01*
Y-504249D01*
X14258Y-505089D01*
X13945Y-505824D01*
X13475Y-506454D01*
X12927Y-506874D01*
X12300Y-506979D01*
G01X18600Y-507189D02*
X18443Y-507084D01*
Y-506874D01*
X18600Y-506769D01*
X18757Y-506874D01*
Y-507084D01*
X18600Y-507189D01*
G01X23412Y-501729D02*
X23882Y-501099D01*
X24430Y-500784D01*
X25057Y-500679D01*
X25840Y-500889D01*
X26388Y-501414D01*
X26545Y-502044D01*
X26467Y-502674D01*
X26153Y-503199D01*
X24587Y-504249D01*
X23882Y-504984D01*
X23412Y-506034D01*
X23255Y-506979D01*
X26545D01*
G01X31200D02*
Y-500679D01*
X30260Y-501939D01*
G01Y-506979D02*
X32140D01*
G01X37500D02*
Y-500679D01*
X36560Y-501939D01*
G01Y-506979D02*
X38440D01*
G01X43643Y-508134D02*
X43957Y-506769D01*
G01X47750Y-500679D02*
X48847Y-506979D01*
X50100Y-500679D01*
X51353Y-506979D01*
X52450Y-500679D01*
G01X57967Y-506979D02*
X54833D01*
Y-500679D01*
X57967D01*
G01X56713Y-503724D02*
X54833D01*
G01X60898Y-506979D02*
Y-500679D01*
X64502Y-506979D01*
Y-500679D01*
G01X67355Y-506979D02*
Y-500679D01*
G01X70645D02*
Y-506979D01*
G01Y-503829D02*
X67355D01*
G01X73577Y-500679D02*
Y-505194D01*
X73890Y-506139D01*
X74517Y-506769D01*
X75300Y-506979D01*
X76083Y-506769D01*
X76710Y-506139D01*
X77023Y-505194D01*
Y-500679D01*
G01X79642Y-506979D02*
X81600Y-500679D01*
X83558Y-506979D01*
G01X82853Y-504774D02*
X80347D01*
G01X92712Y-501729D02*
X93182Y-501099D01*
X93730Y-500784D01*
X94357Y-500679D01*
X95140Y-500889D01*
X95688Y-501414D01*
X95845Y-502044D01*
X95767Y-502674D01*
X95453Y-503199D01*
X93887Y-504249D01*
X93182Y-504984D01*
X92712Y-506034D01*
X92555Y-506979D01*
X95845D01*
G01X98698D02*
Y-500679D01*
X102302Y-506979D01*
Y-500679D01*
G01X105077Y-506979D02*
Y-500679D01*
X106643D01*
X107270Y-500994D01*
X107740Y-501414D01*
X108132Y-502044D01*
X108445Y-502779D01*
X108523Y-503829D01*
X108445Y-504879D01*
X108132Y-505614D01*
X107740Y-506244D01*
X107270Y-506664D01*
X106643Y-506979D01*
X105077D01*
G01X117833D02*
Y-500679D01*
X119792D01*
X120418Y-500994D01*
X120810Y-501414D01*
X120967Y-502254D01*
X120810Y-503094D01*
X120340Y-503619D01*
X119792Y-503934D01*
X117833D01*
G01X119792D02*
X120967Y-506979D01*
G01X123977D02*
Y-500679D01*
X125543D01*
X126170Y-500994D01*
X126640Y-501414D01*
X127032Y-502044D01*
X127345Y-502779D01*
X127423Y-503829D01*
X127345Y-504879D01*
X127032Y-505614D01*
X126640Y-506244D01*
X126170Y-506664D01*
X125543Y-506979D01*
X123977D01*
G01X132000Y-507189D02*
X131843Y-507084D01*
Y-506874D01*
X132000Y-506769D01*
X132157Y-506874D01*
Y-507084D01*
X132000Y-507189D01*
G01X28300Y-494279D02*
X25780Y-493862D01*
X23575Y-492196D01*
X21685Y-489696D01*
X20425Y-486779D01*
X19795Y-483446D01*
Y-480112D01*
X20425Y-476779D01*
X21685Y-473862D01*
X23575Y-471363D01*
X25780Y-469696D01*
X28300Y-469279D01*
X30820Y-469696D01*
X33025Y-471363D01*
X34915Y-473862D01*
X36175Y-476779D01*
X36805Y-480112D01*
Y-483446D01*
X36175Y-486779D01*
X34915Y-489696D01*
X33025Y-492196D01*
X30820Y-493862D01*
X28300Y-494279D01*
G01X30820Y-487612D02*
X34600Y-494279D01*
G01X48145Y-477613D02*
Y-489279D01*
X49405Y-492196D01*
X51295Y-493862D01*
X53500Y-494279D01*
X55705Y-493862D01*
X57595Y-492196D01*
X58855Y-489279D01*
G01Y-494279D02*
Y-477613D01*
G01X84370Y-494279D02*
Y-477613D01*
G01Y-480529D02*
X83110Y-478863D01*
X81220Y-478029D01*
X79015Y-477613D01*
X76810Y-478446D01*
X74920Y-480112D01*
X73660Y-482613D01*
X73030Y-485946D01*
X73660Y-489279D01*
X74920Y-491780D01*
X76810Y-493446D01*
X79015Y-494279D01*
X81220Y-493862D01*
X83110Y-492613D01*
X84370Y-490946D01*
G01X98545Y-494279D02*
Y-477613D01*
G01Y-481779D02*
X99805Y-479696D01*
X101695Y-478029D01*
X104215Y-477613D01*
X106420Y-478029D01*
X108310Y-479696D01*
X109255Y-482613D01*
Y-494279D01*
G01X129100Y-469279D02*
Y-494279D01*
G01X124690Y-477613D02*
X133510D01*
G01X159970Y-494279D02*
Y-477613D01*
G01Y-480529D02*
X158710Y-478863D01*
X156820Y-478029D01*
X154615Y-477613D01*
X152410Y-478446D01*
X150520Y-480112D01*
X149260Y-482613D01*
X148630Y-485946D01*
X149260Y-489279D01*
X150520Y-491780D01*
X152410Y-493446D01*
X154615Y-494279D01*
X156820Y-493862D01*
X158710Y-492613D01*
X159970Y-490946D01*
G01X199650Y-473979D02*
Y-481979D01*
X203650D01*
G01X211450D02*
Y-476646D01*
G01Y-477579D02*
X211050Y-477046D01*
X210450Y-476779D01*
X209750Y-476646D01*
X209050Y-476912D01*
X208450Y-477446D01*
X208050Y-478246D01*
X207850Y-479312D01*
X208050Y-480379D01*
X208450Y-481179D01*
X209050Y-481712D01*
X209750Y-481979D01*
X210450Y-481846D01*
X211050Y-481446D01*
X211450Y-480913D01*
G01X215550Y-484379D02*
X216150Y-484646D01*
X216950Y-484379D01*
X217450Y-483846D01*
X217850Y-483179D01*
X218450Y-481046D01*
X219750Y-476646D01*
G01X216550D02*
X218450Y-481046D01*
G01X224150Y-478379D02*
X227350D01*
X227050Y-477446D01*
X226550Y-476912D01*
X225850Y-476646D01*
X225150Y-476779D01*
X224550Y-477179D01*
X224150Y-478112D01*
X223950Y-478913D01*
Y-479712D01*
X224150Y-480512D01*
X224650Y-481312D01*
X225250Y-481846D01*
X225950Y-481979D01*
X226650Y-481712D01*
X227350Y-480913D01*
G01X232250Y-481979D02*
Y-476646D01*
G01Y-477712D02*
X232750Y-477179D01*
X233250Y-476779D01*
X233950Y-476646D01*
X234450Y-476779D01*
X235050Y-477179D01*
G01X223350Y-531979D02*
Y-523979D01*
X227950Y-531979D01*
Y-523979D01*
G01X233650Y-526646D02*
Y-531979D01*
G01Y-524512D02*
X233450Y-524379D01*
Y-524112D01*
X233650Y-523979D01*
X233850Y-524112D01*
Y-524379D01*
X233650Y-524512D01*
G01X239950Y-531979D02*
Y-526646D01*
G01Y-527979D02*
X240350Y-527312D01*
X240950Y-526779D01*
X241750Y-526646D01*
X242450Y-526779D01*
X243050Y-527312D01*
X243350Y-528246D01*
Y-531979D01*
G01X251450D02*
Y-526646D01*
G01Y-527579D02*
X251050Y-527046D01*
X250450Y-526779D01*
X249750Y-526646D01*
X249050Y-526912D01*
X248450Y-527446D01*
X248050Y-528246D01*
X247850Y-529312D01*
X248050Y-530379D01*
X248450Y-531179D01*
X249050Y-531712D01*
X249750Y-531979D01*
X250450Y-531846D01*
X251050Y-531446D01*
X251450Y-530913D01*
G01X221679Y-500436D02*
X224179Y-508436D01*
X226679Y-500436D01*
G01X234379Y-501103D02*
X233779Y-500703D01*
X233079Y-500436D01*
X232279D01*
X231379Y-500836D01*
X230679Y-501503D01*
X230179Y-502303D01*
X229779Y-503636D01*
X229679Y-504836D01*
X229879Y-506036D01*
X230179Y-506836D01*
X230779Y-507636D01*
X231479Y-508169D01*
X232179Y-508436D01*
X232879D01*
X233579Y-508169D01*
X234179Y-507769D01*
X234679Y-507236D01*
G01X242379Y-501103D02*
X241779Y-500703D01*
X241079Y-500436D01*
X240279D01*
X239379Y-500836D01*
X238679Y-501503D01*
X238179Y-502303D01*
X237779Y-503636D01*
X237679Y-504836D01*
X237879Y-506036D01*
X238179Y-506836D01*
X238779Y-507636D01*
X239479Y-508169D01*
X240179Y-508436D01*
X240879D01*
X241579Y-508169D01*
X242179Y-507769D01*
X242679Y-507236D01*
G01X244979Y-482503D02*
X245679Y-483169D01*
X246479Y-483436D01*
X247279Y-483169D01*
X247979Y-482370D01*
X248479Y-481169D01*
X248679Y-479969D01*
Y-478503D01*
X248479Y-477303D01*
X247979Y-476236D01*
X247379Y-475703D01*
X246679Y-475436D01*
X245879Y-475703D01*
X245279Y-476236D01*
X244879Y-477036D01*
X244679Y-478103D01*
X244879Y-479036D01*
X245379Y-479969D01*
X245979Y-480503D01*
X246679Y-480636D01*
X247479Y-480370D01*
X248079Y-479703D01*
X248679Y-478503D01*
G01X326250Y-525312D02*
X326850Y-524512D01*
X327550Y-524112D01*
X328350Y-523979D01*
X329350Y-524246D01*
X330050Y-524912D01*
X330250Y-525712D01*
X330150Y-526513D01*
X329750Y-527179D01*
X327750Y-528512D01*
X326850Y-529446D01*
X326250Y-530779D01*
X326050Y-531979D01*
X330250D01*
G01X336150Y-523979D02*
X335350Y-524246D01*
X334750Y-524912D01*
X334350Y-525712D01*
X334050Y-526779D01*
X333950Y-527979D01*
X334050Y-529179D01*
X334350Y-530246D01*
X334750Y-531046D01*
X335350Y-531712D01*
X336150Y-531979D01*
X336950Y-531712D01*
X337550Y-531046D01*
X337950Y-530246D01*
X338250Y-529179D01*
X338350Y-527979D01*
X338250Y-526779D01*
X337950Y-525712D01*
X337550Y-524912D01*
X336950Y-524246D01*
X336150Y-523979D01*
G01X342250Y-525312D02*
X342850Y-524512D01*
X343550Y-524112D01*
X344350Y-523979D01*
X345350Y-524246D01*
X346050Y-524912D01*
X346250Y-525712D01*
X346150Y-526513D01*
X345750Y-527179D01*
X343750Y-528512D01*
X342850Y-529446D01*
X342250Y-530779D01*
X342050Y-531979D01*
X346250D01*
G01X349950Y-530379D02*
X350550Y-531312D01*
X351350Y-531846D01*
X352250Y-531979D01*
X353050Y-531846D01*
X353850Y-531179D01*
X354350Y-530379D01*
X354450Y-529579D01*
X354250Y-528646D01*
X353550Y-527979D01*
X352850Y-527712D01*
X351950D01*
G01X352850D02*
X353450Y-527312D01*
X353950Y-526646D01*
X354150Y-525846D01*
X353950Y-525046D01*
X353450Y-524379D01*
X352550Y-523979D01*
X351650Y-524112D01*
X350750Y-524646D01*
G01X358350Y-532246D02*
X361950Y-523979D01*
G01X368150D02*
X367350Y-524246D01*
X366750Y-524912D01*
X366350Y-525712D01*
X366050Y-526779D01*
X365950Y-527979D01*
X366050Y-529179D01*
X366350Y-530246D01*
X366750Y-531046D01*
X367350Y-531712D01*
X368150Y-531979D01*
X368950Y-531712D01*
X369550Y-531046D01*
X369950Y-530246D01*
X370250Y-529179D01*
X370350Y-527979D01*
X370250Y-526779D01*
X369950Y-525712D01*
X369550Y-524912D01*
X368950Y-524246D01*
X368150Y-523979D01*
G01X373950Y-530379D02*
X374550Y-531312D01*
X375350Y-531846D01*
X376250Y-531979D01*
X377050Y-531846D01*
X377850Y-531179D01*
X378350Y-530379D01*
X378450Y-529579D01*
X378250Y-528646D01*
X377550Y-527979D01*
X376850Y-527712D01*
X375950D01*
G01X376850D02*
X377450Y-527312D01*
X377950Y-526646D01*
X378150Y-525846D01*
X377950Y-525046D01*
X377450Y-524379D01*
X376550Y-523979D01*
X375650Y-524112D01*
X374750Y-524646D01*
G01X382350Y-532246D02*
X385950Y-523979D01*
G01X390250Y-525312D02*
X390850Y-524512D01*
X391550Y-524112D01*
X392350Y-523979D01*
X393350Y-524246D01*
X394050Y-524912D01*
X394250Y-525712D01*
X394150Y-526513D01*
X393750Y-527179D01*
X391750Y-528512D01*
X390850Y-529446D01*
X390250Y-530779D01*
X390050Y-531979D01*
X394250D01*
G01X401350D02*
Y-523979D01*
X397650Y-529712D01*
X402650D01*
G01X325950Y-506979D02*
Y-498979D01*
X327950D01*
X328750Y-499379D01*
X329350Y-499912D01*
X329850Y-500712D01*
X330250Y-501646D01*
X330350Y-502979D01*
X330250Y-504312D01*
X329850Y-505246D01*
X329350Y-506046D01*
X328750Y-506579D01*
X327950Y-506979D01*
X325950D01*
G01X333650D02*
X336150Y-498979D01*
X338650Y-506979D01*
G01X337750Y-504179D02*
X334550D01*
G01X344150Y-498979D02*
X343350Y-499246D01*
X342750Y-499912D01*
X342350Y-500712D01*
X342050Y-501779D01*
X341950Y-502979D01*
X342050Y-504179D01*
X342350Y-505246D01*
X342750Y-506046D01*
X343350Y-506712D01*
X344150Y-506979D01*
X344950Y-506712D01*
X345550Y-506046D01*
X345950Y-505246D01*
X346250Y-504179D01*
X346350Y-502979D01*
X346250Y-501779D01*
X345950Y-500712D01*
X345550Y-499912D01*
X344950Y-499246D01*
X344150Y-498979D01*
G01X350250Y-506979D02*
Y-498979D01*
X354050D01*
G01X352650Y-502846D02*
X350250D01*
G01X360150Y-498979D02*
X359350Y-499246D01*
X358750Y-499912D01*
X358350Y-500712D01*
X358050Y-501779D01*
X357950Y-502979D01*
X358050Y-504179D01*
X358350Y-505246D01*
X358750Y-506046D01*
X359350Y-506712D01*
X360150Y-506979D01*
X360950Y-506712D01*
X361550Y-506046D01*
X361950Y-505246D01*
X362250Y-504179D01*
X362350Y-502979D01*
X362250Y-501779D01*
X361950Y-500712D01*
X361550Y-499912D01*
X360950Y-499246D01*
X360150Y-498979D01*
G01X368150D02*
Y-506979D01*
G01X365850Y-498979D02*
X370450D01*
G01X373550Y-506979D02*
Y-498979D01*
X376150Y-505646D01*
X378750Y-498979D01*
Y-506979D01*
G01X384950Y-502712D02*
X385350Y-502312D01*
X385650Y-501646D01*
X385850Y-500712D01*
X385650Y-499912D01*
X385250Y-499379D01*
X384550Y-498979D01*
X381850D01*
Y-506979D01*
X385150D01*
X385850Y-506446D01*
X386250Y-505646D01*
X386450Y-504712D01*
X386250Y-503779D01*
X385650Y-502979D01*
X384950Y-502712D01*
X381850D01*
G01X390950Y-498979D02*
X393350D01*
G01X392150D02*
Y-506979D01*
G01X390950D02*
X393350D01*
G01X398150Y-505379D02*
X398650Y-506179D01*
X399250Y-506712D01*
X399950Y-506979D01*
X400750Y-506712D01*
X401350Y-506179D01*
X401950Y-505379D01*
X402150Y-504312D01*
Y-498979D01*
G01X408150D02*
X407350Y-499246D01*
X406750Y-499912D01*
X406350Y-500712D01*
X406050Y-501779D01*
X405950Y-502979D01*
X406050Y-504179D01*
X406350Y-505246D01*
X406750Y-506046D01*
X407350Y-506712D01*
X408150Y-506979D01*
X408950Y-506712D01*
X409550Y-506046D01*
X409950Y-505246D01*
X410250Y-504179D01*
X410350Y-502979D01*
X410250Y-501779D01*
X409950Y-500712D01*
X409550Y-499912D01*
X408950Y-499246D01*
X408150Y-498979D01*
G01X343750Y-481979D02*
Y-473979D01*
X347550D01*
G01X346150Y-477846D02*
X343750D01*
G01X353650Y-473979D02*
X352850Y-474246D01*
X352250Y-474912D01*
X351850Y-475712D01*
X351550Y-476779D01*
X351450Y-477979D01*
X351550Y-479179D01*
X351850Y-480246D01*
X352250Y-481046D01*
X352850Y-481712D01*
X353650Y-481979D01*
X354450Y-481712D01*
X355050Y-481046D01*
X355450Y-480246D01*
X355750Y-479179D01*
X355850Y-477979D01*
X355750Y-476779D01*
X355450Y-475712D01*
X355050Y-474912D01*
X354450Y-474246D01*
X353650Y-473979D01*
G01X361650D02*
Y-481979D01*
G01X359350Y-473979D02*
X363950D01*
G01X366650Y-484646D02*
X372650D01*
G01X375050Y-481979D02*
Y-473979D01*
X377650Y-480646D01*
X380250Y-473979D01*
Y-481979D01*
G01X386450Y-477712D02*
X386850Y-477312D01*
X387150Y-476646D01*
X387350Y-475712D01*
X387150Y-474912D01*
X386750Y-474379D01*
X386050Y-473979D01*
X383350D01*
Y-481979D01*
X386650D01*
X387350Y-481446D01*
X387750Y-480646D01*
X387950Y-479712D01*
X387750Y-478779D01*
X387150Y-477979D01*
X386450Y-477712D01*
X383350D01*
G01X390650Y-484646D02*
X396650D01*
G01X403650Y-481979D02*
X399650D01*
Y-473979D01*
X403650D01*
G01X402050Y-477846D02*
X399650D01*
G01X407050Y-481979D02*
Y-473979D01*
X409650Y-480646D01*
X412250Y-473979D01*
Y-481979D01*
G01X417650D02*
X418350Y-481846D01*
X419150Y-481446D01*
X419650Y-480779D01*
X419850Y-479846D01*
X419650Y-478913D01*
X419050Y-478112D01*
X418150Y-477712D01*
X417150D01*
X416550Y-477446D01*
X416050Y-476779D01*
X415850Y-475846D01*
X416150Y-474912D01*
X416850Y-474246D01*
X417650Y-473979D01*
X418450Y-474246D01*
X419150Y-474912D01*
X419450Y-475846D01*
X419250Y-476779D01*
X418750Y-477446D01*
X418150Y-477712D01*
X417150D01*
X416250Y-478112D01*
X415650Y-478913D01*
X415450Y-479846D01*
X415650Y-480779D01*
X416150Y-481446D01*
X416950Y-481846D01*
X417650Y-481979D01*
G01X423950Y-481046D02*
X424650Y-481712D01*
X425450Y-481979D01*
X426250Y-481712D01*
X426950Y-480913D01*
X427450Y-479712D01*
X427650Y-478512D01*
Y-477046D01*
X427450Y-475846D01*
X426950Y-474779D01*
X426350Y-474246D01*
X425650Y-473979D01*
X424850Y-474246D01*
X424250Y-474779D01*
X423850Y-475579D01*
X423650Y-476646D01*
X423850Y-477579D01*
X424350Y-478512D01*
X424950Y-479046D01*
X425650Y-479179D01*
X426450Y-478913D01*
X427050Y-478246D01*
X427650Y-477046D01*
G01X433650Y-473979D02*
X432850Y-474246D01*
X432250Y-474912D01*
X431850Y-475712D01*
X431550Y-476779D01*
X431450Y-477979D01*
X431550Y-479179D01*
X431850Y-480246D01*
X432250Y-481046D01*
X432850Y-481712D01*
X433650Y-481979D01*
X434450Y-481712D01*
X435050Y-481046D01*
X435450Y-480246D01*
X435750Y-479179D01*
X435850Y-477979D01*
X435750Y-476779D01*
X435450Y-475712D01*
X435050Y-474912D01*
X434450Y-474246D01*
X433650Y-473979D01*
G01X439450Y-481979D02*
Y-473979D01*
G01X443250D02*
X439450Y-478913D01*
G01X443850Y-481979D02*
X441150Y-476646D01*
G01X414650Y-534979D02*
Y-526979D01*
X413450Y-528579D01*
G01Y-534979D02*
X415850D01*
G01X420750Y-531646D02*
X421450Y-530712D01*
X422050Y-530179D01*
X422850Y-529912D01*
X423550Y-530179D01*
X424050Y-530712D01*
X424450Y-531512D01*
X424550Y-532446D01*
X424450Y-533246D01*
X424050Y-534046D01*
X423450Y-534712D01*
X422750Y-534979D01*
X421950Y-534712D01*
X421250Y-533913D01*
X420850Y-532712D01*
X420750Y-531379D01*
X420950Y-529646D01*
X421250Y-528712D01*
X421750Y-527779D01*
X422450Y-527112D01*
X423150Y-526979D01*
X423850Y-527246D01*
X424350Y-527912D01*
G01X430650Y-535246D02*
X430450Y-535112D01*
Y-534846D01*
X430650Y-534712D01*
X430850Y-534846D01*
Y-535112D01*
X430650Y-535246D01*
G01X436750Y-531646D02*
X437450Y-530712D01*
X438050Y-530179D01*
X438850Y-529912D01*
X439550Y-530179D01*
X440050Y-530712D01*
X440450Y-531512D01*
X440550Y-532446D01*
X440450Y-533246D01*
X440050Y-534046D01*
X439450Y-534712D01*
X438750Y-534979D01*
X437950Y-534712D01*
X437250Y-533913D01*
X436850Y-532712D01*
X436750Y-531379D01*
X436950Y-529646D01*
X437250Y-528712D01*
X437750Y-527779D01*
X438450Y-527112D01*
X439150Y-526979D01*
X439850Y-527246D01*
X440350Y-527912D01*
G01X459650Y-534979D02*
Y-526979D01*
X458450Y-528579D01*
G01Y-534979D02*
X460850D01*
G01X467450D02*
X467650Y-533246D01*
X467950Y-531779D01*
X468350Y-530446D01*
X468850Y-528979D01*
X469650Y-526979D01*
X465650D01*
G01X475650Y-535246D02*
X475450Y-535112D01*
Y-534846D01*
X475650Y-534712D01*
X475850Y-534846D01*
Y-535112D01*
X475650Y-535246D01*
G01X481750Y-528312D02*
X482350Y-527512D01*
X483050Y-527112D01*
X483850Y-526979D01*
X484850Y-527246D01*
X485550Y-527912D01*
X485750Y-528712D01*
X485650Y-529513D01*
X485250Y-530179D01*
X483250Y-531512D01*
X482350Y-532446D01*
X481750Y-533779D01*
X481550Y-534979D01*
X485750D01*
G01X479650Y-508379D02*
X480150Y-509179D01*
X480750Y-509712D01*
X481450Y-509979D01*
X482250Y-509712D01*
X482850Y-509179D01*
X483450Y-508379D01*
X483650Y-507312D01*
Y-501979D01*
M02*
